(lib_symbols
	(symbol "12401598E4_2A_1" (in_bom yes) (on_board yes)
      (property "Reference" "J" (id 0) (at 33.02 -2.54 0)
        (effects (font (size 1.27 1.27) (thickness 0.15)) (justify left bottom))
      )
      (property "Value" "12401598E4_2A_1" (id 1) (at 33.02 -7.62 0)
        (effects (font (size 1.27 1.27) (thickness 0.15)) (justify left bottom) hide)
      )
      (property "Footprint" "antmicro-footprints:USB-C_12401610E4_2A" (id 2) (at 33.02 -10.16 0)
        (effects (font (size 1.27 1.27) (thickness 0.15)) (justify left bottom) hide)
      )
      (property "Datasheet" "http://www.amphenol-icc.com/media/wysiwyg/files/drawing/12401598xxx2a.pdf" (id 3) (at 33.02 -12.7 0)
        (effects (font (size 1.27 1.27) (thickness 0.15)) (justify left bottom) hide)
      )
      (property "MPN" "12401598E4#2A" (id 4) (at 33.02 -5.08 0)
        (effects (font (size 1.27 1.27) (thickness 0.15)) (justify left bottom))
      )
      (property "Manufacturer" "Amphenol" (id 5) (at 33.02 -15.24 0)
        (effects (font (size 1.27 1.27) (thickness 0.15)) (justify left bottom) hide)
      )
      (property "Author" "Antmicro" (id 6) (at 33.02 -17.78 0)
        (effects (font (size 1.27 1.27) (thickness 0.15)) (justify left bottom) hide)
      )
      (property "License" "Apache-2.0" (id 7) (at 33.02 -20.32 0)
        (effects (font (size 1.27 1.27) (thickness 0.15)) (justify left bottom) hide)
      )
      (symbol "12401598E4_2A_1_1_1"
        (polyline
          (pts
            (xy 4.445 -14.605)
            (xy 4.445 -13.462)
          )
          (stroke (width 0) (type default) (color 0 0 0 0))
          (fill (type none))
        )
        (polyline
          (pts
            (xy 4.953 -29.083)
            (xy 9.398 -29.083)
          )
          (stroke (width 0) (type default) (color 0 0 0 0))
          (fill (type none))
        )
        (polyline
          (pts
            (xy 4.953 -26.162)
            (xy 4.953 -14.097)
          )
          (stroke (width 0) (type default) (color 0 0 0 0))
          (fill (type none))
        )
        (polyline
          (pts
            (xy 4.953 -14.605)
            (xy 4.953 -13.462)
          )
          (stroke (width 0) (type default) (color 0 0 0 0))
          (fill (type none))
        )
        (polyline
          (pts
            (xy 4.953 -2.032)
            (xy 4.953 -14.097)
          )
          (stroke (width 0) (type default) (color 0 0 0 0))
          (fill (type none))
        )
        (polyline
          (pts
            (xy 4.953 0.889)
            (xy 9.398 0.889)
          )
          (stroke (width 0) (type default) (color 0 0 0 0))
          (fill (type none))
        )
        (polyline
          (pts
            (xy 5.461 -25.527)
            (xy 5.461 -25.019)
          )
          (stroke (width 0) (type default) (color 0 0 0 0))
          (fill (type none))
        )
        (polyline
          (pts
            (xy 5.461 -20.447)
            (xy 5.461 -20.955)
          )
          (stroke (width 0) (type default) (color 0 0 0 0))
          (fill (type none))
        )
        (polyline
          (pts
            (xy 5.461 -7.747)
            (xy 5.461 -7.239)
          )
          (stroke (width 0) (type default) (color 0 0 0 0))
          (fill (type none))
        )
        (polyline
          (pts
            (xy 5.461 -2.667)
            (xy 5.461 -3.175)
          )
          (stroke (width 0) (type default) (color 0 0 0 0))
          (fill (type none))
        )
        (polyline
          (pts
            (xy 5.715 -28.575)
            (xy 5.715 -25.527)
          )
          (stroke (width 0) (type default) (color 0 0 0 0))
          (fill (type none))
        )
        (polyline
          (pts
            (xy 5.715 -20.447)
            (xy 5.715 -14.097)
          )
          (stroke (width 0) (type default) (color 0 0 0 0))
          (fill (type none))
        )
        (polyline
          (pts
            (xy 5.715 -14.605)
            (xy 5.715 -13.462)
          )
          (stroke (width 0) (type default) (color 0 0 0 0))
          (fill (type none))
        )
        (polyline
          (pts
            (xy 5.715 -7.747)
            (xy 5.715 -14.097)
          )
          (stroke (width 0) (type default) (color 0 0 0 0))
          (fill (type none))
        )
        (polyline
          (pts
            (xy 5.715 0.381)
            (xy 5.715 -2.667)
          )
          (stroke (width 0) (type default) (color 0 0 0 0))
          (fill (type none))
        )
        (polyline
          (pts
            (xy 5.969 -25.527)
            (xy 5.969 -25.146)
          )
          (stroke (width 0) (type default) (color 0 0 0 0))
          (fill (type none))
        )
        (polyline
          (pts
            (xy 5.969 -20.701)
            (xy 5.969 -20.828)
          )
          (stroke (width 0) (type default) (color 0 0 0 0))
          (fill (type none))
        )
        (polyline
          (pts
            (xy 5.969 -20.447)
            (xy 5.969 -20.701)
          )
          (stroke (width 0) (type default) (color 0 0 0 0))
          (fill (type none))
        )
        (polyline
          (pts
            (xy 5.969 -7.747)
            (xy 5.969 -7.493)
          )
          (stroke (width 0) (type default) (color 0 0 0 0))
          (fill (type none))
        )
        (polyline
          (pts
            (xy 5.969 -7.493)
            (xy 5.969 -7.366)
          )
          (stroke (width 0) (type default) (color 0 0 0 0))
          (fill (type none))
        )
        (polyline
          (pts
            (xy 5.969 -2.667)
            (xy 5.969 -3.048)
          )
          (stroke (width 0) (type default) (color 0 0 0 0))
          (fill (type none))
        )
        (polyline
          (pts
            (xy 8.001 -14.605)
            (xy 8.001 -13.462)
          )
          (stroke (width 0) (type default) (color 0 0 0 0))
          (fill (type none))
        )
        (polyline
          (pts
            (xy 8.001 -14.097)
            (xy 8.001 -26.035)
          )
          (stroke (width 0) (type default) (color 0 0 0 0))
          (fill (type none))
        )
        (polyline
          (pts
            (xy 8.001 -14.097)
            (xy 8.001 -2.159)
          )
          (stroke (width 0) (type default) (color 0 0 0 0))
          (fill (type none))
        )
        (polyline
          (pts
            (xy 8.509 -14.605)
            (xy 8.509 -13.462)
          )
          (stroke (width 0) (type default) (color 0 0 0 0))
          (fill (type none))
        )
        (polyline
          (pts
            (xy 8.509 -14.097)
            (xy 8.509 -28.575)
          )
          (stroke (width 0) (type default) (color 0 0 0 0))
          (fill (type none))
        )
        (polyline
          (pts
            (xy 8.509 -14.097)
            (xy 8.509 0.381)
          )
          (stroke (width 0) (type default) (color 0 0 0 0))
          (fill (type none))
        )
        (polyline
          (pts
            (xy 8.763 -28.575)
            (xy 8.763 -14.097)
          )
          (stroke (width 0) (type default) (color 0 0 0 0))
          (fill (type none))
        )
        (polyline
          (pts
            (xy 8.763 -14.605)
            (xy 8.763 -13.462)
          )
          (stroke (width 0) (type default) (color 0 0 0 0))
          (fill (type none))
        )
        (polyline
          (pts
            (xy 8.763 0.381)
            (xy 8.763 -14.097)
          )
          (stroke (width 0) (type default) (color 0 0 0 0))
          (fill (type none))
        )
        (polyline
          (pts
            (xy 9.398 -28.575)
            (xy 4.953 -28.575)
          )
          (stroke (width 0) (type default) (color 0 0 0 0))
          (fill (type none))
        )
        (polyline
          (pts
            (xy 9.398 -14.605)
            (xy 9.398 -13.462)
          )
          (stroke (width 0) (type default) (color 0 0 0 0))
          (fill (type none))
        )
        (polyline
          (pts
            (xy 9.398 -14.097)
            (xy 9.398 -28.702)
          )
          (stroke (width 0) (type default) (color 0 0 0 0))
          (fill (type none))
        )
        (polyline
          (pts
            (xy 9.398 -14.097)
            (xy 9.398 0.508)
          )
          (stroke (width 0) (type default) (color 0 0 0 0))
          (fill (type none))
        )
        (polyline
          (pts
            (xy 9.398 0.381)
            (xy 4.953 0.381)
          )
          (stroke (width 0) (type default) (color 0 0 0 0))
          (fill (type none))
        )
        (polyline
          (pts
            (xy 9.525 -35.687)
            (xy 11.303 -35.687)
          )
          (stroke (width 0) (type default) (color 0 0 0 0))
          (fill (type background))
        )
        (polyline
          (pts
            (xy 9.525 -35.179)
            (xy 9.525 -35.56)
          )
          (stroke (width 0) (type default) (color 0 0 0 0))
          (fill (type none))
        )
        (polyline
          (pts
            (xy 9.525 -35.179)
            (xy 11.303 -35.179)
          )
          (stroke (width 0) (type default) (color 0 0 0 0))
          (fill (type none))
        )
        (polyline
          (pts
            (xy 9.525 6.985)
            (xy 9.525 7.366)
          )
          (stroke (width 0) (type default) (color 0 0 0 0))
          (fill (type none))
        )
        (polyline
          (pts
            (xy 9.525 6.985)
            (xy 11.303 6.985)
          )
          (stroke (width 0) (type default) (color 0 0 0 0))
          (fill (type none))
        )
        (polyline
          (pts
            (xy 9.525 7.493)
            (xy 11.303 7.493)
          )
          (stroke (width 0) (type default) (color 0 0 0 0))
          (fill (type background))
        )
        (polyline
          (pts
            (xy 9.779 -34.798)
            (xy 9.779 -35.179)
          )
          (stroke (width 0) (type default) (color 0 0 0 0))
          (fill (type none))
        )
        (polyline
          (pts
            (xy 9.779 -34.671)
            (xy 11.303 -34.671)
          )
          (stroke (width 0) (type default) (color 0 0 0 0))
          (fill (type none))
        )
        (polyline
          (pts
            (xy 9.779 -14.605)
            (xy 9.779 -13.462)
          )
          (stroke (width 0) (type default) (color 0 0 0 0))
          (fill (type none))
        )
        (polyline
          (pts
            (xy 9.779 6.477)
            (xy 11.303 6.477)
          )
          (stroke (width 0) (type default) (color 0 0 0 0))
          (fill (type none))
        )
        (polyline
          (pts
            (xy 9.779 6.604)
            (xy 9.779 6.985)
          )
          (stroke (width 0) (type default) (color 0 0 0 0))
          (fill (type none))
        )
        (polyline
          (pts
            (xy 10.287 -29.083)
            (xy 9.779 -29.591)
          )
          (stroke (width 0) (type default) (color 0 0 0 0))
          (fill (type none))
        )
        (polyline
          (pts
            (xy 10.287 -14.605)
            (xy 10.287 -13.462)
          )
          (stroke (width 0) (type default) (color 0 0 0 0))
          (fill (type none))
        )
        (polyline
          (pts
            (xy 10.287 0.889)
            (xy 9.779 1.397)
          )
          (stroke (width 0) (type default) (color 0 0 0 0))
          (fill (type none))
        )
        (polyline
          (pts
            (xy 11.303 -30.861)
            (xy 9.779 -30.861)
          )
          (stroke (width 0) (type default) (color 0 0 0 0))
          (fill (type none))
        )
        (polyline
          (pts
            (xy 11.303 -30.861)
            (xy 12.827 -30.861)
          )
          (stroke (width 0) (type default) (color 0 0 0 0))
          (fill (type none))
        )
        (polyline
          (pts
            (xy 11.303 2.667)
            (xy 9.779 2.667)
          )
          (stroke (width 0) (type default) (color 0 0 0 0))
          (fill (type none))
        )
        (polyline
          (pts
            (xy 11.303 2.667)
            (xy 12.827 2.667)
          )
          (stroke (width 0) (type default) (color 0 0 0 0))
          (fill (type none))
        )
        (polyline
          (pts
            (xy 12.319 -29.083)
            (xy 12.827 -29.591)
          )
          (stroke (width 0) (type default) (color 0 0 0 0))
          (fill (type none))
        )
        (polyline
          (pts
            (xy 12.319 -14.605)
            (xy 12.319 -13.462)
          )
          (stroke (width 0) (type default) (color 0 0 0 0))
          (fill (type none))
        )
        (polyline
          (pts
            (xy 12.319 0.889)
            (xy 12.827 1.397)
          )
          (stroke (width 0) (type default) (color 0 0 0 0))
          (fill (type none))
        )
        (polyline
          (pts
            (xy 12.827 -34.798)
            (xy 12.827 -35.179)
          )
          (stroke (width 0) (type default) (color 0 0 0 0))
          (fill (type none))
        )
        (polyline
          (pts
            (xy 12.827 -34.671)
            (xy 11.303 -34.671)
          )
          (stroke (width 0) (type default) (color 0 0 0 0))
          (fill (type none))
        )
        (polyline
          (pts
            (xy 12.827 -14.605)
            (xy 12.827 -13.462)
          )
          (stroke (width 0) (type default) (color 0 0 0 0))
          (fill (type none))
        )
        (polyline
          (pts
            (xy 12.827 6.477)
            (xy 11.303 6.477)
          )
          (stroke (width 0) (type default) (color 0 0 0 0))
          (fill (type none))
        )
        (polyline
          (pts
            (xy 12.827 6.604)
            (xy 12.827 6.985)
          )
          (stroke (width 0) (type default) (color 0 0 0 0))
          (fill (type none))
        )
        (polyline
          (pts
            (xy 13.081 -35.687)
            (xy 11.303 -35.687)
          )
          (stroke (width 0) (type default) (color 0 0 0 0))
          (fill (type background))
        )
        (polyline
          (pts
            (xy 13.081 -35.179)
            (xy 11.303 -35.179)
          )
          (stroke (width 0) (type default) (color 0 0 0 0))
          (fill (type none))
        )
        (polyline
          (pts
            (xy 13.081 -35.179)
            (xy 13.081 -35.56)
          )
          (stroke (width 0) (type default) (color 0 0 0 0))
          (fill (type none))
        )
        (polyline
          (pts
            (xy 13.081 6.985)
            (xy 11.303 6.985)
          )
          (stroke (width 0) (type default) (color 0 0 0 0))
          (fill (type none))
        )
        (polyline
          (pts
            (xy 13.081 6.985)
            (xy 13.081 7.366)
          )
          (stroke (width 0) (type default) (color 0 0 0 0))
          (fill (type none))
        )
        (polyline
          (pts
            (xy 13.081 7.493)
            (xy 11.303 7.493)
          )
          (stroke (width 0) (type default) (color 0 0 0 0))
          (fill (type background))
        )
        (polyline
          (pts
            (xy 13.208 -28.575)
            (xy 17.653 -28.575)
          )
          (stroke (width 0) (type default) (color 0 0 0 0))
          (fill (type none))
        )
        (polyline
          (pts
            (xy 13.208 -14.605)
            (xy 13.208 -13.462)
          )
          (stroke (width 0) (type default) (color 0 0 0 0))
          (fill (type none))
        )
        (polyline
          (pts
            (xy 13.208 -14.097)
            (xy 13.208 -28.702)
          )
          (stroke (width 0) (type default) (color 0 0 0 0))
          (fill (type none))
        )
        (polyline
          (pts
            (xy 13.208 -14.097)
            (xy 13.208 0.508)
          )
          (stroke (width 0) (type default) (color 0 0 0 0))
          (fill (type none))
        )
        (polyline
          (pts
            (xy 13.208 0.381)
            (xy 17.653 0.381)
          )
          (stroke (width 0) (type default) (color 0 0 0 0))
          (fill (type none))
        )
        (polyline
          (pts
            (xy 13.843 -28.575)
            (xy 13.843 -14.097)
          )
          (stroke (width 0) (type default) (color 0 0 0 0))
          (fill (type none))
        )
        (polyline
          (pts
            (xy 13.843 -14.605)
            (xy 13.843 -13.462)
          )
          (stroke (width 0) (type default) (color 0 0 0 0))
          (fill (type none))
        )
        (polyline
          (pts
            (xy 13.843 0.381)
            (xy 13.843 -14.097)
          )
          (stroke (width 0) (type default) (color 0 0 0 0))
          (fill (type none))
        )
        (polyline
          (pts
            (xy 14.097 -14.605)
            (xy 14.097 -13.462)
          )
          (stroke (width 0) (type default) (color 0 0 0 0))
          (fill (type none))
        )
        (polyline
          (pts
            (xy 14.097 -14.097)
            (xy 14.097 -28.575)
          )
          (stroke (width 0) (type default) (color 0 0 0 0))
          (fill (type none))
        )
        (polyline
          (pts
            (xy 14.097 -14.097)
            (xy 14.097 0.381)
          )
          (stroke (width 0) (type default) (color 0 0 0 0))
          (fill (type none))
        )
        (polyline
          (pts
            (xy 14.605 -14.605)
            (xy 14.605 -13.462)
          )
          (stroke (width 0) (type default) (color 0 0 0 0))
          (fill (type none))
        )
        (polyline
          (pts
            (xy 14.605 -14.097)
            (xy 14.605 -26.035)
          )
          (stroke (width 0) (type default) (color 0 0 0 0))
          (fill (type none))
        )
        (polyline
          (pts
            (xy 14.605 -14.097)
            (xy 14.605 -2.159)
          )
          (stroke (width 0) (type default) (color 0 0 0 0))
          (fill (type none))
        )
        (polyline
          (pts
            (xy 16.637 -25.527)
            (xy 16.637 -25.146)
          )
          (stroke (width 0) (type default) (color 0 0 0 0))
          (fill (type none))
        )
        (polyline
          (pts
            (xy 16.637 -20.701)
            (xy 16.637 -20.828)
          )
          (stroke (width 0) (type default) (color 0 0 0 0))
          (fill (type none))
        )
        (polyline
          (pts
            (xy 16.637 -20.447)
            (xy 16.637 -20.701)
          )
          (stroke (width 0) (type default) (color 0 0 0 0))
          (fill (type none))
        )
        (polyline
          (pts
            (xy 16.637 -7.747)
            (xy 16.637 -7.493)
          )
          (stroke (width 0) (type default) (color 0 0 0 0))
          (fill (type none))
        )
        (polyline
          (pts
            (xy 16.637 -7.493)
            (xy 16.637 -7.366)
          )
          (stroke (width 0) (type default) (color 0 0 0 0))
          (fill (type none))
        )
        (polyline
          (pts
            (xy 16.637 -2.667)
            (xy 16.637 -3.048)
          )
          (stroke (width 0) (type default) (color 0 0 0 0))
          (fill (type none))
        )
        (polyline
          (pts
            (xy 16.891 -28.575)
            (xy 16.891 -25.527)
          )
          (stroke (width 0) (type default) (color 0 0 0 0))
          (fill (type none))
        )
        (polyline
          (pts
            (xy 16.891 -20.447)
            (xy 16.891 -14.097)
          )
          (stroke (width 0) (type default) (color 0 0 0 0))
          (fill (type none))
        )
        (polyline
          (pts
            (xy 16.891 -14.605)
            (xy 16.891 -13.462)
          )
          (stroke (width 0) (type default) (color 0 0 0 0))
          (fill (type none))
        )
        (polyline
          (pts
            (xy 16.891 -7.747)
            (xy 16.891 -14.097)
          )
          (stroke (width 0) (type default) (color 0 0 0 0))
          (fill (type none))
        )
        (polyline
          (pts
            (xy 16.891 0.381)
            (xy 16.891 -2.667)
          )
          (stroke (width 0) (type default) (color 0 0 0 0))
          (fill (type none))
        )
        (polyline
          (pts
            (xy 17.145 -25.527)
            (xy 17.145 -25.019)
          )
          (stroke (width 0) (type default) (color 0 0 0 0))
          (fill (type none))
        )
        (polyline
          (pts
            (xy 17.145 -20.447)
            (xy 17.145 -20.955)
          )
          (stroke (width 0) (type default) (color 0 0 0 0))
          (fill (type none))
        )
        (polyline
          (pts
            (xy 17.145 -7.747)
            (xy 17.145 -7.239)
          )
          (stroke (width 0) (type default) (color 0 0 0 0))
          (fill (type none))
        )
        (polyline
          (pts
            (xy 17.145 -2.667)
            (xy 17.145 -3.175)
          )
          (stroke (width 0) (type default) (color 0 0 0 0))
          (fill (type none))
        )
        (polyline
          (pts
            (xy 17.653 -29.083)
            (xy 13.208 -29.083)
          )
          (stroke (width 0) (type default) (color 0 0 0 0))
          (fill (type none))
        )
        (polyline
          (pts
            (xy 17.653 -26.162)
            (xy 17.653 -14.097)
          )
          (stroke (width 0) (type default) (color 0 0 0 0))
          (fill (type none))
        )
        (polyline
          (pts
            (xy 17.653 -14.605)
            (xy 17.653 -13.462)
          )
          (stroke (width 0) (type default) (color 0 0 0 0))
          (fill (type none))
        )
        (polyline
          (pts
            (xy 17.653 -2.032)
            (xy 17.653 -14.097)
          )
          (stroke (width 0) (type default) (color 0 0 0 0))
          (fill (type none))
        )
        (polyline
          (pts
            (xy 17.653 0.889)
            (xy 13.208 0.889)
          )
          (stroke (width 0) (type default) (color 0 0 0 0))
          (fill (type none))
        )
        (polyline
          (pts
            (xy 18.161 -14.605)
            (xy 18.161 -13.462)
          )
          (stroke (width 0) (type default) (color 0 0 0 0))
          (fill (type none))
        )
        (polyline
          (pts
            (xy 18.669 -14.605)
            (xy 18.669 -13.462)
          )
          (stroke (width 0) (type default) (color 0 0 0 0))
          (fill (type none))
        )
        (polyline
          (pts
            (xy 4.953 -30.607)
            (xy 4.445 -30.607)
            (xy 4.445 -14.097)
          )
          (stroke (width 0) (type default) (color 0 0 0 0))
          (fill (type none))
        )
        (polyline
          (pts
            (xy 4.953 -25.781)
            (xy 4.953 -29.972)
            (xy 4.953 -30.607)
          )
          (stroke (width 0) (type default) (color 0 0 0 0))
          (fill (type none))
        )
        (polyline
          (pts
            (xy 4.953 -2.413)
            (xy 4.953 1.778)
            (xy 4.953 2.413)
          )
          (stroke (width 0) (type default) (color 0 0 0 0))
          (fill (type none))
        )
        (polyline
          (pts
            (xy 4.953 2.413)
            (xy 4.445 2.413)
            (xy 4.445 -14.097)
          )
          (stroke (width 0) (type default) (color 0 0 0 0))
          (fill (type none))
        )
        (polyline
          (pts
            (xy 5.461 -29.083)
            (xy 5.461 -30.099)
            (xy 4.953 -30.099)
          )
          (stroke (width 0) (type default) (color 0 0 0 0))
          (fill (type none))
        )
        (polyline
          (pts
            (xy 5.461 0.889)
            (xy 5.461 1.905)
            (xy 4.953 1.905)
          )
          (stroke (width 0) (type default) (color 0 0 0 0))
          (fill (type none))
        )
        (polyline
          (pts
            (xy 9.779 -14.097)
            (xy 9.779 -29.591)
            (xy 11.303 -29.591)
          )
          (stroke (width 0) (type default) (color 0 0 0 0))
          (fill (type none))
        )
        (polyline
          (pts
            (xy 9.779 -14.097)
            (xy 9.779 1.397)
            (xy 11.303 1.397)
          )
          (stroke (width 0) (type default) (color 0 0 0 0))
          (fill (type none))
        )
        (polyline
          (pts
            (xy 10.287 -14.097)
            (xy 10.287 -29.083)
            (xy 11.303 -29.083)
          )
          (stroke (width 0) (type default) (color 0 0 0 0))
          (fill (type none))
        )
        (polyline
          (pts
            (xy 10.287 -14.097)
            (xy 10.287 0.889)
            (xy 11.303 0.889)
          )
          (stroke (width 0) (type default) (color 0 0 0 0))
          (fill (type none))
        )
        (polyline
          (pts
            (xy 12.319 -14.097)
            (xy 12.319 -29.083)
            (xy 11.303 -29.083)
          )
          (stroke (width 0) (type default) (color 0 0 0 0))
          (fill (type none))
        )
        (polyline
          (pts
            (xy 12.319 -14.097)
            (xy 12.319 0.889)
            (xy 11.303 0.889)
          )
          (stroke (width 0) (type default) (color 0 0 0 0))
          (fill (type none))
        )
        (polyline
          (pts
            (xy 12.827 -14.097)
            (xy 12.827 -29.591)
            (xy 11.303 -29.591)
          )
          (stroke (width 0) (type default) (color 0 0 0 0))
          (fill (type none))
        )
        (polyline
          (pts
            (xy 12.827 -14.097)
            (xy 12.827 1.397)
            (xy 11.303 1.397)
          )
          (stroke (width 0) (type default) (color 0 0 0 0))
          (fill (type none))
        )
        (polyline
          (pts
            (xy 17.145 -29.083)
            (xy 17.145 -30.099)
            (xy 17.653 -30.099)
          )
          (stroke (width 0) (type default) (color 0 0 0 0))
          (fill (type none))
        )
        (polyline
          (pts
            (xy 17.145 0.889)
            (xy 17.145 1.905)
            (xy 17.653 1.905)
          )
          (stroke (width 0) (type default) (color 0 0 0 0))
          (fill (type none))
        )
        (polyline
          (pts
            (xy 17.653 -30.607)
            (xy 18.161 -30.607)
            (xy 18.161 -14.097)
          )
          (stroke (width 0) (type default) (color 0 0 0 0))
          (fill (type none))
        )
        (polyline
          (pts
            (xy 17.653 -25.781)
            (xy 17.653 -29.972)
            (xy 17.653 -30.607)
          )
          (stroke (width 0) (type default) (color 0 0 0 0))
          (fill (type none))
        )
        (polyline
          (pts
            (xy 17.653 -2.413)
            (xy 17.653 1.778)
            (xy 17.653 2.413)
          )
          (stroke (width 0) (type default) (color 0 0 0 0))
          (fill (type none))
        )
        (polyline
          (pts
            (xy 17.653 2.413)
            (xy 18.161 2.413)
            (xy 18.161 -14.097)
          )
          (stroke (width 0) (type default) (color 0 0 0 0))
          (fill (type none))
        )
        (polyline
          (pts
            (xy 4.953 -25.527)
            (xy 6.3754 -24.1046)
            (xy 6.6294 -23.5966)
            (xy 6.731 -22.987)
          )
          (stroke (width 0) (type default) (color 0 0 0 0))
          (fill (type none))
        )
        (polyline
          (pts
            (xy 4.953 -24.257)
            (xy 5.461 -23.6982)
            (xy 5.5626 -23.368)
            (xy 5.588 -23.0124)
          )
          (stroke (width 0) (type default) (color 0 0 0 0))
          (fill (type none))
        )
        (polyline
          (pts
            (xy 4.953 -21.717)
            (xy 5.461 -22.2758)
            (xy 5.5626 -22.606)
            (xy 5.588 -22.9616)
          )
          (stroke (width 0) (type default) (color 0 0 0 0))
          (fill (type none))
        )
        (polyline
          (pts
            (xy 4.953 -20.447)
            (xy 6.3754 -21.8694)
            (xy 6.6294 -22.3774)
            (xy 6.731 -22.987)
          )
          (stroke (width 0) (type default) (color 0 0 0 0))
          (fill (type none))
        )
        (polyline
          (pts
            (xy 4.953 -7.747)
            (xy 6.3754 -6.3246)
            (xy 6.6294 -5.8166)
            (xy 6.731 -5.207)
          )
          (stroke (width 0) (type default) (color 0 0 0 0))
          (fill (type none))
        )
        (polyline
          (pts
            (xy 4.953 -6.477)
            (xy 5.461 -5.9182)
            (xy 5.5626 -5.588)
            (xy 5.588 -5.2324)
          )
          (stroke (width 0) (type default) (color 0 0 0 0))
          (fill (type none))
        )
        (polyline
          (pts
            (xy 4.953 -3.937)
            (xy 5.461 -4.4958)
            (xy 5.5626 -4.826)
            (xy 5.588 -5.1816)
          )
          (stroke (width 0) (type default) (color 0 0 0 0))
          (fill (type none))
        )
        (polyline
          (pts
            (xy 4.953 -2.667)
            (xy 6.3754 -4.0894)
            (xy 6.6294 -4.5974)
            (xy 6.731 -5.207)
          )
          (stroke (width 0) (type default) (color 0 0 0 0))
          (fill (type none))
        )
        (polyline
          (pts
            (xy 9.398 -28.702)
            (xy 9.398 -29.083)
            (xy 9.525 -29.337)
            (xy 9.779 -29.591)
          )
          (stroke (width 0) (type default) (color 0 0 0 0))
          (fill (type none))
        )
        (polyline
          (pts
            (xy 9.398 0.508)
            (xy 9.398 0.889)
            (xy 9.525 1.143)
            (xy 9.779 1.397)
          )
          (stroke (width 0) (type default) (color 0 0 0 0))
          (fill (type none))
        )
        (polyline
          (pts
            (xy 11.303 -30.607)
            (xy 9.906 -30.607)
            (xy 9.779 -30.607)
            (xy 9.779 -29.591)
          )
          (stroke (width 0) (type default) (color 0 0 0 0))
          (fill (type none))
        )
        (polyline
          (pts
            (xy 11.303 -30.607)
            (xy 12.7 -30.607)
            (xy 12.827 -30.607)
            (xy 12.827 -29.591)
          )
          (stroke (width 0) (type default) (color 0 0 0 0))
          (fill (type none))
        )
        (polyline
          (pts
            (xy 11.303 2.413)
            (xy 9.906 2.413)
            (xy 9.779 2.413)
            (xy 9.779 1.397)
          )
          (stroke (width 0) (type default) (color 0 0 0 0))
          (fill (type none))
        )
        (polyline
          (pts
            (xy 11.303 2.413)
            (xy 12.7 2.413)
            (xy 12.827 2.413)
            (xy 12.827 1.397)
          )
          (stroke (width 0) (type default) (color 0 0 0 0))
          (fill (type none))
        )
        (polyline
          (pts
            (xy 13.208 -28.702)
            (xy 13.208 -29.083)
            (xy 13.081 -29.337)
            (xy 12.827 -29.591)
          )
          (stroke (width 0) (type default) (color 0 0 0 0))
          (fill (type none))
        )
        (polyline
          (pts
            (xy 13.208 0.508)
            (xy 13.208 0.889)
            (xy 13.081 1.143)
            (xy 12.827 1.397)
          )
          (stroke (width 0) (type default) (color 0 0 0 0))
          (fill (type none))
        )
        (polyline
          (pts
            (xy 17.653 -25.527)
            (xy 16.2306 -24.1046)
            (xy 15.9766 -23.5966)
            (xy 15.875 -22.987)
          )
          (stroke (width 0) (type default) (color 0 0 0 0))
          (fill (type none))
        )
        (polyline
          (pts
            (xy 17.653 -24.257)
            (xy 17.145 -23.6982)
            (xy 17.0434 -23.368)
            (xy 17.018 -23.0124)
          )
          (stroke (width 0) (type default) (color 0 0 0 0))
          (fill (type none))
        )
        (polyline
          (pts
            (xy 17.653 -21.717)
            (xy 17.145 -22.2758)
            (xy 17.0434 -22.606)
            (xy 17.018 -22.9616)
          )
          (stroke (width 0) (type default) (color 0 0 0 0))
          (fill (type none))
        )
        (polyline
          (pts
            (xy 17.653 -20.447)
            (xy 16.2306 -21.8694)
            (xy 15.9766 -22.3774)
            (xy 15.875 -22.987)
          )
          (stroke (width 0) (type default) (color 0 0 0 0))
          (fill (type none))
        )
        (polyline
          (pts
            (xy 17.653 -7.747)
            (xy 16.2306 -6.3246)
            (xy 15.9766 -5.8166)
            (xy 15.875 -5.207)
          )
          (stroke (width 0) (type default) (color 0 0 0 0))
          (fill (type none))
        )
        (polyline
          (pts
            (xy 17.653 -6.477)
            (xy 17.145 -5.9182)
            (xy 17.0434 -5.588)
            (xy 17.018 -5.2324)
          )
          (stroke (width 0) (type default) (color 0 0 0 0))
          (fill (type none))
        )
        (polyline
          (pts
            (xy 17.653 -3.937)
            (xy 17.145 -4.4958)
            (xy 17.0434 -4.826)
            (xy 17.018 -5.1816)
          )
          (stroke (width 0) (type default) (color 0 0 0 0))
          (fill (type none))
        )
        (polyline
          (pts
            (xy 17.653 -2.667)
            (xy 16.2306 -4.0894)
            (xy 15.9766 -4.5974)
            (xy 15.875 -5.207)
          )
          (stroke (width 0) (type default) (color 0 0 0 0))
          (fill (type none))
        )
        (polyline
          (pts
            (xy 5.461 -25.527)
            (xy 6.5278 -24.5618)
            (xy 6.858 -24.2062)
            (xy 7.0866 -23.7236)
            (xy 7.239 -22.987)
          )
          (stroke (width 0) (type default) (color 0 0 0 0))
          (fill (type none))
        )
        (polyline
          (pts
            (xy 5.461 -20.447)
            (xy 6.5278 -21.4122)
            (xy 6.858 -21.7678)
            (xy 7.0866 -22.2504)
            (xy 7.239 -22.987)
          )
          (stroke (width 0) (type default) (color 0 0 0 0))
          (fill (type none))
        )
        (polyline
          (pts
            (xy 5.461 -7.747)
            (xy 6.5278 -6.7818)
            (xy 6.858 -6.4262)
            (xy 7.0866 -5.9436)
            (xy 7.239 -5.207)
          )
          (stroke (width 0) (type default) (color 0 0 0 0))
          (fill (type none))
        )
        (polyline
          (pts
            (xy 5.461 -2.667)
            (xy 6.5278 -3.6322)
            (xy 6.858 -3.9878)
            (xy 7.0866 -4.4704)
            (xy 7.239 -5.207)
          )
          (stroke (width 0) (type default) (color 0 0 0 0))
          (fill (type none))
        )
        (polyline
          (pts
            (xy 17.145 -25.527)
            (xy 16.0782 -24.5618)
            (xy 15.748 -24.2062)
            (xy 15.5194 -23.7236)
            (xy 15.367 -22.987)
          )
          (stroke (width 0) (type default) (color 0 0 0 0))
          (fill (type none))
        )
        (polyline
          (pts
            (xy 17.145 -20.447)
            (xy 16.0782 -21.4122)
            (xy 15.748 -21.7678)
            (xy 15.5194 -22.2504)
            (xy 15.367 -22.987)
          )
          (stroke (width 0) (type default) (color 0 0 0 0))
          (fill (type none))
        )
        (polyline
          (pts
            (xy 17.145 -7.747)
            (xy 16.0782 -6.7818)
            (xy 15.748 -6.4262)
            (xy 15.5194 -5.9436)
            (xy 15.367 -5.207)
          )
          (stroke (width 0) (type default) (color 0 0 0 0))
          (fill (type none))
        )
        (polyline
          (pts
            (xy 17.145 -2.667)
            (xy 16.0782 -3.6322)
            (xy 15.748 -3.9878)
            (xy 15.5194 -4.4704)
            (xy 15.367 -5.207)
          )
          (stroke (width 0) (type default) (color 0 0 0 0))
          (fill (type none))
        )
        (polyline
          (pts
            (xy 4.953 -25.527)
            (xy 5.969 -25.527)
            (xy 7.239 -24.257)
            (xy 7.239 -21.717)
            (xy 5.969 -20.447)
            (xy 4.953 -20.447)
          )
          (stroke (width 0) (type default) (color 0 0 0 0))
          (fill (type none))
        )
        (polyline
          (pts
            (xy 4.953 -2.667)
            (xy 5.969 -2.667)
            (xy 7.239 -3.937)
            (xy 7.239 -6.477)
            (xy 5.969 -7.747)
            (xy 4.953 -7.747)
          )
          (stroke (width 0) (type default) (color 0 0 0 0))
          (fill (type none))
        )
        (polyline
          (pts
            (xy 8.509 -29.083)
            (xy 8.5598 -29.4894)
            (xy 8.6614 -29.8958)
            (xy 8.9154 -30.3022)
            (xy 9.3218 -30.6578)
            (xy 9.779 -30.861)
          )
          (stroke (width 0) (type default) (color 0 0 0 0))
          (fill (type none))
        )
        (polyline
          (pts
            (xy 8.509 -27.559)
            (xy 8.001 -27.559)
            (xy 7.747 -27.305)
            (xy 7.747 -26.289)
            (xy 8.001 -26.035)
            (xy 8.509 -26.035)
          )
          (stroke (width 0) (type default) (color 0 0 0 0))
          (fill (type none))
        )
        (polyline
          (pts
            (xy 8.509 -0.635)
            (xy 8.001 -0.635)
            (xy 7.747 -0.889)
            (xy 7.747 -1.905)
            (xy 8.001 -2.159)
            (xy 8.509 -2.159)
          )
          (stroke (width 0) (type default) (color 0 0 0 0))
          (fill (type none))
        )
        (polyline
          (pts
            (xy 8.509 0.889)
            (xy 8.5598 1.2954)
            (xy 8.6614 1.7018)
            (xy 8.9154 2.1082)
            (xy 9.3218 2.4638)
            (xy 9.779 2.667)
          )
          (stroke (width 0) (type default) (color 0 0 0 0))
          (fill (type none))
        )
        (polyline
          (pts
            (xy 14.097 -29.083)
            (xy 14.0462 -29.4894)
            (xy 13.9446 -29.8958)
            (xy 13.6906 -30.3022)
            (xy 13.2842 -30.6578)
            (xy 12.827 -30.861)
          )
          (stroke (width 0) (type default) (color 0 0 0 0))
          (fill (type none))
        )
        (polyline
          (pts
            (xy 14.097 -27.559)
            (xy 14.605 -27.559)
            (xy 14.859 -27.305)
            (xy 14.859 -26.289)
            (xy 14.605 -26.035)
            (xy 14.097 -26.035)
          )
          (stroke (width 0) (type default) (color 0 0 0 0))
          (fill (type none))
        )
        (polyline
          (pts
            (xy 14.097 -0.635)
            (xy 14.605 -0.635)
            (xy 14.859 -0.889)
            (xy 14.859 -1.905)
            (xy 14.605 -2.159)
            (xy 14.097 -2.159)
          )
          (stroke (width 0) (type default) (color 0 0 0 0))
          (fill (type none))
        )
        (polyline
          (pts
            (xy 14.097 0.889)
            (xy 14.0462 1.2954)
            (xy 13.9446 1.7018)
            (xy 13.6906 2.1082)
            (xy 13.2842 2.4638)
            (xy 12.827 2.667)
          )
          (stroke (width 0) (type default) (color 0 0 0 0))
          (fill (type none))
        )
        (polyline
          (pts
            (xy 17.653 -25.527)
            (xy 16.637 -25.527)
            (xy 15.367 -24.257)
            (xy 15.367 -21.717)
            (xy 16.637 -20.447)
            (xy 17.653 -20.447)
          )
          (stroke (width 0) (type default) (color 0 0 0 0))
          (fill (type none))
        )
        (polyline
          (pts
            (xy 17.653 -2.667)
            (xy 16.637 -2.667)
            (xy 15.367 -3.937)
            (xy 15.367 -6.477)
            (xy 16.637 -7.747)
            (xy 17.653 -7.747)
          )
          (stroke (width 0) (type default) (color 0 0 0 0))
          (fill (type none))
        )
        (polyline
          (pts
            (xy 18.669 -14.097)
            (xy 18.796 -31.115)
            (xy 18.796 -31.115)
            (xy 18.669 -31.623)
            (xy 18.5674 -32.131)
            (xy 18.3642 -32.8422)
            (xy 18.0086 -33.6042)
            (xy 17.6022 -34.2138)
            (xy 17.1958 -34.671)
            (xy 16.6878 -35.1282)
            (xy 15.9766 -35.5854)
            (xy 15.2654 -35.8902)
            (xy 14.5542 -36.0934)
            (xy 13.843 -36.195)
            (xy 9.017 -36.195)
            (xy 7.8994 -36.0934)
            (xy 7.0358 -35.7886)
            (xy 5.969 -35.179)
            (xy 4.953 -34.1122)
            (xy 4.3942 -33.0962)
            (xy 4.0386 -32.0802)
            (xy 3.937 -31.75)
            (xy 3.81 -31.115)
            (xy 3.81 -14.097)
          )
          (stroke (width 0.254) (type default) (color 0 0 0 0))
          (fill (type background))
        )
        (polyline
          (pts
            (xy 18.669 -14.097)
            (xy 18.796 2.921)
            (xy 18.796 3.175)
            (xy 18.669 3.683)
            (xy 18.5674 3.937)
            (xy 18.3642 4.6482)
            (xy 18.0086 5.4102)
            (xy 17.6022 6.0198)
            (xy 17.1958 6.477)
            (xy 16.6878 6.9342)
            (xy 15.9766 7.3914)
            (xy 15.2654 7.6962)
            (xy 14.5542 7.8994)
            (xy 13.843 8.001)
            (xy 9.017 8.001)
            (xy 7.8994 7.8994)
            (xy 7.0358 7.5946)
            (xy 5.969 6.985)
            (xy 4.953 5.9182)
            (xy 4.3942 4.9022)
            (xy 4.0386 3.8862)
            (xy 3.937 3.429)
            (xy 3.81 2.794)
            (xy 3.81 -14.097)
          )
          (stroke (width 0.254) (type default) (color 0 0 0 0))
          (fill (type background))
        )
        (arc (start 4.445 -30.607) (mid 5.8538 -34.2782) (end 9.525 -35.687)
          (stroke (width 0) (type default) (color 0 0 0 0))
          (fill (type none))
        )
        (arc (start 4.953 -30.607) (mid 6.3281 -33.8039) (end 9.525 -35.179)
          (stroke (width 0) (type default) (color 0 0 0 0))
          (fill (type none))
        )
        (arc (start 5.461 -30.099) (mid 6.604 -33.3447) (end 9.779 -34.671)
          (stroke (width 0) (type default) (color 0 0 0 0))
          (fill (type none))
        )
        (rectangle (start 9.525 -28.702) (end 9.779 -27.432)
          (stroke (width 0) (type default) (color 0 0 0 0))
          (fill (type outline))
        )
        (rectangle (start 9.525 -26.162) (end 9.779 -24.892)
          (stroke (width 0) (type default) (color 0 0 0 0))
          (fill (type outline))
        )
        (rectangle (start 9.525 -23.622) (end 9.779 -22.352)
          (stroke (width 0) (type default) (color 0 0 0 0))
          (fill (type outline))
        )
        (rectangle (start 9.525 -21.082) (end 9.779 -19.812)
          (stroke (width 0) (type default) (color 0 0 0 0))
          (fill (type outline))
        )
        (rectangle (start 9.525 -18.542) (end 9.779 -17.272)
          (stroke (width 0) (type default) (color 0 0 0 0))
          (fill (type outline))
        )
        (rectangle (start 9.525 -16.002) (end 9.779 -14.732)
          (stroke (width 0) (type default) (color 0 0 0 0))
          (fill (type outline))
        )
        (rectangle (start 9.525 -12.192) (end 9.779 -13.462)
          (stroke (width 0) (type default) (color 0 0 0 0))
          (fill (type outline))
        )
        (rectangle (start 9.525 -9.652) (end 9.779 -10.922)
          (stroke (width 0) (type default) (color 0 0 0 0))
          (fill (type outline))
        )
        (rectangle (start 9.525 -7.112) (end 9.779 -8.382)
          (stroke (width 0) (type default) (color 0 0 0 0))
          (fill (type outline))
        )
        (rectangle (start 9.525 -4.572) (end 9.779 -5.842)
          (stroke (width 0) (type default) (color 0 0 0 0))
          (fill (type outline))
        )
        (rectangle (start 9.525 -2.032) (end 9.779 -3.302)
          (stroke (width 0) (type default) (color 0 0 0 0))
          (fill (type outline))
        )
        (rectangle (start 9.525 0.508) (end 9.779 -0.762)
          (stroke (width 0) (type default) (color 0 0 0 0))
          (fill (type outline))
        )
        (arc (start 9.525 6.985) (mid 6.3281 5.6099) (end 4.953 2.413)
          (stroke (width 0) (type default) (color 0 0 0 0))
          (fill (type none))
        )
        (arc (start 9.525 7.493) (mid 5.8538 6.0842) (end 4.445 2.413)
          (stroke (width 0) (type default) (color 0 0 0 0))
          (fill (type none))
        )
        (arc (start 9.779 6.477) (mid 6.6129 5.1421) (end 5.461 1.905)
          (stroke (width 0) (type default) (color 0 0 0 0))
          (fill (type none))
        )
        (arc (start 12.827 -34.671) (mid 15.9931 -33.3361) (end 17.145 -30.099)
          (stroke (width 0) (type default) (color 0 0 0 0))
          (fill (type none))
        )
        (arc (start 13.081 -35.687) (mid 16.7522 -34.2782) (end 18.161 -30.607)
          (stroke (width 0) (type default) (color 0 0 0 0))
          (fill (type none))
        )
        (arc (start 13.081 -35.179) (mid 16.2779 -33.8039) (end 17.653 -30.607)
          (stroke (width 0) (type default) (color 0 0 0 0))
          (fill (type none))
        )
        (rectangle (start 13.081 -28.702) (end 12.827 -27.432)
          (stroke (width 0) (type default) (color 0 0 0 0))
          (fill (type outline))
        )
        (rectangle (start 13.081 -26.162) (end 12.827 -24.892)
          (stroke (width 0) (type default) (color 0 0 0 0))
          (fill (type outline))
        )
        (rectangle (start 13.081 -23.622) (end 12.827 -22.352)
          (stroke (width 0) (type default) (color 0 0 0 0))
          (fill (type outline))
        )
        (rectangle (start 13.081 -21.082) (end 12.827 -19.812)
          (stroke (width 0) (type default) (color 0 0 0 0))
          (fill (type outline))
        )
        (rectangle (start 13.081 -18.542) (end 12.827 -17.272)
          (stroke (width 0) (type default) (color 0 0 0 0))
          (fill (type outline))
        )
        (rectangle (start 13.081 -16.002) (end 12.827 -14.732)
          (stroke (width 0) (type default) (color 0 0 0 0))
          (fill (type outline))
        )
        (rectangle (start 13.081 -12.192) (end 12.827 -13.462)
          (stroke (width 0) (type default) (color 0 0 0 0))
          (fill (type outline))
        )
        (rectangle (start 13.081 -9.652) (end 12.827 -10.922)
          (stroke (width 0) (type default) (color 0 0 0 0))
          (fill (type outline))
        )
        (rectangle (start 13.081 -7.112) (end 12.827 -8.382)
          (stroke (width 0) (type default) (color 0 0 0 0))
          (fill (type outline))
        )
        (rectangle (start 13.081 -4.572) (end 12.827 -5.842)
          (stroke (width 0) (type default) (color 0 0 0 0))
          (fill (type outline))
        )
        (rectangle (start 13.081 -2.032) (end 12.827 -3.302)
          (stroke (width 0) (type default) (color 0 0 0 0))
          (fill (type outline))
        )
        (rectangle (start 13.081 0.508) (end 12.827 -0.762)
          (stroke (width 0) (type default) (color 0 0 0 0))
          (fill (type outline))
        )
        (arc (start 17.145 1.905) (mid 16.002 5.1507) (end 12.827 6.477)
          (stroke (width 0) (type default) (color 0 0 0 0))
          (fill (type none))
        )
        (arc (start 17.653 2.413) (mid 16.2779 5.6099) (end 13.081 6.985)
          (stroke (width 0) (type default) (color 0 0 0 0))
          (fill (type none))
        )
        (arc (start 18.161 2.413) (mid 16.7522 6.0842) (end 13.081 7.493)
          (stroke (width 0) (type default) (color 0 0 0 0))
          (fill (type none))
        )
        (pin passive line (at 22.86 0 180) (length 3.81)
          (name "~" (effects (font (size 1.27 1.27))))
          (number "A1" (effects (font (size 1.27 1.27))))
        )
        (pin passive line (at 22.86 -22.86 180) (length 3.81)
          (name "~" (effects (font (size 1.27 1.27))))
          (number "A10" (effects (font (size 1.27 1.27))))
        )
        (pin passive line (at 22.86 -25.4 180) (length 3.81)
          (name "~" (effects (font (size 1.27 1.27))))
          (number "A11" (effects (font (size 1.27 1.27))))
        )
        (pin passive line (at 22.86 -27.94 180) (length 3.81)
          (name "~" (effects (font (size 1.27 1.27))))
          (number "A12" (effects (font (size 1.27 1.27))))
        )
        (pin passive line (at 22.86 -2.54 180) (length 3.81)
          (name "~" (effects (font (size 1.27 1.27))))
          (number "A2" (effects (font (size 1.27 1.27))))
        )
        (pin passive line (at 22.86 -5.08 180) (length 3.81)
          (name "~" (effects (font (size 1.27 1.27))))
          (number "A3" (effects (font (size 1.27 1.27))))
        )
        (pin passive line (at 22.86 -7.62 180) (length 3.81)
          (name "~" (effects (font (size 1.27 1.27))))
          (number "A4" (effects (font (size 1.27 1.27))))
        )
        (pin passive line (at 22.86 -10.16 180) (length 3.81)
          (name "~" (effects (font (size 1.27 1.27))))
          (number "A5" (effects (font (size 1.27 1.27))))
        )
        (pin passive line (at 22.86 -12.7 180) (length 3.81)
          (name "~" (effects (font (size 1.27 1.27))))
          (number "A6" (effects (font (size 1.27 1.27))))
        )
        (pin passive line (at 22.86 -15.24 180) (length 3.81)
          (name "~" (effects (font (size 1.27 1.27))))
          (number "A7" (effects (font (size 1.27 1.27))))
        )
        (pin passive line (at 22.86 -17.78 180) (length 3.81)
          (name "~" (effects (font (size 1.27 1.27))))
          (number "A8" (effects (font (size 1.27 1.27))))
        )
        (pin passive line (at 22.86 -20.32 180) (length 3.81)
          (name "~" (effects (font (size 1.27 1.27))))
          (number "A9" (effects (font (size 1.27 1.27))))
        )
        (pin passive line (at 0 -27.94 0) (length 3.81)
          (name "~" (effects (font (size 1.27 1.27))))
          (number "B1" (effects (font (size 1.27 1.27))))
        )
        (pin passive line (at 0 -5.08 0) (length 3.81)
          (name "~" (effects (font (size 1.27 1.27))))
          (number "B10" (effects (font (size 1.27 1.27))))
        )
        (pin passive line (at 0 -2.54 0) (length 3.81)
          (name "~" (effects (font (size 1.27 1.27))))
          (number "B11" (effects (font (size 1.27 1.27))))
        )
        (pin passive line (at 0 0 0) (length 3.81)
          (name "~" (effects (font (size 1.27 1.27))))
          (number "B12" (effects (font (size 1.27 1.27))))
        )
        (pin passive line (at 0 -25.4 0) (length 3.81)
          (name "~" (effects (font (size 1.27 1.27))))
          (number "B2" (effects (font (size 1.27 1.27))))
        )
        (pin passive line (at 0 -22.86 0) (length 3.81)
          (name "~" (effects (font (size 1.27 1.27))))
          (number "B3" (effects (font (size 1.27 1.27))))
        )
        (pin passive line (at 0 -20.32 0) (length 3.81)
          (name "~" (effects (font (size 1.27 1.27))))
          (number "B4" (effects (font (size 1.27 1.27))))
        )
        (pin passive line (at 0 -17.78 0) (length 3.81)
          (name "~" (effects (font (size 1.27 1.27))))
          (number "B5" (effects (font (size 1.27 1.27))))
        )
        (pin passive line (at 0 -15.24 0) (length 3.81)
          (name "~" (effects (font (size 1.27 1.27))))
          (number "B6" (effects (font (size 1.27 1.27))))
        )
        (pin passive line (at 0 -12.7 0) (length 3.81)
          (name "~" (effects (font (size 1.27 1.27))))
          (number "B7" (effects (font (size 1.27 1.27))))
        )
        (pin passive line (at 0 -10.16 0) (length 3.81)
          (name "~" (effects (font (size 1.27 1.27))))
          (number "B8" (effects (font (size 1.27 1.27))))
        )
        (pin passive line (at 0 -7.62 0) (length 3.81)
          (name "~" (effects (font (size 1.27 1.27))))
          (number "B9" (effects (font (size 1.27 1.27))))
        )
        (pin input line (at 6.35 -39.37 90) (length 3.81)
          (name "~" (effects (font (size 1.27 1.27))))
          (number "SH" (effects (font (size 1.27 1.27))))
        )
      )
    )
	(symbol "12401598E4_2A_2" (in_bom yes) (on_board yes)
      (property "Reference" "J" (id 0) (at 33.02 -2.54 0)
        (effects (font (size 1.27 1.27) (thickness 0.15)) (justify left bottom))
      )
      (property "Value" "12401598E4_2A_2" (id 1) (at 33.02 -7.62 0)
        (effects (font (size 1.27 1.27) (thickness 0.15)) (justify left bottom) hide)
      )
      (property "Footprint" "antmicro-footprints:USB-C_12401610E4_2A" (id 2) (at 33.02 -10.16 0)
        (effects (font (size 1.27 1.27) (thickness 0.15)) (justify left bottom) hide)
      )
      (property "Datasheet" "http://www.amphenol-icc.com/media/wysiwyg/files/drawing/12401598xxx2a.pdf" (id 3) (at 33.02 -12.7 0)
        (effects (font (size 1.27 1.27) (thickness 0.15)) (justify left bottom) hide)
      )
      (property "MPN" "12401598E4#2A" (id 4) (at 33.02 -5.08 0)
        (effects (font (size 1.27 1.27) (thickness 0.15)) (justify left bottom))
      )
      (property "Manufacturer" "Amphenol" (id 5) (at 33.02 -15.24 0)
        (effects (font (size 1.27 1.27) (thickness 0.15)) (justify left bottom) hide)
      )
      (property "Author" "Antmicro" (id 6) (at 33.02 -17.78 0)
        (effects (font (size 1.27 1.27) (thickness 0.15)) (justify left bottom) hide)
      )
      (property "License" "Apache-2.0" (id 7) (at 33.02 -20.32 0)
        (effects (font (size 1.27 1.27) (thickness 0.15)) (justify left bottom) hide)
      )
      (symbol "12401598E4_2A_2_1_1"
        (polyline
          (pts
            (xy 4.445 -14.605)
            (xy 4.445 -13.462)
          )
          (stroke (width 0) (type default) (color 0 0 0 0))
          (fill (type none))
        )
        (polyline
          (pts
            (xy 4.953 -29.083)
            (xy 9.398 -29.083)
          )
          (stroke (width 0) (type default) (color 0 0 0 0))
          (fill (type none))
        )
        (polyline
          (pts
            (xy 4.953 -26.162)
            (xy 4.953 -14.097)
          )
          (stroke (width 0) (type default) (color 0 0 0 0))
          (fill (type none))
        )
        (polyline
          (pts
            (xy 4.953 -14.605)
            (xy 4.953 -13.462)
          )
          (stroke (width 0) (type default) (color 0 0 0 0))
          (fill (type none))
        )
        (polyline
          (pts
            (xy 4.953 -2.032)
            (xy 4.953 -14.097)
          )
          (stroke (width 0) (type default) (color 0 0 0 0))
          (fill (type none))
        )
        (polyline
          (pts
            (xy 4.953 0.889)
            (xy 9.398 0.889)
          )
          (stroke (width 0) (type default) (color 0 0 0 0))
          (fill (type none))
        )
        (polyline
          (pts
            (xy 5.461 -25.527)
            (xy 5.461 -25.019)
          )
          (stroke (width 0) (type default) (color 0 0 0 0))
          (fill (type none))
        )
        (polyline
          (pts
            (xy 5.461 -20.447)
            (xy 5.461 -20.955)
          )
          (stroke (width 0) (type default) (color 0 0 0 0))
          (fill (type none))
        )
        (polyline
          (pts
            (xy 5.461 -7.747)
            (xy 5.461 -7.239)
          )
          (stroke (width 0) (type default) (color 0 0 0 0))
          (fill (type none))
        )
        (polyline
          (pts
            (xy 5.461 -2.667)
            (xy 5.461 -3.175)
          )
          (stroke (width 0) (type default) (color 0 0 0 0))
          (fill (type none))
        )
        (polyline
          (pts
            (xy 5.715 -28.575)
            (xy 5.715 -25.527)
          )
          (stroke (width 0) (type default) (color 0 0 0 0))
          (fill (type none))
        )
        (polyline
          (pts
            (xy 5.715 -20.447)
            (xy 5.715 -14.097)
          )
          (stroke (width 0) (type default) (color 0 0 0 0))
          (fill (type none))
        )
        (polyline
          (pts
            (xy 5.715 -14.605)
            (xy 5.715 -13.462)
          )
          (stroke (width 0) (type default) (color 0 0 0 0))
          (fill (type none))
        )
        (polyline
          (pts
            (xy 5.715 -7.747)
            (xy 5.715 -14.097)
          )
          (stroke (width 0) (type default) (color 0 0 0 0))
          (fill (type none))
        )
        (polyline
          (pts
            (xy 5.715 0.381)
            (xy 5.715 -2.667)
          )
          (stroke (width 0) (type default) (color 0 0 0 0))
          (fill (type none))
        )
        (polyline
          (pts
            (xy 5.969 -25.527)
            (xy 5.969 -25.146)
          )
          (stroke (width 0) (type default) (color 0 0 0 0))
          (fill (type none))
        )
        (polyline
          (pts
            (xy 5.969 -20.701)
            (xy 5.969 -20.828)
          )
          (stroke (width 0) (type default) (color 0 0 0 0))
          (fill (type none))
        )
        (polyline
          (pts
            (xy 5.969 -20.447)
            (xy 5.969 -20.701)
          )
          (stroke (width 0) (type default) (color 0 0 0 0))
          (fill (type none))
        )
        (polyline
          (pts
            (xy 5.969 -7.747)
            (xy 5.969 -7.493)
          )
          (stroke (width 0) (type default) (color 0 0 0 0))
          (fill (type none))
        )
        (polyline
          (pts
            (xy 5.969 -7.493)
            (xy 5.969 -7.366)
          )
          (stroke (width 0) (type default) (color 0 0 0 0))
          (fill (type none))
        )
        (polyline
          (pts
            (xy 5.969 -2.667)
            (xy 5.969 -3.048)
          )
          (stroke (width 0) (type default) (color 0 0 0 0))
          (fill (type none))
        )
        (polyline
          (pts
            (xy 8.001 -14.605)
            (xy 8.001 -13.462)
          )
          (stroke (width 0) (type default) (color 0 0 0 0))
          (fill (type none))
        )
        (polyline
          (pts
            (xy 8.001 -14.097)
            (xy 8.001 -26.035)
          )
          (stroke (width 0) (type default) (color 0 0 0 0))
          (fill (type none))
        )
        (polyline
          (pts
            (xy 8.001 -14.097)
            (xy 8.001 -2.159)
          )
          (stroke (width 0) (type default) (color 0 0 0 0))
          (fill (type none))
        )
        (polyline
          (pts
            (xy 8.509 -14.605)
            (xy 8.509 -13.462)
          )
          (stroke (width 0) (type default) (color 0 0 0 0))
          (fill (type none))
        )
        (polyline
          (pts
            (xy 8.509 -14.097)
            (xy 8.509 -28.575)
          )
          (stroke (width 0) (type default) (color 0 0 0 0))
          (fill (type none))
        )
        (polyline
          (pts
            (xy 8.509 -14.097)
            (xy 8.509 0.381)
          )
          (stroke (width 0) (type default) (color 0 0 0 0))
          (fill (type none))
        )
        (polyline
          (pts
            (xy 8.763 -28.575)
            (xy 8.763 -14.097)
          )
          (stroke (width 0) (type default) (color 0 0 0 0))
          (fill (type none))
        )
        (polyline
          (pts
            (xy 8.763 -14.605)
            (xy 8.763 -13.462)
          )
          (stroke (width 0) (type default) (color 0 0 0 0))
          (fill (type none))
        )
        (polyline
          (pts
            (xy 8.763 0.381)
            (xy 8.763 -14.097)
          )
          (stroke (width 0) (type default) (color 0 0 0 0))
          (fill (type none))
        )
        (polyline
          (pts
            (xy 9.398 -28.575)
            (xy 4.953 -28.575)
          )
          (stroke (width 0) (type default) (color 0 0 0 0))
          (fill (type none))
        )
        (polyline
          (pts
            (xy 9.398 -14.605)
            (xy 9.398 -13.462)
          )
          (stroke (width 0) (type default) (color 0 0 0 0))
          (fill (type none))
        )
        (polyline
          (pts
            (xy 9.398 -14.097)
            (xy 9.398 -28.702)
          )
          (stroke (width 0) (type default) (color 0 0 0 0))
          (fill (type none))
        )
        (polyline
          (pts
            (xy 9.398 -14.097)
            (xy 9.398 0.508)
          )
          (stroke (width 0) (type default) (color 0 0 0 0))
          (fill (type none))
        )
        (polyline
          (pts
            (xy 9.398 0.381)
            (xy 4.953 0.381)
          )
          (stroke (width 0) (type default) (color 0 0 0 0))
          (fill (type none))
        )
        (polyline
          (pts
            (xy 9.525 -35.687)
            (xy 11.303 -35.687)
          )
          (stroke (width 0) (type default) (color 0 0 0 0))
          (fill (type background))
        )
        (polyline
          (pts
            (xy 9.525 -35.179)
            (xy 9.525 -35.56)
          )
          (stroke (width 0) (type default) (color 0 0 0 0))
          (fill (type none))
        )
        (polyline
          (pts
            (xy 9.525 -35.179)
            (xy 11.303 -35.179)
          )
          (stroke (width 0) (type default) (color 0 0 0 0))
          (fill (type none))
        )
        (polyline
          (pts
            (xy 9.525 6.985)
            (xy 9.525 7.366)
          )
          (stroke (width 0) (type default) (color 0 0 0 0))
          (fill (type none))
        )
        (polyline
          (pts
            (xy 9.525 6.985)
            (xy 11.303 6.985)
          )
          (stroke (width 0) (type default) (color 0 0 0 0))
          (fill (type none))
        )
        (polyline
          (pts
            (xy 9.525 7.493)
            (xy 11.303 7.493)
          )
          (stroke (width 0) (type default) (color 0 0 0 0))
          (fill (type background))
        )
        (polyline
          (pts
            (xy 9.779 -34.798)
            (xy 9.779 -35.179)
          )
          (stroke (width 0) (type default) (color 0 0 0 0))
          (fill (type none))
        )
        (polyline
          (pts
            (xy 9.779 -34.671)
            (xy 11.303 -34.671)
          )
          (stroke (width 0) (type default) (color 0 0 0 0))
          (fill (type none))
        )
        (polyline
          (pts
            (xy 9.779 -14.605)
            (xy 9.779 -13.462)
          )
          (stroke (width 0) (type default) (color 0 0 0 0))
          (fill (type none))
        )
        (polyline
          (pts
            (xy 9.779 6.477)
            (xy 11.303 6.477)
          )
          (stroke (width 0) (type default) (color 0 0 0 0))
          (fill (type none))
        )
        (polyline
          (pts
            (xy 9.779 6.604)
            (xy 9.779 6.985)
          )
          (stroke (width 0) (type default) (color 0 0 0 0))
          (fill (type none))
        )
        (polyline
          (pts
            (xy 10.287 -29.083)
            (xy 9.779 -29.591)
          )
          (stroke (width 0) (type default) (color 0 0 0 0))
          (fill (type none))
        )
        (polyline
          (pts
            (xy 10.287 -14.605)
            (xy 10.287 -13.462)
          )
          (stroke (width 0) (type default) (color 0 0 0 0))
          (fill (type none))
        )
        (polyline
          (pts
            (xy 10.287 0.889)
            (xy 9.779 1.397)
          )
          (stroke (width 0) (type default) (color 0 0 0 0))
          (fill (type none))
        )
        (polyline
          (pts
            (xy 11.303 -30.861)
            (xy 9.779 -30.861)
          )
          (stroke (width 0) (type default) (color 0 0 0 0))
          (fill (type none))
        )
        (polyline
          (pts
            (xy 11.303 -30.861)
            (xy 12.827 -30.861)
          )
          (stroke (width 0) (type default) (color 0 0 0 0))
          (fill (type none))
        )
        (polyline
          (pts
            (xy 11.303 2.667)
            (xy 9.779 2.667)
          )
          (stroke (width 0) (type default) (color 0 0 0 0))
          (fill (type none))
        )
        (polyline
          (pts
            (xy 11.303 2.667)
            (xy 12.827 2.667)
          )
          (stroke (width 0) (type default) (color 0 0 0 0))
          (fill (type none))
        )
        (polyline
          (pts
            (xy 12.319 -29.083)
            (xy 12.827 -29.591)
          )
          (stroke (width 0) (type default) (color 0 0 0 0))
          (fill (type none))
        )
        (polyline
          (pts
            (xy 12.319 -14.605)
            (xy 12.319 -13.462)
          )
          (stroke (width 0) (type default) (color 0 0 0 0))
          (fill (type none))
        )
        (polyline
          (pts
            (xy 12.319 0.889)
            (xy 12.827 1.397)
          )
          (stroke (width 0) (type default) (color 0 0 0 0))
          (fill (type none))
        )
        (polyline
          (pts
            (xy 12.827 -34.798)
            (xy 12.827 -35.179)
          )
          (stroke (width 0) (type default) (color 0 0 0 0))
          (fill (type none))
        )
        (polyline
          (pts
            (xy 12.827 -34.671)
            (xy 11.303 -34.671)
          )
          (stroke (width 0) (type default) (color 0 0 0 0))
          (fill (type none))
        )
        (polyline
          (pts
            (xy 12.827 -14.605)
            (xy 12.827 -13.462)
          )
          (stroke (width 0) (type default) (color 0 0 0 0))
          (fill (type none))
        )
        (polyline
          (pts
            (xy 12.827 6.477)
            (xy 11.303 6.477)
          )
          (stroke (width 0) (type default) (color 0 0 0 0))
          (fill (type none))
        )
        (polyline
          (pts
            (xy 12.827 6.604)
            (xy 12.827 6.985)
          )
          (stroke (width 0) (type default) (color 0 0 0 0))
          (fill (type none))
        )
        (polyline
          (pts
            (xy 13.081 -35.687)
            (xy 11.303 -35.687)
          )
          (stroke (width 0) (type default) (color 0 0 0 0))
          (fill (type background))
        )
        (polyline
          (pts
            (xy 13.081 -35.179)
            (xy 11.303 -35.179)
          )
          (stroke (width 0) (type default) (color 0 0 0 0))
          (fill (type none))
        )
        (polyline
          (pts
            (xy 13.081 -35.179)
            (xy 13.081 -35.56)
          )
          (stroke (width 0) (type default) (color 0 0 0 0))
          (fill (type none))
        )
        (polyline
          (pts
            (xy 13.081 6.985)
            (xy 11.303 6.985)
          )
          (stroke (width 0) (type default) (color 0 0 0 0))
          (fill (type none))
        )
        (polyline
          (pts
            (xy 13.081 6.985)
            (xy 13.081 7.366)
          )
          (stroke (width 0) (type default) (color 0 0 0 0))
          (fill (type none))
        )
        (polyline
          (pts
            (xy 13.081 7.493)
            (xy 11.303 7.493)
          )
          (stroke (width 0) (type default) (color 0 0 0 0))
          (fill (type background))
        )
        (polyline
          (pts
            (xy 13.208 -28.575)
            (xy 17.653 -28.575)
          )
          (stroke (width 0) (type default) (color 0 0 0 0))
          (fill (type none))
        )
        (polyline
          (pts
            (xy 13.208 -14.605)
            (xy 13.208 -13.462)
          )
          (stroke (width 0) (type default) (color 0 0 0 0))
          (fill (type none))
        )
        (polyline
          (pts
            (xy 13.208 -14.097)
            (xy 13.208 -28.702)
          )
          (stroke (width 0) (type default) (color 0 0 0 0))
          (fill (type none))
        )
        (polyline
          (pts
            (xy 13.208 -14.097)
            (xy 13.208 0.508)
          )
          (stroke (width 0) (type default) (color 0 0 0 0))
          (fill (type none))
        )
        (polyline
          (pts
            (xy 13.208 0.381)
            (xy 17.653 0.381)
          )
          (stroke (width 0) (type default) (color 0 0 0 0))
          (fill (type none))
        )
        (polyline
          (pts
            (xy 13.843 -28.575)
            (xy 13.843 -14.097)
          )
          (stroke (width 0) (type default) (color 0 0 0 0))
          (fill (type none))
        )
        (polyline
          (pts
            (xy 13.843 -14.605)
            (xy 13.843 -13.462)
          )
          (stroke (width 0) (type default) (color 0 0 0 0))
          (fill (type none))
        )
        (polyline
          (pts
            (xy 13.843 0.381)
            (xy 13.843 -14.097)
          )
          (stroke (width 0) (type default) (color 0 0 0 0))
          (fill (type none))
        )
        (polyline
          (pts
            (xy 14.097 -14.605)
            (xy 14.097 -13.462)
          )
          (stroke (width 0) (type default) (color 0 0 0 0))
          (fill (type none))
        )
        (polyline
          (pts
            (xy 14.097 -14.097)
            (xy 14.097 -28.575)
          )
          (stroke (width 0) (type default) (color 0 0 0 0))
          (fill (type none))
        )
        (polyline
          (pts
            (xy 14.097 -14.097)
            (xy 14.097 0.381)
          )
          (stroke (width 0) (type default) (color 0 0 0 0))
          (fill (type none))
        )
        (polyline
          (pts
            (xy 14.605 -14.605)
            (xy 14.605 -13.462)
          )
          (stroke (width 0) (type default) (color 0 0 0 0))
          (fill (type none))
        )
        (polyline
          (pts
            (xy 14.605 -14.097)
            (xy 14.605 -26.035)
          )
          (stroke (width 0) (type default) (color 0 0 0 0))
          (fill (type none))
        )
        (polyline
          (pts
            (xy 14.605 -14.097)
            (xy 14.605 -2.159)
          )
          (stroke (width 0) (type default) (color 0 0 0 0))
          (fill (type none))
        )
        (polyline
          (pts
            (xy 16.637 -25.527)
            (xy 16.637 -25.146)
          )
          (stroke (width 0) (type default) (color 0 0 0 0))
          (fill (type none))
        )
        (polyline
          (pts
            (xy 16.637 -20.701)
            (xy 16.637 -20.828)
          )
          (stroke (width 0) (type default) (color 0 0 0 0))
          (fill (type none))
        )
        (polyline
          (pts
            (xy 16.637 -20.447)
            (xy 16.637 -20.701)
          )
          (stroke (width 0) (type default) (color 0 0 0 0))
          (fill (type none))
        )
        (polyline
          (pts
            (xy 16.637 -7.747)
            (xy 16.637 -7.493)
          )
          (stroke (width 0) (type default) (color 0 0 0 0))
          (fill (type none))
        )
        (polyline
          (pts
            (xy 16.637 -7.493)
            (xy 16.637 -7.366)
          )
          (stroke (width 0) (type default) (color 0 0 0 0))
          (fill (type none))
        )
        (polyline
          (pts
            (xy 16.637 -2.667)
            (xy 16.637 -3.048)
          )
          (stroke (width 0) (type default) (color 0 0 0 0))
          (fill (type none))
        )
        (polyline
          (pts
            (xy 16.891 -28.575)
            (xy 16.891 -25.527)
          )
          (stroke (width 0) (type default) (color 0 0 0 0))
          (fill (type none))
        )
        (polyline
          (pts
            (xy 16.891 -20.447)
            (xy 16.891 -14.097)
          )
          (stroke (width 0) (type default) (color 0 0 0 0))
          (fill (type none))
        )
        (polyline
          (pts
            (xy 16.891 -14.605)
            (xy 16.891 -13.462)
          )
          (stroke (width 0) (type default) (color 0 0 0 0))
          (fill (type none))
        )
        (polyline
          (pts
            (xy 16.891 -7.747)
            (xy 16.891 -14.097)
          )
          (stroke (width 0) (type default) (color 0 0 0 0))
          (fill (type none))
        )
        (polyline
          (pts
            (xy 16.891 0.381)
            (xy 16.891 -2.667)
          )
          (stroke (width 0) (type default) (color 0 0 0 0))
          (fill (type none))
        )
        (polyline
          (pts
            (xy 17.145 -25.527)
            (xy 17.145 -25.019)
          )
          (stroke (width 0) (type default) (color 0 0 0 0))
          (fill (type none))
        )
        (polyline
          (pts
            (xy 17.145 -20.447)
            (xy 17.145 -20.955)
          )
          (stroke (width 0) (type default) (color 0 0 0 0))
          (fill (type none))
        )
        (polyline
          (pts
            (xy 17.145 -7.747)
            (xy 17.145 -7.239)
          )
          (stroke (width 0) (type default) (color 0 0 0 0))
          (fill (type none))
        )
        (polyline
          (pts
            (xy 17.145 -2.667)
            (xy 17.145 -3.175)
          )
          (stroke (width 0) (type default) (color 0 0 0 0))
          (fill (type none))
        )
        (polyline
          (pts
            (xy 17.653 -29.083)
            (xy 13.208 -29.083)
          )
          (stroke (width 0) (type default) (color 0 0 0 0))
          (fill (type none))
        )
        (polyline
          (pts
            (xy 17.653 -26.162)
            (xy 17.653 -14.097)
          )
          (stroke (width 0) (type default) (color 0 0 0 0))
          (fill (type none))
        )
        (polyline
          (pts
            (xy 17.653 -14.605)
            (xy 17.653 -13.462)
          )
          (stroke (width 0) (type default) (color 0 0 0 0))
          (fill (type none))
        )
        (polyline
          (pts
            (xy 17.653 -2.032)
            (xy 17.653 -14.097)
          )
          (stroke (width 0) (type default) (color 0 0 0 0))
          (fill (type none))
        )
        (polyline
          (pts
            (xy 17.653 0.889)
            (xy 13.208 0.889)
          )
          (stroke (width 0) (type default) (color 0 0 0 0))
          (fill (type none))
        )
        (polyline
          (pts
            (xy 18.161 -14.605)
            (xy 18.161 -13.462)
          )
          (stroke (width 0) (type default) (color 0 0 0 0))
          (fill (type none))
        )
        (polyline
          (pts
            (xy 18.669 -14.605)
            (xy 18.669 -13.462)
          )
          (stroke (width 0) (type default) (color 0 0 0 0))
          (fill (type none))
        )
        (polyline
          (pts
            (xy 4.953 -30.607)
            (xy 4.445 -30.607)
            (xy 4.445 -14.097)
          )
          (stroke (width 0) (type default) (color 0 0 0 0))
          (fill (type none))
        )
        (polyline
          (pts
            (xy 4.953 -25.781)
            (xy 4.953 -29.972)
            (xy 4.953 -30.607)
          )
          (stroke (width 0) (type default) (color 0 0 0 0))
          (fill (type none))
        )
        (polyline
          (pts
            (xy 4.953 -2.413)
            (xy 4.953 1.778)
            (xy 4.953 2.413)
          )
          (stroke (width 0) (type default) (color 0 0 0 0))
          (fill (type none))
        )
        (polyline
          (pts
            (xy 4.953 2.413)
            (xy 4.445 2.413)
            (xy 4.445 -14.097)
          )
          (stroke (width 0) (type default) (color 0 0 0 0))
          (fill (type none))
        )
        (polyline
          (pts
            (xy 5.461 -29.083)
            (xy 5.461 -30.099)
            (xy 4.953 -30.099)
          )
          (stroke (width 0) (type default) (color 0 0 0 0))
          (fill (type none))
        )
        (polyline
          (pts
            (xy 5.461 0.889)
            (xy 5.461 1.905)
            (xy 4.953 1.905)
          )
          (stroke (width 0) (type default) (color 0 0 0 0))
          (fill (type none))
        )
        (polyline
          (pts
            (xy 9.779 -14.097)
            (xy 9.779 -29.591)
            (xy 11.303 -29.591)
          )
          (stroke (width 0) (type default) (color 0 0 0 0))
          (fill (type none))
        )
        (polyline
          (pts
            (xy 9.779 -14.097)
            (xy 9.779 1.397)
            (xy 11.303 1.397)
          )
          (stroke (width 0) (type default) (color 0 0 0 0))
          (fill (type none))
        )
        (polyline
          (pts
            (xy 10.287 -14.097)
            (xy 10.287 -29.083)
            (xy 11.303 -29.083)
          )
          (stroke (width 0) (type default) (color 0 0 0 0))
          (fill (type none))
        )
        (polyline
          (pts
            (xy 10.287 -14.097)
            (xy 10.287 0.889)
            (xy 11.303 0.889)
          )
          (stroke (width 0) (type default) (color 0 0 0 0))
          (fill (type none))
        )
        (polyline
          (pts
            (xy 12.319 -14.097)
            (xy 12.319 -29.083)
            (xy 11.303 -29.083)
          )
          (stroke (width 0) (type default) (color 0 0 0 0))
          (fill (type none))
        )
        (polyline
          (pts
            (xy 12.319 -14.097)
            (xy 12.319 0.889)
            (xy 11.303 0.889)
          )
          (stroke (width 0) (type default) (color 0 0 0 0))
          (fill (type none))
        )
        (polyline
          (pts
            (xy 12.827 -14.097)
            (xy 12.827 -29.591)
            (xy 11.303 -29.591)
          )
          (stroke (width 0) (type default) (color 0 0 0 0))
          (fill (type none))
        )
        (polyline
          (pts
            (xy 12.827 -14.097)
            (xy 12.827 1.397)
            (xy 11.303 1.397)
          )
          (stroke (width 0) (type default) (color 0 0 0 0))
          (fill (type none))
        )
        (polyline
          (pts
            (xy 17.145 -29.083)
            (xy 17.145 -30.099)
            (xy 17.653 -30.099)
          )
          (stroke (width 0) (type default) (color 0 0 0 0))
          (fill (type none))
        )
        (polyline
          (pts
            (xy 17.145 0.889)
            (xy 17.145 1.905)
            (xy 17.653 1.905)
          )
          (stroke (width 0) (type default) (color 0 0 0 0))
          (fill (type none))
        )
        (polyline
          (pts
            (xy 17.653 -30.607)
            (xy 18.161 -30.607)
            (xy 18.161 -14.097)
          )
          (stroke (width 0) (type default) (color 0 0 0 0))
          (fill (type none))
        )
        (polyline
          (pts
            (xy 17.653 -25.781)
            (xy 17.653 -29.972)
            (xy 17.653 -30.607)
          )
          (stroke (width 0) (type default) (color 0 0 0 0))
          (fill (type none))
        )
        (polyline
          (pts
            (xy 17.653 -2.413)
            (xy 17.653 1.778)
            (xy 17.653 2.413)
          )
          (stroke (width 0) (type default) (color 0 0 0 0))
          (fill (type none))
        )
        (polyline
          (pts
            (xy 17.653 2.413)
            (xy 18.161 2.413)
            (xy 18.161 -14.097)
          )
          (stroke (width 0) (type default) (color 0 0 0 0))
          (fill (type none))
        )
        (polyline
          (pts
            (xy 4.953 -25.527)
            (xy 6.3754 -24.1046)
            (xy 6.6294 -23.5966)
            (xy 6.731 -22.987)
          )
          (stroke (width 0) (type default) (color 0 0 0 0))
          (fill (type none))
        )
        (polyline
          (pts
            (xy 4.953 -24.257)
            (xy 5.461 -23.6982)
            (xy 5.5626 -23.368)
            (xy 5.588 -23.0124)
          )
          (stroke (width 0) (type default) (color 0 0 0 0))
          (fill (type none))
        )
        (polyline
          (pts
            (xy 4.953 -21.717)
            (xy 5.461 -22.2758)
            (xy 5.5626 -22.606)
            (xy 5.588 -22.9616)
          )
          (stroke (width 0) (type default) (color 0 0 0 0))
          (fill (type none))
        )
        (polyline
          (pts
            (xy 4.953 -20.447)
            (xy 6.3754 -21.8694)
            (xy 6.6294 -22.3774)
            (xy 6.731 -22.987)
          )
          (stroke (width 0) (type default) (color 0 0 0 0))
          (fill (type none))
        )
        (polyline
          (pts
            (xy 4.953 -7.747)
            (xy 6.3754 -6.3246)
            (xy 6.6294 -5.8166)
            (xy 6.731 -5.207)
          )
          (stroke (width 0) (type default) (color 0 0 0 0))
          (fill (type none))
        )
        (polyline
          (pts
            (xy 4.953 -6.477)
            (xy 5.461 -5.9182)
            (xy 5.5626 -5.588)
            (xy 5.588 -5.2324)
          )
          (stroke (width 0) (type default) (color 0 0 0 0))
          (fill (type none))
        )
        (polyline
          (pts
            (xy 4.953 -3.937)
            (xy 5.461 -4.4958)
            (xy 5.5626 -4.826)
            (xy 5.588 -5.1816)
          )
          (stroke (width 0) (type default) (color 0 0 0 0))
          (fill (type none))
        )
        (polyline
          (pts
            (xy 4.953 -2.667)
            (xy 6.3754 -4.0894)
            (xy 6.6294 -4.5974)
            (xy 6.731 -5.207)
          )
          (stroke (width 0) (type default) (color 0 0 0 0))
          (fill (type none))
        )
        (polyline
          (pts
            (xy 9.398 -28.702)
            (xy 9.398 -29.083)
            (xy 9.525 -29.337)
            (xy 9.779 -29.591)
          )
          (stroke (width 0) (type default) (color 0 0 0 0))
          (fill (type none))
        )
        (polyline
          (pts
            (xy 9.398 0.508)
            (xy 9.398 0.889)
            (xy 9.525 1.143)
            (xy 9.779 1.397)
          )
          (stroke (width 0) (type default) (color 0 0 0 0))
          (fill (type none))
        )
        (polyline
          (pts
            (xy 11.303 -30.607)
            (xy 9.906 -30.607)
            (xy 9.779 -30.607)
            (xy 9.779 -29.591)
          )
          (stroke (width 0) (type default) (color 0 0 0 0))
          (fill (type none))
        )
        (polyline
          (pts
            (xy 11.303 -30.607)
            (xy 12.7 -30.607)
            (xy 12.827 -30.607)
            (xy 12.827 -29.591)
          )
          (stroke (width 0) (type default) (color 0 0 0 0))
          (fill (type none))
        )
        (polyline
          (pts
            (xy 11.303 2.413)
            (xy 9.906 2.413)
            (xy 9.779 2.413)
            (xy 9.779 1.397)
          )
          (stroke (width 0) (type default) (color 0 0 0 0))
          (fill (type none))
        )
        (polyline
          (pts
            (xy 11.303 2.413)
            (xy 12.7 2.413)
            (xy 12.827 2.413)
            (xy 12.827 1.397)
          )
          (stroke (width 0) (type default) (color 0 0 0 0))
          (fill (type none))
        )
        (polyline
          (pts
            (xy 13.208 -28.702)
            (xy 13.208 -29.083)
            (xy 13.081 -29.337)
            (xy 12.827 -29.591)
          )
          (stroke (width 0) (type default) (color 0 0 0 0))
          (fill (type none))
        )
        (polyline
          (pts
            (xy 13.208 0.508)
            (xy 13.208 0.889)
            (xy 13.081 1.143)
            (xy 12.827 1.397)
          )
          (stroke (width 0) (type default) (color 0 0 0 0))
          (fill (type none))
        )
        (polyline
          (pts
            (xy 17.653 -25.527)
            (xy 16.2306 -24.1046)
            (xy 15.9766 -23.5966)
            (xy 15.875 -22.987)
          )
          (stroke (width 0) (type default) (color 0 0 0 0))
          (fill (type none))
        )
        (polyline
          (pts
            (xy 17.653 -24.257)
            (xy 17.145 -23.6982)
            (xy 17.0434 -23.368)
            (xy 17.018 -23.0124)
          )
          (stroke (width 0) (type default) (color 0 0 0 0))
          (fill (type none))
        )
        (polyline
          (pts
            (xy 17.653 -21.717)
            (xy 17.145 -22.2758)
            (xy 17.0434 -22.606)
            (xy 17.018 -22.9616)
          )
          (stroke (width 0) (type default) (color 0 0 0 0))
          (fill (type none))
        )
        (polyline
          (pts
            (xy 17.653 -20.447)
            (xy 16.2306 -21.8694)
            (xy 15.9766 -22.3774)
            (xy 15.875 -22.987)
          )
          (stroke (width 0) (type default) (color 0 0 0 0))
          (fill (type none))
        )
        (polyline
          (pts
            (xy 17.653 -7.747)
            (xy 16.2306 -6.3246)
            (xy 15.9766 -5.8166)
            (xy 15.875 -5.207)
          )
          (stroke (width 0) (type default) (color 0 0 0 0))
          (fill (type none))
        )
        (polyline
          (pts
            (xy 17.653 -6.477)
            (xy 17.145 -5.9182)
            (xy 17.0434 -5.588)
            (xy 17.018 -5.2324)
          )
          (stroke (width 0) (type default) (color 0 0 0 0))
          (fill (type none))
        )
        (polyline
          (pts
            (xy 17.653 -3.937)
            (xy 17.145 -4.4958)
            (xy 17.0434 -4.826)
            (xy 17.018 -5.1816)
          )
          (stroke (width 0) (type default) (color 0 0 0 0))
          (fill (type none))
        )
        (polyline
          (pts
            (xy 17.653 -2.667)
            (xy 16.2306 -4.0894)
            (xy 15.9766 -4.5974)
            (xy 15.875 -5.207)
          )
          (stroke (width 0) (type default) (color 0 0 0 0))
          (fill (type none))
        )
        (polyline
          (pts
            (xy 5.461 -25.527)
            (xy 6.5278 -24.5618)
            (xy 6.858 -24.2062)
            (xy 7.0866 -23.7236)
            (xy 7.239 -22.987)
          )
          (stroke (width 0) (type default) (color 0 0 0 0))
          (fill (type none))
        )
        (polyline
          (pts
            (xy 5.461 -20.447)
            (xy 6.5278 -21.4122)
            (xy 6.858 -21.7678)
            (xy 7.0866 -22.2504)
            (xy 7.239 -22.987)
          )
          (stroke (width 0) (type default) (color 0 0 0 0))
          (fill (type none))
        )
        (polyline
          (pts
            (xy 5.461 -7.747)
            (xy 6.5278 -6.7818)
            (xy 6.858 -6.4262)
            (xy 7.0866 -5.9436)
            (xy 7.239 -5.207)
          )
          (stroke (width 0) (type default) (color 0 0 0 0))
          (fill (type none))
        )
        (polyline
          (pts
            (xy 5.461 -2.667)
            (xy 6.5278 -3.6322)
            (xy 6.858 -3.9878)
            (xy 7.0866 -4.4704)
            (xy 7.239 -5.207)
          )
          (stroke (width 0) (type default) (color 0 0 0 0))
          (fill (type none))
        )
        (polyline
          (pts
            (xy 17.145 -25.527)
            (xy 16.0782 -24.5618)
            (xy 15.748 -24.2062)
            (xy 15.5194 -23.7236)
            (xy 15.367 -22.987)
          )
          (stroke (width 0) (type default) (color 0 0 0 0))
          (fill (type none))
        )
        (polyline
          (pts
            (xy 17.145 -20.447)
            (xy 16.0782 -21.4122)
            (xy 15.748 -21.7678)
            (xy 15.5194 -22.2504)
            (xy 15.367 -22.987)
          )
          (stroke (width 0) (type default) (color 0 0 0 0))
          (fill (type none))
        )
        (polyline
          (pts
            (xy 17.145 -7.747)
            (xy 16.0782 -6.7818)
            (xy 15.748 -6.4262)
            (xy 15.5194 -5.9436)
            (xy 15.367 -5.207)
          )
          (stroke (width 0) (type default) (color 0 0 0 0))
          (fill (type none))
        )
        (polyline
          (pts
            (xy 17.145 -2.667)
            (xy 16.0782 -3.6322)
            (xy 15.748 -3.9878)
            (xy 15.5194 -4.4704)
            (xy 15.367 -5.207)
          )
          (stroke (width 0) (type default) (color 0 0 0 0))
          (fill (type none))
        )
        (polyline
          (pts
            (xy 4.953 -25.527)
            (xy 5.969 -25.527)
            (xy 7.239 -24.257)
            (xy 7.239 -21.717)
            (xy 5.969 -20.447)
            (xy 4.953 -20.447)
          )
          (stroke (width 0) (type default) (color 0 0 0 0))
          (fill (type none))
        )
        (polyline
          (pts
            (xy 4.953 -2.667)
            (xy 5.969 -2.667)
            (xy 7.239 -3.937)
            (xy 7.239 -6.477)
            (xy 5.969 -7.747)
            (xy 4.953 -7.747)
          )
          (stroke (width 0) (type default) (color 0 0 0 0))
          (fill (type none))
        )
        (polyline
          (pts
            (xy 8.509 -29.083)
            (xy 8.5598 -29.4894)
            (xy 8.6614 -29.8958)
            (xy 8.9154 -30.3022)
            (xy 9.3218 -30.6578)
            (xy 9.779 -30.861)
          )
          (stroke (width 0) (type default) (color 0 0 0 0))
          (fill (type none))
        )
        (polyline
          (pts
            (xy 8.509 -27.559)
            (xy 8.001 -27.559)
            (xy 7.747 -27.305)
            (xy 7.747 -26.289)
            (xy 8.001 -26.035)
            (xy 8.509 -26.035)
          )
          (stroke (width 0) (type default) (color 0 0 0 0))
          (fill (type none))
        )
        (polyline
          (pts
            (xy 8.509 -0.635)
            (xy 8.001 -0.635)
            (xy 7.747 -0.889)
            (xy 7.747 -1.905)
            (xy 8.001 -2.159)
            (xy 8.509 -2.159)
          )
          (stroke (width 0) (type default) (color 0 0 0 0))
          (fill (type none))
        )
        (polyline
          (pts
            (xy 8.509 0.889)
            (xy 8.5598 1.2954)
            (xy 8.6614 1.7018)
            (xy 8.9154 2.1082)
            (xy 9.3218 2.4638)
            (xy 9.779 2.667)
          )
          (stroke (width 0) (type default) (color 0 0 0 0))
          (fill (type none))
        )
        (polyline
          (pts
            (xy 14.097 -29.083)
            (xy 14.0462 -29.4894)
            (xy 13.9446 -29.8958)
            (xy 13.6906 -30.3022)
            (xy 13.2842 -30.6578)
            (xy 12.827 -30.861)
          )
          (stroke (width 0) (type default) (color 0 0 0 0))
          (fill (type none))
        )
        (polyline
          (pts
            (xy 14.097 -27.559)
            (xy 14.605 -27.559)
            (xy 14.859 -27.305)
            (xy 14.859 -26.289)
            (xy 14.605 -26.035)
            (xy 14.097 -26.035)
          )
          (stroke (width 0) (type default) (color 0 0 0 0))
          (fill (type none))
        )
        (polyline
          (pts
            (xy 14.097 -0.635)
            (xy 14.605 -0.635)
            (xy 14.859 -0.889)
            (xy 14.859 -1.905)
            (xy 14.605 -2.159)
            (xy 14.097 -2.159)
          )
          (stroke (width 0) (type default) (color 0 0 0 0))
          (fill (type none))
        )
        (polyline
          (pts
            (xy 14.097 0.889)
            (xy 14.0462 1.2954)
            (xy 13.9446 1.7018)
            (xy 13.6906 2.1082)
            (xy 13.2842 2.4638)
            (xy 12.827 2.667)
          )
          (stroke (width 0) (type default) (color 0 0 0 0))
          (fill (type none))
        )
        (polyline
          (pts
            (xy 17.653 -25.527)
            (xy 16.637 -25.527)
            (xy 15.367 -24.257)
            (xy 15.367 -21.717)
            (xy 16.637 -20.447)
            (xy 17.653 -20.447)
          )
          (stroke (width 0) (type default) (color 0 0 0 0))
          (fill (type none))
        )
        (polyline
          (pts
            (xy 17.653 -2.667)
            (xy 16.637 -2.667)
            (xy 15.367 -3.937)
            (xy 15.367 -6.477)
            (xy 16.637 -7.747)
            (xy 17.653 -7.747)
          )
          (stroke (width 0) (type default) (color 0 0 0 0))
          (fill (type none))
        )
        (polyline
          (pts
            (xy 18.669 -14.097)
            (xy 18.796 -31.115)
            (xy 18.796 -31.115)
            (xy 18.669 -31.623)
            (xy 18.5674 -32.131)
            (xy 18.3642 -32.8422)
            (xy 18.0086 -33.6042)
            (xy 17.6022 -34.2138)
            (xy 17.1958 -34.671)
            (xy 16.6878 -35.1282)
            (xy 15.9766 -35.5854)
            (xy 15.2654 -35.8902)
            (xy 14.5542 -36.0934)
            (xy 13.843 -36.195)
            (xy 9.017 -36.195)
            (xy 7.8994 -36.0934)
            (xy 7.0358 -35.7886)
            (xy 5.969 -35.179)
            (xy 4.953 -34.1122)
            (xy 4.3942 -33.0962)
            (xy 4.0386 -32.0802)
            (xy 3.937 -31.75)
            (xy 3.81 -31.115)
            (xy 3.81 -14.097)
          )
          (stroke (width 0.254) (type default) (color 0 0 0 0))
          (fill (type background))
        )
        (polyline
          (pts
            (xy 18.669 -14.097)
            (xy 18.796 2.921)
            (xy 18.796 3.175)
            (xy 18.669 3.683)
            (xy 18.5674 3.937)
            (xy 18.3642 4.6482)
            (xy 18.0086 5.4102)
            (xy 17.6022 6.0198)
            (xy 17.1958 6.477)
            (xy 16.6878 6.9342)
            (xy 15.9766 7.3914)
            (xy 15.2654 7.6962)
            (xy 14.5542 7.8994)
            (xy 13.843 8.001)
            (xy 9.017 8.001)
            (xy 7.8994 7.8994)
            (xy 7.0358 7.5946)
            (xy 5.969 6.985)
            (xy 4.953 5.9182)
            (xy 4.3942 4.9022)
            (xy 4.0386 3.8862)
            (xy 3.937 3.429)
            (xy 3.81 2.794)
            (xy 3.81 -14.097)
          )
          (stroke (width 0.254) (type default) (color 0 0 0 0))
          (fill (type background))
        )
        (arc (start 4.445 -30.607) (mid 5.8538 -34.2782) (end 9.525 -35.687)
          (stroke (width 0) (type default) (color 0 0 0 0))
          (fill (type none))
        )
        (arc (start 4.953 -30.607) (mid 6.3281 -33.8039) (end 9.525 -35.179)
          (stroke (width 0) (type default) (color 0 0 0 0))
          (fill (type none))
        )
        (arc (start 5.461 -30.099) (mid 6.604 -33.3447) (end 9.779 -34.671)
          (stroke (width 0) (type default) (color 0 0 0 0))
          (fill (type none))
        )
        (rectangle (start 9.525 -28.702) (end 9.779 -27.432)
          (stroke (width 0) (type default) (color 0 0 0 0))
          (fill (type outline))
        )
        (rectangle (start 9.525 -26.162) (end 9.779 -24.892)
          (stroke (width 0) (type default) (color 0 0 0 0))
          (fill (type outline))
        )
        (rectangle (start 9.525 -23.622) (end 9.779 -22.352)
          (stroke (width 0) (type default) (color 0 0 0 0))
          (fill (type outline))
        )
        (rectangle (start 9.525 -21.082) (end 9.779 -19.812)
          (stroke (width 0) (type default) (color 0 0 0 0))
          (fill (type outline))
        )
        (rectangle (start 9.525 -18.542) (end 9.779 -17.272)
          (stroke (width 0) (type default) (color 0 0 0 0))
          (fill (type outline))
        )
        (rectangle (start 9.525 -16.002) (end 9.779 -14.732)
          (stroke (width 0) (type default) (color 0 0 0 0))
          (fill (type outline))
        )
        (rectangle (start 9.525 -12.192) (end 9.779 -13.462)
          (stroke (width 0) (type default) (color 0 0 0 0))
          (fill (type outline))
        )
        (rectangle (start 9.525 -9.652) (end 9.779 -10.922)
          (stroke (width 0) (type default) (color 0 0 0 0))
          (fill (type outline))
        )
        (rectangle (start 9.525 -7.112) (end 9.779 -8.382)
          (stroke (width 0) (type default) (color 0 0 0 0))
          (fill (type outline))
        )
        (rectangle (start 9.525 -4.572) (end 9.779 -5.842)
          (stroke (width 0) (type default) (color 0 0 0 0))
          (fill (type outline))
        )
        (rectangle (start 9.525 -2.032) (end 9.779 -3.302)
          (stroke (width 0) (type default) (color 0 0 0 0))
          (fill (type outline))
        )
        (rectangle (start 9.525 0.508) (end 9.779 -0.762)
          (stroke (width 0) (type default) (color 0 0 0 0))
          (fill (type outline))
        )
        (arc (start 9.525 6.985) (mid 6.3281 5.6099) (end 4.953 2.413)
          (stroke (width 0) (type default) (color 0 0 0 0))
          (fill (type none))
        )
        (arc (start 9.525 7.493) (mid 5.8538 6.0842) (end 4.445 2.413)
          (stroke (width 0) (type default) (color 0 0 0 0))
          (fill (type none))
        )
        (arc (start 9.779 6.477) (mid 6.6129 5.1421) (end 5.461 1.905)
          (stroke (width 0) (type default) (color 0 0 0 0))
          (fill (type none))
        )
        (arc (start 12.827 -34.671) (mid 15.9931 -33.3361) (end 17.145 -30.099)
          (stroke (width 0) (type default) (color 0 0 0 0))
          (fill (type none))
        )
        (arc (start 13.081 -35.687) (mid 16.7522 -34.2782) (end 18.161 -30.607)
          (stroke (width 0) (type default) (color 0 0 0 0))
          (fill (type none))
        )
        (arc (start 13.081 -35.179) (mid 16.2779 -33.8039) (end 17.653 -30.607)
          (stroke (width 0) (type default) (color 0 0 0 0))
          (fill (type none))
        )
        (rectangle (start 13.081 -28.702) (end 12.827 -27.432)
          (stroke (width 0) (type default) (color 0 0 0 0))
          (fill (type outline))
        )
        (rectangle (start 13.081 -26.162) (end 12.827 -24.892)
          (stroke (width 0) (type default) (color 0 0 0 0))
          (fill (type outline))
        )
        (rectangle (start 13.081 -23.622) (end 12.827 -22.352)
          (stroke (width 0) (type default) (color 0 0 0 0))
          (fill (type outline))
        )
        (rectangle (start 13.081 -21.082) (end 12.827 -19.812)
          (stroke (width 0) (type default) (color 0 0 0 0))
          (fill (type outline))
        )
        (rectangle (start 13.081 -18.542) (end 12.827 -17.272)
          (stroke (width 0) (type default) (color 0 0 0 0))
          (fill (type outline))
        )
        (rectangle (start 13.081 -16.002) (end 12.827 -14.732)
          (stroke (width 0) (type default) (color 0 0 0 0))
          (fill (type outline))
        )
        (rectangle (start 13.081 -12.192) (end 12.827 -13.462)
          (stroke (width 0) (type default) (color 0 0 0 0))
          (fill (type outline))
        )
        (rectangle (start 13.081 -9.652) (end 12.827 -10.922)
          (stroke (width 0) (type default) (color 0 0 0 0))
          (fill (type outline))
        )
        (rectangle (start 13.081 -7.112) (end 12.827 -8.382)
          (stroke (width 0) (type default) (color 0 0 0 0))
          (fill (type outline))
        )
        (rectangle (start 13.081 -4.572) (end 12.827 -5.842)
          (stroke (width 0) (type default) (color 0 0 0 0))
          (fill (type outline))
        )
        (rectangle (start 13.081 -2.032) (end 12.827 -3.302)
          (stroke (width 0) (type default) (color 0 0 0 0))
          (fill (type outline))
        )
        (rectangle (start 13.081 0.508) (end 12.827 -0.762)
          (stroke (width 0) (type default) (color 0 0 0 0))
          (fill (type outline))
        )
        (arc (start 17.145 1.905) (mid 16.002 5.1507) (end 12.827 6.477)
          (stroke (width 0) (type default) (color 0 0 0 0))
          (fill (type none))
        )
        (arc (start 17.653 2.413) (mid 16.2779 5.6099) (end 13.081 6.985)
          (stroke (width 0) (type default) (color 0 0 0 0))
          (fill (type none))
        )
        (arc (start 18.161 2.413) (mid 16.7522 6.0842) (end 13.081 7.493)
          (stroke (width 0) (type default) (color 0 0 0 0))
          (fill (type none))
        )
        (pin passive line (at 22.86 0 180) (length 3.81)
          (name "~" (effects (font (size 1.27 1.27))))
          (number "A1" (effects (font (size 1.27 1.27))))
        )
        (pin passive line (at 22.86 -22.86 180) (length 3.81)
          (name "~" (effects (font (size 1.27 1.27))))
          (number "A10" (effects (font (size 1.27 1.27))))
        )
        (pin passive line (at 22.86 -25.4 180) (length 3.81)
          (name "~" (effects (font (size 1.27 1.27))))
          (number "A11" (effects (font (size 1.27 1.27))))
        )
        (pin passive line (at 22.86 -27.94 180) (length 3.81)
          (name "~" (effects (font (size 1.27 1.27))))
          (number "A12" (effects (font (size 1.27 1.27))))
        )
        (pin passive line (at 22.86 -2.54 180) (length 3.81)
          (name "~" (effects (font (size 1.27 1.27))))
          (number "A2" (effects (font (size 1.27 1.27))))
        )
        (pin passive line (at 22.86 -5.08 180) (length 3.81)
          (name "~" (effects (font (size 1.27 1.27))))
          (number "A3" (effects (font (size 1.27 1.27))))
        )
        (pin passive line (at 22.86 -7.62 180) (length 3.81)
          (name "~" (effects (font (size 1.27 1.27))))
          (number "A4" (effects (font (size 1.27 1.27))))
        )
        (pin passive line (at 22.86 -10.16 180) (length 3.81)
          (name "~" (effects (font (size 1.27 1.27))))
          (number "A5" (effects (font (size 1.27 1.27))))
        )
        (pin passive line (at 22.86 -12.7 180) (length 3.81)
          (name "~" (effects (font (size 1.27 1.27))))
          (number "A6" (effects (font (size 1.27 1.27))))
        )
        (pin passive line (at 22.86 -15.24 180) (length 3.81)
          (name "~" (effects (font (size 1.27 1.27))))
          (number "A7" (effects (font (size 1.27 1.27))))
        )
        (pin passive line (at 22.86 -17.78 180) (length 3.81)
          (name "~" (effects (font (size 1.27 1.27))))
          (number "A8" (effects (font (size 1.27 1.27))))
        )
        (pin passive line (at 22.86 -20.32 180) (length 3.81)
          (name "~" (effects (font (size 1.27 1.27))))
          (number "A9" (effects (font (size 1.27 1.27))))
        )
        (pin passive line (at 0 -27.94 0) (length 3.81)
          (name "~" (effects (font (size 1.27 1.27))))
          (number "B1" (effects (font (size 1.27 1.27))))
        )
        (pin passive line (at 0 -5.08 0) (length 3.81)
          (name "~" (effects (font (size 1.27 1.27))))
          (number "B10" (effects (font (size 1.27 1.27))))
        )
        (pin passive line (at 0 -2.54 0) (length 3.81)
          (name "~" (effects (font (size 1.27 1.27))))
          (number "B11" (effects (font (size 1.27 1.27))))
        )
        (pin passive line (at 0 0 0) (length 3.81)
          (name "~" (effects (font (size 1.27 1.27))))
          (number "B12" (effects (font (size 1.27 1.27))))
        )
        (pin passive line (at 0 -25.4 0) (length 3.81)
          (name "~" (effects (font (size 1.27 1.27))))
          (number "B2" (effects (font (size 1.27 1.27))))
        )
        (pin passive line (at 0 -22.86 0) (length 3.81)
          (name "~" (effects (font (size 1.27 1.27))))
          (number "B3" (effects (font (size 1.27 1.27))))
        )
        (pin passive line (at 0 -20.32 0) (length 3.81)
          (name "~" (effects (font (size 1.27 1.27))))
          (number "B4" (effects (font (size 1.27 1.27))))
        )
        (pin passive line (at 0 -17.78 0) (length 3.81)
          (name "~" (effects (font (size 1.27 1.27))))
          (number "B5" (effects (font (size 1.27 1.27))))
        )
        (pin passive line (at 0 -15.24 0) (length 3.81)
          (name "~" (effects (font (size 1.27 1.27))))
          (number "B6" (effects (font (size 1.27 1.27))))
        )
        (pin passive line (at 0 -12.7 0) (length 3.81)
          (name "~" (effects (font (size 1.27 1.27))))
          (number "B7" (effects (font (size 1.27 1.27))))
        )
        (pin passive line (at 0 -10.16 0) (length 3.81)
          (name "~" (effects (font (size 1.27 1.27))))
          (number "B8" (effects (font (size 1.27 1.27))))
        )
        (pin passive line (at 0 -7.62 0) (length 3.81)
          (name "~" (effects (font (size 1.27 1.27))))
          (number "B9" (effects (font (size 1.27 1.27))))
        )
        (pin input line (at 6.35 -39.37 90) (length 3.81)
          (name "~" (effects (font (size 1.27 1.27))))
          (number "SH" (effects (font (size 1.27 1.27))))
        )
      )
    )
	(symbol "C_47u_ELEC_100V_1" (pin_numbers hide) (pin_names hide) (in_bom yes) (on_board yes)
      (property "Reference" "C" (id 0) (at 13.97 0 0)
        (effects (font (size 1.27 1.27) (thickness 0.15)) (justify left bottom))
      )
      (property "Value" "C_47u_ELEC_100V_1" (id 1) (at 13.97 -5.08 0)
        (effects (font (size 1.27 1.27) (thickness 0.15)) (justify left bottom) hide)
      )
      (property "Footprint" "antmicro-footprints:C_Elec_10x10.5mm" (id 2) (at 13.97 -7.62 0)
        (effects (font (size 1.27 1.27) (thickness 0.15)) (justify left bottom) hide)
      )
      (property "Datasheet" "https://industrial.panasonic.com/cdbs/www-data/pdf/RDE0000/ABA0000C1151.pdf" (id 3) (at 13.97 -10.16 0)
        (effects (font (size 1.27 1.27) (thickness 0.15)) (justify left bottom) hide)
      )
      (property "MPN" "EEEHA2A470UP" (id 4) (at 13.97 -12.7 0)
        (effects (font (size 1.27 1.27) (thickness 0.15)) (justify left bottom) hide)
      )
      (property "Manufacturer" "Panasonic" (id 5) (at 13.97 -15.24 0)
        (effects (font (size 1.27 1.27) (thickness 0.15)) (justify left bottom) hide)
      )
      (property "License" "Apache-2.0" (id 6) (at 13.97 -17.78 0)
        (effects (font (size 1.27 1.27) (thickness 0.15)) (justify left bottom) hide)
      )
      (property "Author" "Antmicro" (id 7) (at 13.97 -20.32 0)
        (effects (font (size 1.27 1.27) (thickness 0.15)) (justify left bottom) hide)
      )
      (property "Val" "47u/100V" (id 8) (at 13.97 -2.54 0)
        (effects (font (size 1.27 1.27) (thickness 0.15)) (justify left bottom))
      )
      (property "Voltage" "" (id 9) (at 13.97 -22.86 0)
        (effects (font (size 1.27 1.27)) (justify left bottom) hide)
      )
      (property "Dielectric" "" (id 10) (at 13.97 -25.4 0)
        (effects (font (size 1.27 1.27)) (justify left bottom) hide)
      )
      (property "ki_description" " " (id 11) (at 0 0 0)
        (effects (font (size 1.27 1.27)) hide)
      )
      (symbol "C_47u_ELEC_100V_1_0_1"
        (rectangle (start -1.524 -2.921) (end 1.524 -3.302)
          (stroke (width 0) (type default) (color 0 0 0 0))
          (fill (type outline))
        )
        (rectangle (start -1.524 -1.905) (end 1.524 -2.286)
          (stroke (width 0) (type default) (color 0 0 0 0))
          (fill (type none))
        )
        (polyline
          (pts
            (xy -1.27 -0.9652)
            (xy -0.762 -0.9652)
          )
          (stroke (width 0) (type default) (color 0 0 0 0))
          (fill (type none))
        )
        (polyline
          (pts
            (xy -1.016 -1.2192)
            (xy -1.016 -0.7112)
          )
          (stroke (width 0) (type default) (color 0 0 0 0))
          (fill (type none))
        )
      )
      (symbol "C_47u_ELEC_100V_1_1_1"
        (pin passive line (at 0 0 270) (length 1.8542)
          (name "~" (effects (font (size 1.27 1.27))))
          (number "1" (effects (font (size 1.27 1.27))))
        )
        (pin passive line (at 0 -5.08 90) (length 1.8542)
          (name "~" (effects (font (size 1.27 1.27))))
          (number "2" (effects (font (size 1.27 1.27))))
        )
      )
    )
	(symbol "L_2u2_6.1A_XEL4030_1" (pin_numbers hide) (pin_names hide) (in_bom yes) (on_board yes)
      (property "Reference" "L" (id 0) (at 13.97 0 0)
        (effects (font (size 1.27 1.27) (thickness 0.15)) (justify left bottom))
      )
      (property "Value" "L_2u2_6.1A_XEL4030_1" (id 1) (at 13.97 -2.54 0)
        (effects (font (size 1.27 1.27) (thickness 0.15)) (justify left bottom) hide)
      )
      (property "Footprint" "antmicro-footprints:L_Coilcraft_XEL4030" (id 2) (at 13.97 -7.62 0)
        (effects (font (size 1.27 1.27) (thickness 0.15)) (justify left bottom) hide)
      )
      (property "Datasheet" "https://www.coilcraft.com/getmedia/8245f050-f190-4295-8c41-7c03d662ee3d/xel4030.pdf" (id 3) (at 13.97 -10.16 0)
        (effects (font (size 1.27 1.27) (thickness 0.15)) (justify left bottom) hide)
      )
      (property "Val" "2u2/6.1A" (id 4) (at 13.97 -5.08 0)
        (effects (font (size 1.27 1.27) (thickness 0.15)) (justify left bottom))
      )
      (property "Manufacturer" "Coilcraft" (id 5) (at 13.97 -12.7 0)
        (effects (font (size 1.27 1.27) (thickness 0.15)) (justify left bottom) hide)
      )
      (property "MPN" "XEL4030-222MEC" (id 6) (at 13.97 -15.24 0)
        (effects (font (size 1.27 1.27) (thickness 0.15)) (justify left bottom) hide)
      )
      (property "ISat" "" (id 7) (at 13.97 -16.51 0)
        (effects (font (size 1.27 1.27)) (justify left) hide)
      )
      (property "IMax" "" (id 8) (at 13.97 -20.32 0)
        (effects (font (size 1.27 1.27) (thickness 0.15)) (justify left bottom) hide)
      )
      (property "Size" "4x4" (id 9) (at 13.97 -22.86 0)
        (effects (font (size 1.27 1.27) (thickness 0.15)) (justify left bottom) hide)
      )
      (property "Author" "Antmicro" (id 10) (at 13.97 -25.4 0)
        (effects (font (size 1.27 1.27) (thickness 0.15)) (justify left bottom) hide)
      )
      (property "License" "Apache-2.0" (id 11) (at 13.97 -27.94 0)
        (effects (font (size 1.27 1.27) (thickness 0.15)) (justify left bottom) hide)
      )
      (symbol "L_2u2_6.1A_XEL4030_1_0_1"
        (arc (start 1.524 0) (mid 1.016 0.508) (end 0.508 0)
          (stroke (width 0) (type default) (color 0 0 0 0))
          (fill (type none))
        )
        (arc (start 2.54 0) (mid 2.032 0.508) (end 1.524 0)
          (stroke (width 0) (type default) (color 0 0 0 0))
          (fill (type none))
        )
        (arc (start 3.556 0) (mid 3.048 0.508) (end 2.54 0)
          (stroke (width 0) (type default) (color 0 0 0 0))
          (fill (type none))
        )
        (arc (start 4.572 0) (mid 4.064 0.508) (end 3.556 0)
          (stroke (width 0) (type default) (color 0 0 0 0))
          (fill (type none))
        )
      )
      (symbol "L_2u2_6.1A_XEL4030_1_1_1"
        (pin passive line (at 0 0 0) (length 0.508)
          (name "~" (effects (font (size 1.27 1.27))))
          (number "1" (effects (font (size 1.27 1.27))))
        )
        (pin passive line (at 5.08 0 180) (length 0.508)
          (name "~" (effects (font (size 1.27 1.27))))
          (number "2" (effects (font (size 1.27 1.27))))
        )
      )
    )
	(symbol "L_2u2_6.1A_XEL4030_2" (pin_numbers hide) (pin_names hide) (in_bom yes) (on_board yes)
      (property "Reference" "L" (id 0) (at 13.97 0 0)
        (effects (font (size 1.27 1.27) (thickness 0.15)) (justify left bottom))
      )
      (property "Value" "L_2u2_6.1A_XEL4030_2" (id 1) (at 13.97 -2.54 0)
        (effects (font (size 1.27 1.27) (thickness 0.15)) (justify left bottom) hide)
      )
      (property "Footprint" "antmicro-footprints:L_Coilcraft_XEL4030" (id 2) (at 13.97 -7.62 0)
        (effects (font (size 1.27 1.27) (thickness 0.15)) (justify left bottom) hide)
      )
      (property "Datasheet" "https://www.coilcraft.com/getmedia/8245f050-f190-4295-8c41-7c03d662ee3d/xel4030.pdf" (id 3) (at 13.97 -10.16 0)
        (effects (font (size 1.27 1.27) (thickness 0.15)) (justify left bottom) hide)
      )
      (property "Val" "2u2/6.1A" (id 4) (at 13.97 -5.08 0)
        (effects (font (size 1.27 1.27) (thickness 0.15)) (justify left bottom))
      )
      (property "Manufacturer" "Coilcraft" (id 5) (at 13.97 -12.7 0)
        (effects (font (size 1.27 1.27) (thickness 0.15)) (justify left bottom) hide)
      )
      (property "MPN" "XEL4030-222MEC" (id 6) (at 13.97 -15.24 0)
        (effects (font (size 1.27 1.27) (thickness 0.15)) (justify left bottom) hide)
      )
      (property "ISat" "" (id 7) (at 13.97 -16.51 0)
        (effects (font (size 1.27 1.27)) (justify left) hide)
      )
      (property "IMax" "" (id 8) (at 13.97 -20.32 0)
        (effects (font (size 1.27 1.27) (thickness 0.15)) (justify left bottom) hide)
      )
      (property "Size" "4x4" (id 9) (at 13.97 -22.86 0)
        (effects (font (size 1.27 1.27) (thickness 0.15)) (justify left bottom) hide)
      )
      (property "Author" "Antmicro" (id 10) (at 13.97 -25.4 0)
        (effects (font (size 1.27 1.27) (thickness 0.15)) (justify left bottom) hide)
      )
      (property "License" "Apache-2.0" (id 11) (at 13.97 -27.94 0)
        (effects (font (size 1.27 1.27) (thickness 0.15)) (justify left bottom) hide)
      )
      (symbol "L_2u2_6.1A_XEL4030_2_0_1"
        (arc (start 1.524 0) (mid 1.016 0.508) (end 0.508 0)
          (stroke (width 0) (type default) (color 0 0 0 0))
          (fill (type none))
        )
        (arc (start 2.54 0) (mid 2.032 0.508) (end 1.524 0)
          (stroke (width 0) (type default) (color 0 0 0 0))
          (fill (type none))
        )
        (arc (start 3.556 0) (mid 3.048 0.508) (end 2.54 0)
          (stroke (width 0) (type default) (color 0 0 0 0))
          (fill (type none))
        )
        (arc (start 4.572 0) (mid 4.064 0.508) (end 3.556 0)
          (stroke (width 0) (type default) (color 0 0 0 0))
          (fill (type none))
        )
      )
      (symbol "L_2u2_6.1A_XEL4030_2_1_1"
        (pin passive line (at 0 0 0) (length 0.508)
          (name "~" (effects (font (size 1.27 1.27))))
          (number "1" (effects (font (size 1.27 1.27))))
        )
        (pin passive line (at 5.08 0 180) (length 0.508)
          (name "~" (effects (font (size 1.27 1.27))))
          (number "2" (effects (font (size 1.27 1.27))))
        )
      )
    )
	(symbol "L_2u2_6.1A_XEL4030_3" (pin_numbers hide) (pin_names hide) (in_bom yes) (on_board yes)
      (property "Reference" "L" (id 0) (at 13.97 0 0)
        (effects (font (size 1.27 1.27) (thickness 0.15)) (justify left bottom))
      )
      (property "Value" "L_2u2_6.1A_XEL4030_3" (id 1) (at 13.97 -2.54 0)
        (effects (font (size 1.27 1.27) (thickness 0.15)) (justify left bottom) hide)
      )
      (property "Footprint" "antmicro-footprints:L_Coilcraft_XEL4030" (id 2) (at 13.97 -7.62 0)
        (effects (font (size 1.27 1.27) (thickness 0.15)) (justify left bottom) hide)
      )
      (property "Datasheet" "https://www.coilcraft.com/getmedia/8245f050-f190-4295-8c41-7c03d662ee3d/xel4030.pdf" (id 3) (at 13.97 -10.16 0)
        (effects (font (size 1.27 1.27) (thickness 0.15)) (justify left bottom) hide)
      )
      (property "Val" "2u2/6.1A" (id 4) (at 13.97 -5.08 0)
        (effects (font (size 1.27 1.27) (thickness 0.15)) (justify left bottom))
      )
      (property "Manufacturer" "Coilcraft" (id 5) (at 13.97 -12.7 0)
        (effects (font (size 1.27 1.27) (thickness 0.15)) (justify left bottom) hide)
      )
      (property "MPN" "XEL4030-222MEC" (id 6) (at 13.97 -15.24 0)
        (effects (font (size 1.27 1.27) (thickness 0.15)) (justify left bottom) hide)
      )
      (property "ISat" "" (id 7) (at 13.97 -16.51 0)
        (effects (font (size 1.27 1.27)) (justify left) hide)
      )
      (property "IMax" "" (id 8) (at 13.97 -20.32 0)
        (effects (font (size 1.27 1.27) (thickness 0.15)) (justify left bottom) hide)
      )
      (property "Size" "4x4" (id 9) (at 13.97 -22.86 0)
        (effects (font (size 1.27 1.27) (thickness 0.15)) (justify left bottom) hide)
      )
      (property "Author" "Antmicro" (id 10) (at 13.97 -25.4 0)
        (effects (font (size 1.27 1.27) (thickness 0.15)) (justify left bottom) hide)
      )
      (property "License" "Apache-2.0" (id 11) (at 13.97 -27.94 0)
        (effects (font (size 1.27 1.27) (thickness 0.15)) (justify left bottom) hide)
      )
      (symbol "L_2u2_6.1A_XEL4030_3_0_1"
        (arc (start 1.524 0) (mid 1.016 0.508) (end 0.508 0)
          (stroke (width 0) (type default) (color 0 0 0 0))
          (fill (type none))
        )
        (arc (start 2.54 0) (mid 2.032 0.508) (end 1.524 0)
          (stroke (width 0) (type default) (color 0 0 0 0))
          (fill (type none))
        )
        (arc (start 3.556 0) (mid 3.048 0.508) (end 2.54 0)
          (stroke (width 0) (type default) (color 0 0 0 0))
          (fill (type none))
        )
        (arc (start 4.572 0) (mid 4.064 0.508) (end 3.556 0)
          (stroke (width 0) (type default) (color 0 0 0 0))
          (fill (type none))
        )
      )
      (symbol "L_2u2_6.1A_XEL4030_3_1_1"
        (pin passive line (at 0 0 0) (length 0.508)
          (name "~" (effects (font (size 1.27 1.27))))
          (number "1" (effects (font (size 1.27 1.27))))
        )
        (pin passive line (at 5.08 0 180) (length 0.508)
          (name "~" (effects (font (size 1.27 1.27))))
          (number "2" (effects (font (size 1.27 1.27))))
        )
      )
    )
	(symbol "MB10S_1" (pin_names hide) (in_bom yes) (on_board yes)
      (property "Reference" "D" (id 0) (at 27.94 -2.54 0)
        (effects (font (size 1.27 1.27) (thickness 0.15)) (justify left bottom))
      )
      (property "Value" "MB10S_1" (id 1) (at 27.94 -5.08 0)
        (effects (font (size 1.27 1.27) (thickness 0.15)) (justify left bottom) hide)
      )
      (property "Footprint" "antmicro-footprints:SOIC-4_4.2x5.0mm_P5.7mm" (id 2) (at 27.94 -7.62 0)
        (effects (font (size 1.27 1.27) (thickness 0.15)) (justify left bottom) hide)
      )
      (property "Datasheet" "http://www.farnell.com/datasheets/2895435.pdf" (id 3) (at 27.94 -10.16 0)
        (effects (font (size 1.27 1.27) (thickness 0.15)) (justify left bottom) hide)
      )
      (property "MPN" "MB10S" (id 4) (at 27.94 -12.7 0)
        (effects (font (size 1.27 1.27) (thickness 0.15)) (justify left bottom))
      )
      (property "Manufacturer" "Multicomp" (id 5) (at 27.94 -15.24 0)
        (effects (font (size 1.27 1.27) (thickness 0.15)) (justify left bottom) hide)
      )
      (property "Author" "Antmicro" (id 6) (at 27.94 -17.78 0)
        (effects (font (size 1.27 1.27) (thickness 0.15)) (justify left bottom) hide)
      )
      (property "License" "Apache-2.0" (id 7) (at 27.94 -20.32 0)
        (effects (font (size 1.27 1.27) (thickness 0.15)) (justify left bottom) hide)
      )
      (property "ki_description" "Bridge Rectifier" (id 8) (at 0 0 0)
        (effects (font (size 1.27 1.27)) hide)
      )
      (symbol "MB10S_1_1_1"
        (polyline
          (pts
            (xy 2.54 -5.08)
            (xy 3.81 -5.08)
          )
          (stroke (width 0.254) (type default) (color 0 0 0 0))
          (fill (type none))
        )
        (polyline
          (pts
            (xy 3.81 -10.16)
            (xy 2.54 -10.16)
          )
          (stroke (width 0.254) (type default) (color 0 0 0 0))
          (fill (type none))
        )
        (polyline
          (pts
            (xy 3.81 -3.81)
            (xy 3.81 -7.62)
          )
          (stroke (width 0.254) (type default) (color 0 0 0 0))
          (fill (type none))
        )
        (polyline
          (pts
            (xy 3.81 -2.54)
            (xy 3.81 -3.81)
          )
          (stroke (width 0.254) (type default) (color 0 0 0 0))
          (fill (type none))
        )
        (polyline
          (pts
            (xy 3.81 0)
            (xy 2.54 0)
          )
          (stroke (width 0.254) (type default) (color 0 0 0 0))
          (fill (type none))
        )
        (polyline
          (pts
            (xy 5.08 -7.62)
            (xy 3.81 -7.62)
          )
          (stroke (width 0.254) (type default) (color 0 0 0 0))
          (fill (type none))
        )
        (polyline
          (pts
            (xy 5.08 -2.54)
            (xy 3.81 -2.54)
          )
          (stroke (width 0.254) (type default) (color 0 0 0 0))
          (fill (type none))
        )
        (polyline
          (pts
            (xy 7.62 -6.35)
            (xy 7.62 -8.89)
          )
          (stroke (width 0.254) (type default) (color 0 0 0 0))
          (fill (type none))
        )
        (polyline
          (pts
            (xy 7.62 -1.27)
            (xy 7.62 -3.81)
          )
          (stroke (width 0.254) (type default) (color 0 0 0 0))
          (fill (type none))
        )
        (polyline
          (pts
            (xy 8.89 -7.62)
            (xy 7.62 -7.62)
          )
          (stroke (width 0.254) (type default) (color 0 0 0 0))
          (fill (type none))
        )
        (polyline
          (pts
            (xy 8.89 -2.54)
            (xy 7.62 -2.54)
          )
          (stroke (width 0.254) (type default) (color 0 0 0 0))
          (fill (type none))
        )
        (polyline
          (pts
            (xy 10.16 -7.62)
            (xy 7.62 -7.62)
          )
          (stroke (width 0.254) (type default) (color 0 0 0 0))
          (fill (type none))
        )
        (polyline
          (pts
            (xy 10.16 -2.54)
            (xy 7.62 -2.54)
          )
          (stroke (width 0.254) (type default) (color 0 0 0 0))
          (fill (type none))
        )
        (polyline
          (pts
            (xy 12.7 -7.62)
            (xy 13.97 -7.62)
          )
          (stroke (width 0.254) (type default) (color 0 0 0 0))
          (fill (type none))
        )
        (polyline
          (pts
            (xy 12.7 -6.35)
            (xy 12.7 -8.89)
          )
          (stroke (width 0.254) (type default) (color 0 0 0 0))
          (fill (type none))
        )
        (polyline
          (pts
            (xy 12.7 -2.54)
            (xy 13.97 -2.54)
          )
          (stroke (width 0.254) (type default) (color 0 0 0 0))
          (fill (type none))
        )
        (polyline
          (pts
            (xy 12.7 -1.27)
            (xy 12.7 -3.81)
          )
          (stroke (width 0.254) (type default) (color 0 0 0 0))
          (fill (type none))
        )
        (polyline
          (pts
            (xy 13.97 -5.08)
            (xy 15.24 -5.08)
          )
          (stroke (width 0.254) (type default) (color 0 0 0 0))
          (fill (type none))
        )
        (polyline
          (pts
            (xy 13.97 -3.81)
            (xy 13.97 -7.62)
          )
          (stroke (width 0.254) (type default) (color 0 0 0 0))
          (fill (type none))
        )
        (polyline
          (pts
            (xy 13.97 -2.54)
            (xy 13.97 -3.81)
          )
          (stroke (width 0.254) (type default) (color 0 0 0 0))
          (fill (type none))
        )
        (polyline
          (pts
            (xy 8.89 -7.62)
            (xy 8.89 -10.16)
            (xy 3.81 -10.16)
          )
          (stroke (width 0.254) (type default) (color 0 0 0 0))
          (fill (type none))
        )
        (polyline
          (pts
            (xy 8.89 -2.54)
            (xy 8.89 0)
            (xy 3.81 0)
          )
          (stroke (width 0.254) (type default) (color 0 0 0 0))
          (fill (type none))
        )
        (polyline
          (pts
            (xy 5.08 -6.35)
            (xy 5.08 -8.89)
            (xy 7.62 -7.62)
            (xy 5.08 -6.35)
          )
          (stroke (width 0.254) (type default) (color 0 0 0 0))
          (fill (type outline))
        )
        (polyline
          (pts
            (xy 5.08 -1.27)
            (xy 5.08 -3.81)
            (xy 7.62 -2.54)
            (xy 5.08 -1.27)
          )
          (stroke (width 0.254) (type default) (color 0 0 0 0))
          (fill (type outline))
        )
        (polyline
          (pts
            (xy 10.16 -6.35)
            (xy 10.16 -8.89)
            (xy 12.7 -7.62)
            (xy 10.16 -6.35)
          )
          (stroke (width 0.254) (type default) (color 0 0 0 0))
          (fill (type outline))
        )
        (polyline
          (pts
            (xy 10.16 -1.27)
            (xy 10.16 -3.81)
            (xy 12.7 -2.54)
            (xy 10.16 -1.27)
          )
          (stroke (width 0.254) (type default) (color 0 0 0 0))
          (fill (type outline))
        )
        (rectangle (start 2.54 1.27) (end 15.24 -11.43)
          (stroke (width 0.254) (type default) (color 0 0 0 0))
          (fill (type background))
        )
        (pin passive line (at 17.78 -5.08 180) (length 2.54)
          (name "1" (effects (font (size 1.27 1.27))))
          (number "1" (effects (font (size 1.27 1.27))))
        )
        (pin passive line (at 0 -5.08 0) (length 2.54)
          (name "2" (effects (font (size 1.27 1.27))))
          (number "2" (effects (font (size 1.27 1.27))))
        )
        (pin passive line (at 0 0 0) (length 2.54)
          (name "3" (effects (font (size 1.27 1.27))))
          (number "3" (effects (font (size 1.27 1.27))))
        )
        (pin passive line (at 0 -10.16 0) (length 2.54)
          (name "4" (effects (font (size 1.27 1.27))))
          (number "4" (effects (font (size 1.27 1.27))))
        )
      )
    )
	(symbol "NFP0QHB242HS2D_1" (pin_names hide) (in_bom yes) (on_board yes)
      (property "Reference" "L" (id 0) (at 31.75 -5.08 0)
        (effects (font (size 1.27 1.27) (thickness 0.15)) (justify left bottom))
      )
      (property "Value" "NFP0QHB242HS2D_1" (id 1) (at 31.75 -7.62 0)
        (effects (font (size 1.27 1.27) (thickness 0.15)) (justify left bottom) hide)
      )
      (property "Footprint" "antmicro-footprints:L_Murata_025020_0605Metric" (id 2) (at 31.75 -10.16 0)
        (effects (font (size 1.27 1.27) (thickness 0.15)) (justify left bottom) hide)
      )
      (property "Datasheet" "https://www.farnell.com/datasheets/2616945.pdf" (id 3) (at 31.75 -12.7 0)
        (effects (font (size 1.27 1.27) (thickness 0.15)) (justify left bottom) hide)
      )
      (property "MPN" "NFP0QHB242HS2D" (id 4) (at 31.75 -15.24 0)
        (effects (font (size 1.27 1.27) (thickness 0.15)) (justify left bottom) hide)
      )
      (property "Manufacturer" "Murata" (id 5) (at 31.75 -17.78 0)
        (effects (font (size 1.27 1.27) (thickness 0.15)) (justify left bottom) hide)
      )
      (property "Author" "Antmicro" (id 6) (at 31.75 -20.32 0)
        (effects (font (size 1.27 1.27) (thickness 0.15)) (justify left bottom) hide)
      )
      (property "License" "Apache-2.0" (id 7) (at 31.75 -22.86 0)
        (effects (font (size 1.27 1.27) (thickness 0.15)) (justify left bottom) hide)
      )
      (property "ki_description" "Common mode filter" (id 8) (at 0 0 0)
        (effects (font (size 1.27 1.27)) hide)
      )
      (symbol "NFP0QHB242HS2D_1_1_1"
        (polyline
          (pts
            (xy 2.54 -2.921)
            (xy 12.7 -2.921)
          )
          (stroke (width 0.254) (type default) (color 0 0 0 0))
          (fill (type none))
        )
        (polyline
          (pts
            (xy 12.7 -2.032)
            (xy 2.54 -2.032)
          )
          (stroke (width 0.254) (type default) (color 0 0 0 0))
          (fill (type none))
        )
        (circle (center 1.905 -3.429) (radius 0.2032)
          (stroke (width 0.254) (type default) (color 0 0 0 0))
          (fill (type none))
        )
        (circle (center 1.905 -1.651) (radius 0.2032)
          (stroke (width 0.254) (type default) (color 0 0 0 0))
          (fill (type none))
        )
        (arc (start 2.54 0) (mid 3.81 -1.27) (end 5.08 0)
          (stroke (width 0.254) (type default) (color 0 0 0 0))
          (fill (type none))
        )
        (arc (start 5.08 -5.08) (mid 3.81 -3.81) (end 2.54 -5.08)
          (stroke (width 0.254) (type default) (color 0 0 0 0))
          (fill (type none))
        )
        (arc (start 5.08 0) (mid 6.35 -1.27) (end 7.62 0)
          (stroke (width 0.254) (type default) (color 0 0 0 0))
          (fill (type none))
        )
        (arc (start 7.62 -5.08) (mid 6.35 -3.81) (end 5.08 -5.08)
          (stroke (width 0.254) (type default) (color 0 0 0 0))
          (fill (type none))
        )
        (arc (start 7.62 0) (mid 8.89 -1.27) (end 10.16 0)
          (stroke (width 0.254) (type default) (color 0 0 0 0))
          (fill (type none))
        )
        (arc (start 10.16 -5.08) (mid 8.89 -3.81) (end 7.62 -5.08)
          (stroke (width 0.254) (type default) (color 0 0 0 0))
          (fill (type none))
        )
        (arc (start 10.16 0) (mid 11.43 -1.27) (end 12.7 0)
          (stroke (width 0.254) (type default) (color 0 0 0 0))
          (fill (type none))
        )
        (arc (start 12.7 -5.08) (mid 11.43 -3.81) (end 10.16 -5.08)
          (stroke (width 0.254) (type default) (color 0 0 0 0))
          (fill (type none))
        )
        (pin passive line (at 0 0 0) (length 2.54)
          (name "1" (effects (font (size 1.27 1.27))))
          (number "1" (effects (font (size 1.27 1.27))))
        )
        (pin passive line (at 15.24 0 180) (length 2.54)
          (name "2" (effects (font (size 1.27 1.27))))
          (number "2" (effects (font (size 1.27 1.27))))
        )
        (pin passive line (at 15.24 -5.08 180) (length 2.54)
          (name "3" (effects (font (size 1.27 1.27))))
          (number "3" (effects (font (size 1.27 1.27))))
        )
        (pin passive line (at 0 -5.08 0) (length 2.54)
          (name "4" (effects (font (size 1.27 1.27))))
          (number "4" (effects (font (size 1.27 1.27))))
        )
      )
    )
	(symbol "NFP0QHB242HS2D_2" (pin_names hide) (in_bom yes) (on_board yes)
      (property "Reference" "L" (id 0) (at 31.75 -5.08 0)
        (effects (font (size 1.27 1.27) (thickness 0.15)) (justify left bottom))
      )
      (property "Value" "NFP0QHB242HS2D_2" (id 1) (at 31.75 -7.62 0)
        (effects (font (size 1.27 1.27) (thickness 0.15)) (justify left bottom) hide)
      )
      (property "Footprint" "antmicro-footprints:L_Murata_025020_0605Metric" (id 2) (at 31.75 -10.16 0)
        (effects (font (size 1.27 1.27) (thickness 0.15)) (justify left bottom) hide)
      )
      (property "Datasheet" "https://www.farnell.com/datasheets/2616945.pdf" (id 3) (at 31.75 -12.7 0)
        (effects (font (size 1.27 1.27) (thickness 0.15)) (justify left bottom) hide)
      )
      (property "MPN" "NFP0QHB242HS2D" (id 4) (at 31.75 -15.24 0)
        (effects (font (size 1.27 1.27) (thickness 0.15)) (justify left bottom) hide)
      )
      (property "Manufacturer" "Murata" (id 5) (at 31.75 -17.78 0)
        (effects (font (size 1.27 1.27) (thickness 0.15)) (justify left bottom) hide)
      )
      (property "Author" "Antmicro" (id 6) (at 31.75 -20.32 0)
        (effects (font (size 1.27 1.27) (thickness 0.15)) (justify left bottom) hide)
      )
      (property "License" "Apache-2.0" (id 7) (at 31.75 -22.86 0)
        (effects (font (size 1.27 1.27) (thickness 0.15)) (justify left bottom) hide)
      )
      (property "ki_description" "Common mode filter" (id 8) (at 0 0 0)
        (effects (font (size 1.27 1.27)) hide)
      )
      (symbol "NFP0QHB242HS2D_2_1_1"
        (polyline
          (pts
            (xy 2.54 -2.921)
            (xy 12.7 -2.921)
          )
          (stroke (width 0.254) (type default) (color 0 0 0 0))
          (fill (type none))
        )
        (polyline
          (pts
            (xy 12.7 -2.032)
            (xy 2.54 -2.032)
          )
          (stroke (width 0.254) (type default) (color 0 0 0 0))
          (fill (type none))
        )
        (circle (center 1.905 -3.429) (radius 0.2032)
          (stroke (width 0.254) (type default) (color 0 0 0 0))
          (fill (type none))
        )
        (circle (center 1.905 -1.651) (radius 0.2032)
          (stroke (width 0.254) (type default) (color 0 0 0 0))
          (fill (type none))
        )
        (arc (start 2.54 0) (mid 3.81 -1.27) (end 5.08 0)
          (stroke (width 0.254) (type default) (color 0 0 0 0))
          (fill (type none))
        )
        (arc (start 5.08 -5.08) (mid 3.81 -3.81) (end 2.54 -5.08)
          (stroke (width 0.254) (type default) (color 0 0 0 0))
          (fill (type none))
        )
        (arc (start 5.08 0) (mid 6.35 -1.27) (end 7.62 0)
          (stroke (width 0.254) (type default) (color 0 0 0 0))
          (fill (type none))
        )
        (arc (start 7.62 -5.08) (mid 6.35 -3.81) (end 5.08 -5.08)
          (stroke (width 0.254) (type default) (color 0 0 0 0))
          (fill (type none))
        )
        (arc (start 7.62 0) (mid 8.89 -1.27) (end 10.16 0)
          (stroke (width 0.254) (type default) (color 0 0 0 0))
          (fill (type none))
        )
        (arc (start 10.16 -5.08) (mid 8.89 -3.81) (end 7.62 -5.08)
          (stroke (width 0.254) (type default) (color 0 0 0 0))
          (fill (type none))
        )
        (arc (start 10.16 0) (mid 11.43 -1.27) (end 12.7 0)
          (stroke (width 0.254) (type default) (color 0 0 0 0))
          (fill (type none))
        )
        (arc (start 12.7 -5.08) (mid 11.43 -3.81) (end 10.16 -5.08)
          (stroke (width 0.254) (type default) (color 0 0 0 0))
          (fill (type none))
        )
        (pin passive line (at 0 0 0) (length 2.54)
          (name "1" (effects (font (size 1.27 1.27))))
          (number "1" (effects (font (size 1.27 1.27))))
        )
        (pin passive line (at 15.24 0 180) (length 2.54)
          (name "2" (effects (font (size 1.27 1.27))))
          (number "2" (effects (font (size 1.27 1.27))))
        )
        (pin passive line (at 15.24 -5.08 180) (length 2.54)
          (name "3" (effects (font (size 1.27 1.27))))
          (number "3" (effects (font (size 1.27 1.27))))
        )
        (pin passive line (at 0 -5.08 0) (length 2.54)
          (name "4" (effects (font (size 1.27 1.27))))
          (number "4" (effects (font (size 1.27 1.27))))
        )
      )
    )
	(symbol "NFP0QHB242HS2D_3" (pin_names hide) (in_bom yes) (on_board yes)
      (property "Reference" "L" (id 0) (at 31.75 -5.08 0)
        (effects (font (size 1.27 1.27) (thickness 0.15)) (justify left bottom))
      )
      (property "Value" "NFP0QHB242HS2D_3" (id 1) (at 31.75 -7.62 0)
        (effects (font (size 1.27 1.27) (thickness 0.15)) (justify left bottom) hide)
      )
      (property "Footprint" "antmicro-footprints:L_Murata_025020_0605Metric" (id 2) (at 31.75 -10.16 0)
        (effects (font (size 1.27 1.27) (thickness 0.15)) (justify left bottom) hide)
      )
      (property "Datasheet" "https://www.farnell.com/datasheets/2616945.pdf" (id 3) (at 31.75 -12.7 0)
        (effects (font (size 1.27 1.27) (thickness 0.15)) (justify left bottom) hide)
      )
      (property "MPN" "NFP0QHB242HS2D" (id 4) (at 31.75 -15.24 0)
        (effects (font (size 1.27 1.27) (thickness 0.15)) (justify left bottom) hide)
      )
      (property "Manufacturer" "Murata" (id 5) (at 31.75 -17.78 0)
        (effects (font (size 1.27 1.27) (thickness 0.15)) (justify left bottom) hide)
      )
      (property "Author" "Antmicro" (id 6) (at 31.75 -20.32 0)
        (effects (font (size 1.27 1.27) (thickness 0.15)) (justify left bottom) hide)
      )
      (property "License" "Apache-2.0" (id 7) (at 31.75 -22.86 0)
        (effects (font (size 1.27 1.27) (thickness 0.15)) (justify left bottom) hide)
      )
      (property "ki_description" "Common mode filter" (id 8) (at 0 0 0)
        (effects (font (size 1.27 1.27)) hide)
      )
      (symbol "NFP0QHB242HS2D_3_1_1"
        (polyline
          (pts
            (xy 2.54 -2.921)
            (xy 12.7 -2.921)
          )
          (stroke (width 0.254) (type default) (color 0 0 0 0))
          (fill (type none))
        )
        (polyline
          (pts
            (xy 12.7 -2.032)
            (xy 2.54 -2.032)
          )
          (stroke (width 0.254) (type default) (color 0 0 0 0))
          (fill (type none))
        )
        (circle (center 1.905 -3.429) (radius 0.2032)
          (stroke (width 0.254) (type default) (color 0 0 0 0))
          (fill (type none))
        )
        (circle (center 1.905 -1.651) (radius 0.2032)
          (stroke (width 0.254) (type default) (color 0 0 0 0))
          (fill (type none))
        )
        (arc (start 2.54 0) (mid 3.81 -1.27) (end 5.08 0)
          (stroke (width 0.254) (type default) (color 0 0 0 0))
          (fill (type none))
        )
        (arc (start 5.08 -5.08) (mid 3.81 -3.81) (end 2.54 -5.08)
          (stroke (width 0.254) (type default) (color 0 0 0 0))
          (fill (type none))
        )
        (arc (start 5.08 0) (mid 6.35 -1.27) (end 7.62 0)
          (stroke (width 0.254) (type default) (color 0 0 0 0))
          (fill (type none))
        )
        (arc (start 7.62 -5.08) (mid 6.35 -3.81) (end 5.08 -5.08)
          (stroke (width 0.254) (type default) (color 0 0 0 0))
          (fill (type none))
        )
        (arc (start 7.62 0) (mid 8.89 -1.27) (end 10.16 0)
          (stroke (width 0.254) (type default) (color 0 0 0 0))
          (fill (type none))
        )
        (arc (start 10.16 -5.08) (mid 8.89 -3.81) (end 7.62 -5.08)
          (stroke (width 0.254) (type default) (color 0 0 0 0))
          (fill (type none))
        )
        (arc (start 10.16 0) (mid 11.43 -1.27) (end 12.7 0)
          (stroke (width 0.254) (type default) (color 0 0 0 0))
          (fill (type none))
        )
        (arc (start 12.7 -5.08) (mid 11.43 -3.81) (end 10.16 -5.08)
          (stroke (width 0.254) (type default) (color 0 0 0 0))
          (fill (type none))
        )
        (pin passive line (at 0 0 0) (length 2.54)
          (name "1" (effects (font (size 1.27 1.27))))
          (number "1" (effects (font (size 1.27 1.27))))
        )
        (pin passive line (at 15.24 0 180) (length 2.54)
          (name "2" (effects (font (size 1.27 1.27))))
          (number "2" (effects (font (size 1.27 1.27))))
        )
        (pin passive line (at 15.24 -5.08 180) (length 2.54)
          (name "3" (effects (font (size 1.27 1.27))))
          (number "3" (effects (font (size 1.27 1.27))))
        )
        (pin passive line (at 0 -5.08 0) (length 2.54)
          (name "4" (effects (font (size 1.27 1.27))))
          (number "4" (effects (font (size 1.27 1.27))))
        )
      )
    )
	(symbol "NFP0QHB242HS2D_4" (pin_names hide) (in_bom yes) (on_board yes)
      (property "Reference" "L" (id 0) (at 31.75 -5.08 0)
        (effects (font (size 1.27 1.27) (thickness 0.15)) (justify left bottom))
      )
      (property "Value" "NFP0QHB242HS2D_4" (id 1) (at 31.75 -7.62 0)
        (effects (font (size 1.27 1.27) (thickness 0.15)) (justify left bottom) hide)
      )
      (property "Footprint" "antmicro-footprints:L_Murata_025020_0605Metric" (id 2) (at 31.75 -10.16 0)
        (effects (font (size 1.27 1.27) (thickness 0.15)) (justify left bottom) hide)
      )
      (property "Datasheet" "https://www.farnell.com/datasheets/2616945.pdf" (id 3) (at 31.75 -12.7 0)
        (effects (font (size 1.27 1.27) (thickness 0.15)) (justify left bottom) hide)
      )
      (property "MPN" "NFP0QHB242HS2D" (id 4) (at 31.75 -15.24 0)
        (effects (font (size 1.27 1.27) (thickness 0.15)) (justify left bottom) hide)
      )
      (property "Manufacturer" "Murata" (id 5) (at 31.75 -17.78 0)
        (effects (font (size 1.27 1.27) (thickness 0.15)) (justify left bottom) hide)
      )
      (property "Author" "Antmicro" (id 6) (at 31.75 -20.32 0)
        (effects (font (size 1.27 1.27) (thickness 0.15)) (justify left bottom) hide)
      )
      (property "License" "Apache-2.0" (id 7) (at 31.75 -22.86 0)
        (effects (font (size 1.27 1.27) (thickness 0.15)) (justify left bottom) hide)
      )
      (property "ki_description" "Common mode filter" (id 8) (at 0 0 0)
        (effects (font (size 1.27 1.27)) hide)
      )
      (symbol "NFP0QHB242HS2D_4_1_1"
        (polyline
          (pts
            (xy 2.54 -2.921)
            (xy 12.7 -2.921)
          )
          (stroke (width 0.254) (type default) (color 0 0 0 0))
          (fill (type none))
        )
        (polyline
          (pts
            (xy 12.7 -2.032)
            (xy 2.54 -2.032)
          )
          (stroke (width 0.254) (type default) (color 0 0 0 0))
          (fill (type none))
        )
        (circle (center 1.905 -3.429) (radius 0.2032)
          (stroke (width 0.254) (type default) (color 0 0 0 0))
          (fill (type none))
        )
        (circle (center 1.905 -1.651) (radius 0.2032)
          (stroke (width 0.254) (type default) (color 0 0 0 0))
          (fill (type none))
        )
        (arc (start 2.54 0) (mid 3.81 -1.27) (end 5.08 0)
          (stroke (width 0.254) (type default) (color 0 0 0 0))
          (fill (type none))
        )
        (arc (start 5.08 -5.08) (mid 3.81 -3.81) (end 2.54 -5.08)
          (stroke (width 0.254) (type default) (color 0 0 0 0))
          (fill (type none))
        )
        (arc (start 5.08 0) (mid 6.35 -1.27) (end 7.62 0)
          (stroke (width 0.254) (type default) (color 0 0 0 0))
          (fill (type none))
        )
        (arc (start 7.62 -5.08) (mid 6.35 -3.81) (end 5.08 -5.08)
          (stroke (width 0.254) (type default) (color 0 0 0 0))
          (fill (type none))
        )
        (arc (start 7.62 0) (mid 8.89 -1.27) (end 10.16 0)
          (stroke (width 0.254) (type default) (color 0 0 0 0))
          (fill (type none))
        )
        (arc (start 10.16 -5.08) (mid 8.89 -3.81) (end 7.62 -5.08)
          (stroke (width 0.254) (type default) (color 0 0 0 0))
          (fill (type none))
        )
        (arc (start 10.16 0) (mid 11.43 -1.27) (end 12.7 0)
          (stroke (width 0.254) (type default) (color 0 0 0 0))
          (fill (type none))
        )
        (arc (start 12.7 -5.08) (mid 11.43 -3.81) (end 10.16 -5.08)
          (stroke (width 0.254) (type default) (color 0 0 0 0))
          (fill (type none))
        )
        (pin passive line (at 0 0 0) (length 2.54)
          (name "1" (effects (font (size 1.27 1.27))))
          (number "1" (effects (font (size 1.27 1.27))))
        )
        (pin passive line (at 15.24 0 180) (length 2.54)
          (name "2" (effects (font (size 1.27 1.27))))
          (number "2" (effects (font (size 1.27 1.27))))
        )
        (pin passive line (at 15.24 -5.08 180) (length 2.54)
          (name "3" (effects (font (size 1.27 1.27))))
          (number "3" (effects (font (size 1.27 1.27))))
        )
        (pin passive line (at 0 -5.08 0) (length 2.54)
          (name "4" (effects (font (size 1.27 1.27))))
          (number "4" (effects (font (size 1.27 1.27))))
        )
      )
    )
	(symbol "NFP0QHB242HS2D_5" (pin_names hide) (in_bom yes) (on_board yes)
      (property "Reference" "L" (id 0) (at 31.75 -5.08 0)
        (effects (font (size 1.27 1.27) (thickness 0.15)) (justify left bottom))
      )
      (property "Value" "NFP0QHB242HS2D_5" (id 1) (at 31.75 -7.62 0)
        (effects (font (size 1.27 1.27) (thickness 0.15)) (justify left bottom) hide)
      )
      (property "Footprint" "antmicro-footprints:L_Murata_025020_0605Metric" (id 2) (at 31.75 -10.16 0)
        (effects (font (size 1.27 1.27) (thickness 0.15)) (justify left bottom) hide)
      )
      (property "Datasheet" "https://www.farnell.com/datasheets/2616945.pdf" (id 3) (at 31.75 -12.7 0)
        (effects (font (size 1.27 1.27) (thickness 0.15)) (justify left bottom) hide)
      )
      (property "MPN" "NFP0QHB242HS2D" (id 4) (at 31.75 -15.24 0)
        (effects (font (size 1.27 1.27) (thickness 0.15)) (justify left bottom) hide)
      )
      (property "Manufacturer" "Murata" (id 5) (at 31.75 -17.78 0)
        (effects (font (size 1.27 1.27) (thickness 0.15)) (justify left bottom) hide)
      )
      (property "Author" "Antmicro" (id 6) (at 31.75 -20.32 0)
        (effects (font (size 1.27 1.27) (thickness 0.15)) (justify left bottom) hide)
      )
      (property "License" "Apache-2.0" (id 7) (at 31.75 -22.86 0)
        (effects (font (size 1.27 1.27) (thickness 0.15)) (justify left bottom) hide)
      )
      (property "ki_description" "Common mode filter" (id 8) (at 0 0 0)
        (effects (font (size 1.27 1.27)) hide)
      )
      (symbol "NFP0QHB242HS2D_5_1_1"
        (polyline
          (pts
            (xy 2.54 -2.921)
            (xy 12.7 -2.921)
          )
          (stroke (width 0.254) (type default) (color 0 0 0 0))
          (fill (type none))
        )
        (polyline
          (pts
            (xy 12.7 -2.032)
            (xy 2.54 -2.032)
          )
          (stroke (width 0.254) (type default) (color 0 0 0 0))
          (fill (type none))
        )
        (circle (center 1.905 -3.429) (radius 0.2032)
          (stroke (width 0.254) (type default) (color 0 0 0 0))
          (fill (type none))
        )
        (circle (center 1.905 -1.651) (radius 0.2032)
          (stroke (width 0.254) (type default) (color 0 0 0 0))
          (fill (type none))
        )
        (arc (start 2.54 0) (mid 3.81 -1.27) (end 5.08 0)
          (stroke (width 0.254) (type default) (color 0 0 0 0))
          (fill (type none))
        )
        (arc (start 5.08 -5.08) (mid 3.81 -3.81) (end 2.54 -5.08)
          (stroke (width 0.254) (type default) (color 0 0 0 0))
          (fill (type none))
        )
        (arc (start 5.08 0) (mid 6.35 -1.27) (end 7.62 0)
          (stroke (width 0.254) (type default) (color 0 0 0 0))
          (fill (type none))
        )
        (arc (start 7.62 -5.08) (mid 6.35 -3.81) (end 5.08 -5.08)
          (stroke (width 0.254) (type default) (color 0 0 0 0))
          (fill (type none))
        )
        (arc (start 7.62 0) (mid 8.89 -1.27) (end 10.16 0)
          (stroke (width 0.254) (type default) (color 0 0 0 0))
          (fill (type none))
        )
        (arc (start 10.16 -5.08) (mid 8.89 -3.81) (end 7.62 -5.08)
          (stroke (width 0.254) (type default) (color 0 0 0 0))
          (fill (type none))
        )
        (arc (start 10.16 0) (mid 11.43 -1.27) (end 12.7 0)
          (stroke (width 0.254) (type default) (color 0 0 0 0))
          (fill (type none))
        )
        (arc (start 12.7 -5.08) (mid 11.43 -3.81) (end 10.16 -5.08)
          (stroke (width 0.254) (type default) (color 0 0 0 0))
          (fill (type none))
        )
        (pin passive line (at 0 0 0) (length 2.54)
          (name "1" (effects (font (size 1.27 1.27))))
          (number "1" (effects (font (size 1.27 1.27))))
        )
        (pin passive line (at 15.24 0 180) (length 2.54)
          (name "2" (effects (font (size 1.27 1.27))))
          (number "2" (effects (font (size 1.27 1.27))))
        )
        (pin passive line (at 15.24 -5.08 180) (length 2.54)
          (name "3" (effects (font (size 1.27 1.27))))
          (number "3" (effects (font (size 1.27 1.27))))
        )
        (pin passive line (at 0 -5.08 0) (length 2.54)
          (name "4" (effects (font (size 1.27 1.27))))
          (number "4" (effects (font (size 1.27 1.27))))
        )
      )
    )
	(symbol "NFP0QHB242HS2D_6" (pin_names hide) (in_bom yes) (on_board yes)
      (property "Reference" "L" (id 0) (at 31.75 -5.08 0)
        (effects (font (size 1.27 1.27) (thickness 0.15)) (justify left bottom))
      )
      (property "Value" "NFP0QHB242HS2D_6" (id 1) (at 31.75 -7.62 0)
        (effects (font (size 1.27 1.27) (thickness 0.15)) (justify left bottom) hide)
      )
      (property "Footprint" "antmicro-footprints:L_Murata_025020_0605Metric" (id 2) (at 31.75 -10.16 0)
        (effects (font (size 1.27 1.27) (thickness 0.15)) (justify left bottom) hide)
      )
      (property "Datasheet" "https://www.farnell.com/datasheets/2616945.pdf" (id 3) (at 31.75 -12.7 0)
        (effects (font (size 1.27 1.27) (thickness 0.15)) (justify left bottom) hide)
      )
      (property "MPN" "NFP0QHB242HS2D" (id 4) (at 31.75 -15.24 0)
        (effects (font (size 1.27 1.27) (thickness 0.15)) (justify left bottom) hide)
      )
      (property "Manufacturer" "Murata" (id 5) (at 31.75 -17.78 0)
        (effects (font (size 1.27 1.27) (thickness 0.15)) (justify left bottom) hide)
      )
      (property "Author" "Antmicro" (id 6) (at 31.75 -20.32 0)
        (effects (font (size 1.27 1.27) (thickness 0.15)) (justify left bottom) hide)
      )
      (property "License" "Apache-2.0" (id 7) (at 31.75 -22.86 0)
        (effects (font (size 1.27 1.27) (thickness 0.15)) (justify left bottom) hide)
      )
      (property "ki_description" "Common mode filter" (id 8) (at 0 0 0)
        (effects (font (size 1.27 1.27)) hide)
      )
      (symbol "NFP0QHB242HS2D_6_1_1"
        (polyline
          (pts
            (xy 2.54 -2.921)
            (xy 12.7 -2.921)
          )
          (stroke (width 0.254) (type default) (color 0 0 0 0))
          (fill (type none))
        )
        (polyline
          (pts
            (xy 12.7 -2.032)
            (xy 2.54 -2.032)
          )
          (stroke (width 0.254) (type default) (color 0 0 0 0))
          (fill (type none))
        )
        (circle (center 1.905 -3.429) (radius 0.2032)
          (stroke (width 0.254) (type default) (color 0 0 0 0))
          (fill (type none))
        )
        (circle (center 1.905 -1.651) (radius 0.2032)
          (stroke (width 0.254) (type default) (color 0 0 0 0))
          (fill (type none))
        )
        (arc (start 2.54 0) (mid 3.81 -1.27) (end 5.08 0)
          (stroke (width 0.254) (type default) (color 0 0 0 0))
          (fill (type none))
        )
        (arc (start 5.08 -5.08) (mid 3.81 -3.81) (end 2.54 -5.08)
          (stroke (width 0.254) (type default) (color 0 0 0 0))
          (fill (type none))
        )
        (arc (start 5.08 0) (mid 6.35 -1.27) (end 7.62 0)
          (stroke (width 0.254) (type default) (color 0 0 0 0))
          (fill (type none))
        )
        (arc (start 7.62 -5.08) (mid 6.35 -3.81) (end 5.08 -5.08)
          (stroke (width 0.254) (type default) (color 0 0 0 0))
          (fill (type none))
        )
        (arc (start 7.62 0) (mid 8.89 -1.27) (end 10.16 0)
          (stroke (width 0.254) (type default) (color 0 0 0 0))
          (fill (type none))
        )
        (arc (start 10.16 -5.08) (mid 8.89 -3.81) (end 7.62 -5.08)
          (stroke (width 0.254) (type default) (color 0 0 0 0))
          (fill (type none))
        )
        (arc (start 10.16 0) (mid 11.43 -1.27) (end 12.7 0)
          (stroke (width 0.254) (type default) (color 0 0 0 0))
          (fill (type none))
        )
        (arc (start 12.7 -5.08) (mid 11.43 -3.81) (end 10.16 -5.08)
          (stroke (width 0.254) (type default) (color 0 0 0 0))
          (fill (type none))
        )
        (pin passive line (at 0 0 0) (length 2.54)
          (name "1" (effects (font (size 1.27 1.27))))
          (number "1" (effects (font (size 1.27 1.27))))
        )
        (pin passive line (at 15.24 0 180) (length 2.54)
          (name "2" (effects (font (size 1.27 1.27))))
          (number "2" (effects (font (size 1.27 1.27))))
        )
        (pin passive line (at 15.24 -5.08 180) (length 2.54)
          (name "3" (effects (font (size 1.27 1.27))))
          (number "3" (effects (font (size 1.27 1.27))))
        )
        (pin passive line (at 0 -5.08 0) (length 2.54)
          (name "4" (effects (font (size 1.27 1.27))))
          (number "4" (effects (font (size 1.27 1.27))))
        )
      )
    )
	(symbol "NFP0QHB242HS2D_7" (pin_names hide) (in_bom yes) (on_board yes)
      (property "Reference" "L" (id 0) (at 31.75 -5.08 0)
        (effects (font (size 1.27 1.27) (thickness 0.15)) (justify left bottom))
      )
      (property "Value" "NFP0QHB242HS2D_7" (id 1) (at 31.75 -7.62 0)
        (effects (font (size 1.27 1.27) (thickness 0.15)) (justify left bottom) hide)
      )
      (property "Footprint" "antmicro-footprints:L_Murata_025020_0605Metric" (id 2) (at 31.75 -10.16 0)
        (effects (font (size 1.27 1.27) (thickness 0.15)) (justify left bottom) hide)
      )
      (property "Datasheet" "https://www.farnell.com/datasheets/2616945.pdf" (id 3) (at 31.75 -12.7 0)
        (effects (font (size 1.27 1.27) (thickness 0.15)) (justify left bottom) hide)
      )
      (property "MPN" "NFP0QHB242HS2D" (id 4) (at 31.75 -15.24 0)
        (effects (font (size 1.27 1.27) (thickness 0.15)) (justify left bottom) hide)
      )
      (property "Manufacturer" "Murata" (id 5) (at 31.75 -17.78 0)
        (effects (font (size 1.27 1.27) (thickness 0.15)) (justify left bottom) hide)
      )
      (property "Author" "Antmicro" (id 6) (at 31.75 -20.32 0)
        (effects (font (size 1.27 1.27) (thickness 0.15)) (justify left bottom) hide)
      )
      (property "License" "Apache-2.0" (id 7) (at 31.75 -22.86 0)
        (effects (font (size 1.27 1.27) (thickness 0.15)) (justify left bottom) hide)
      )
      (property "ki_description" "Common mode filter" (id 8) (at 0 0 0)
        (effects (font (size 1.27 1.27)) hide)
      )
      (symbol "NFP0QHB242HS2D_7_1_1"
        (polyline
          (pts
            (xy 2.54 -2.921)
            (xy 12.7 -2.921)
          )
          (stroke (width 0.254) (type default) (color 0 0 0 0))
          (fill (type none))
        )
        (polyline
          (pts
            (xy 12.7 -2.032)
            (xy 2.54 -2.032)
          )
          (stroke (width 0.254) (type default) (color 0 0 0 0))
          (fill (type none))
        )
        (circle (center 1.905 -3.429) (radius 0.2032)
          (stroke (width 0.254) (type default) (color 0 0 0 0))
          (fill (type none))
        )
        (circle (center 1.905 -1.651) (radius 0.2032)
          (stroke (width 0.254) (type default) (color 0 0 0 0))
          (fill (type none))
        )
        (arc (start 2.54 0) (mid 3.81 -1.27) (end 5.08 0)
          (stroke (width 0.254) (type default) (color 0 0 0 0))
          (fill (type none))
        )
        (arc (start 5.08 -5.08) (mid 3.81 -3.81) (end 2.54 -5.08)
          (stroke (width 0.254) (type default) (color 0 0 0 0))
          (fill (type none))
        )
        (arc (start 5.08 0) (mid 6.35 -1.27) (end 7.62 0)
          (stroke (width 0.254) (type default) (color 0 0 0 0))
          (fill (type none))
        )
        (arc (start 7.62 -5.08) (mid 6.35 -3.81) (end 5.08 -5.08)
          (stroke (width 0.254) (type default) (color 0 0 0 0))
          (fill (type none))
        )
        (arc (start 7.62 0) (mid 8.89 -1.27) (end 10.16 0)
          (stroke (width 0.254) (type default) (color 0 0 0 0))
          (fill (type none))
        )
        (arc (start 10.16 -5.08) (mid 8.89 -3.81) (end 7.62 -5.08)
          (stroke (width 0.254) (type default) (color 0 0 0 0))
          (fill (type none))
        )
        (arc (start 10.16 0) (mid 11.43 -1.27) (end 12.7 0)
          (stroke (width 0.254) (type default) (color 0 0 0 0))
          (fill (type none))
        )
        (arc (start 12.7 -5.08) (mid 11.43 -3.81) (end 10.16 -5.08)
          (stroke (width 0.254) (type default) (color 0 0 0 0))
          (fill (type none))
        )
        (pin passive line (at 0 0 0) (length 2.54)
          (name "1" (effects (font (size 1.27 1.27))))
          (number "1" (effects (font (size 1.27 1.27))))
        )
        (pin passive line (at 15.24 0 180) (length 2.54)
          (name "2" (effects (font (size 1.27 1.27))))
          (number "2" (effects (font (size 1.27 1.27))))
        )
        (pin passive line (at 15.24 -5.08 180) (length 2.54)
          (name "3" (effects (font (size 1.27 1.27))))
          (number "3" (effects (font (size 1.27 1.27))))
        )
        (pin passive line (at 0 -5.08 0) (length 2.54)
          (name "4" (effects (font (size 1.27 1.27))))
          (number "4" (effects (font (size 1.27 1.27))))
        )
      )
    )
	(symbol "NFP0QHB242HS2D_8" (pin_names hide) (in_bom yes) (on_board yes)
      (property "Reference" "L" (id 0) (at 31.75 -5.08 0)
        (effects (font (size 1.27 1.27) (thickness 0.15)) (justify left bottom))
      )
      (property "Value" "NFP0QHB242HS2D_8" (id 1) (at 31.75 -7.62 0)
        (effects (font (size 1.27 1.27) (thickness 0.15)) (justify left bottom) hide)
      )
      (property "Footprint" "antmicro-footprints:L_Murata_025020_0605Metric" (id 2) (at 31.75 -10.16 0)
        (effects (font (size 1.27 1.27) (thickness 0.15)) (justify left bottom) hide)
      )
      (property "Datasheet" "https://www.farnell.com/datasheets/2616945.pdf" (id 3) (at 31.75 -12.7 0)
        (effects (font (size 1.27 1.27) (thickness 0.15)) (justify left bottom) hide)
      )
      (property "MPN" "NFP0QHB242HS2D" (id 4) (at 31.75 -15.24 0)
        (effects (font (size 1.27 1.27) (thickness 0.15)) (justify left bottom) hide)
      )
      (property "Manufacturer" "Murata" (id 5) (at 31.75 -17.78 0)
        (effects (font (size 1.27 1.27) (thickness 0.15)) (justify left bottom) hide)
      )
      (property "Author" "Antmicro" (id 6) (at 31.75 -20.32 0)
        (effects (font (size 1.27 1.27) (thickness 0.15)) (justify left bottom) hide)
      )
      (property "License" "Apache-2.0" (id 7) (at 31.75 -22.86 0)
        (effects (font (size 1.27 1.27) (thickness 0.15)) (justify left bottom) hide)
      )
      (property "ki_description" "Common mode filter" (id 8) (at 0 0 0)
        (effects (font (size 1.27 1.27)) hide)
      )
      (symbol "NFP0QHB242HS2D_8_1_1"
        (polyline
          (pts
            (xy 2.54 -2.921)
            (xy 12.7 -2.921)
          )
          (stroke (width 0.254) (type default) (color 0 0 0 0))
          (fill (type none))
        )
        (polyline
          (pts
            (xy 12.7 -2.032)
            (xy 2.54 -2.032)
          )
          (stroke (width 0.254) (type default) (color 0 0 0 0))
          (fill (type none))
        )
        (circle (center 1.905 -3.429) (radius 0.2032)
          (stroke (width 0.254) (type default) (color 0 0 0 0))
          (fill (type none))
        )
        (circle (center 1.905 -1.651) (radius 0.2032)
          (stroke (width 0.254) (type default) (color 0 0 0 0))
          (fill (type none))
        )
        (arc (start 2.54 0) (mid 3.81 -1.27) (end 5.08 0)
          (stroke (width 0.254) (type default) (color 0 0 0 0))
          (fill (type none))
        )
        (arc (start 5.08 -5.08) (mid 3.81 -3.81) (end 2.54 -5.08)
          (stroke (width 0.254) (type default) (color 0 0 0 0))
          (fill (type none))
        )
        (arc (start 5.08 0) (mid 6.35 -1.27) (end 7.62 0)
          (stroke (width 0.254) (type default) (color 0 0 0 0))
          (fill (type none))
        )
        (arc (start 7.62 -5.08) (mid 6.35 -3.81) (end 5.08 -5.08)
          (stroke (width 0.254) (type default) (color 0 0 0 0))
          (fill (type none))
        )
        (arc (start 7.62 0) (mid 8.89 -1.27) (end 10.16 0)
          (stroke (width 0.254) (type default) (color 0 0 0 0))
          (fill (type none))
        )
        (arc (start 10.16 -5.08) (mid 8.89 -3.81) (end 7.62 -5.08)
          (stroke (width 0.254) (type default) (color 0 0 0 0))
          (fill (type none))
        )
        (arc (start 10.16 0) (mid 11.43 -1.27) (end 12.7 0)
          (stroke (width 0.254) (type default) (color 0 0 0 0))
          (fill (type none))
        )
        (arc (start 12.7 -5.08) (mid 11.43 -3.81) (end 10.16 -5.08)
          (stroke (width 0.254) (type default) (color 0 0 0 0))
          (fill (type none))
        )
        (pin passive line (at 0 0 0) (length 2.54)
          (name "1" (effects (font (size 1.27 1.27))))
          (number "1" (effects (font (size 1.27 1.27))))
        )
        (pin passive line (at 15.24 0 180) (length 2.54)
          (name "2" (effects (font (size 1.27 1.27))))
          (number "2" (effects (font (size 1.27 1.27))))
        )
        (pin passive line (at 15.24 -5.08 180) (length 2.54)
          (name "3" (effects (font (size 1.27 1.27))))
          (number "3" (effects (font (size 1.27 1.27))))
        )
        (pin passive line (at 0 -5.08 0) (length 2.54)
          (name "4" (effects (font (size 1.27 1.27))))
          (number "4" (effects (font (size 1.27 1.27))))
        )
      )
    )
	(symbol "NFP0QHB242HS2D_9" (pin_names hide) (in_bom yes) (on_board yes)
      (property "Reference" "L" (id 0) (at 31.75 -5.08 0)
        (effects (font (size 1.27 1.27) (thickness 0.15)) (justify left bottom))
      )
      (property "Value" "NFP0QHB242HS2D_9" (id 1) (at 31.75 -7.62 0)
        (effects (font (size 1.27 1.27) (thickness 0.15)) (justify left bottom) hide)
      )
      (property "Footprint" "antmicro-footprints:L_Murata_025020_0605Metric" (id 2) (at 31.75 -10.16 0)
        (effects (font (size 1.27 1.27) (thickness 0.15)) (justify left bottom) hide)
      )
      (property "Datasheet" "https://www.farnell.com/datasheets/2616945.pdf" (id 3) (at 31.75 -12.7 0)
        (effects (font (size 1.27 1.27) (thickness 0.15)) (justify left bottom) hide)
      )
      (property "MPN" "NFP0QHB242HS2D" (id 4) (at 31.75 -15.24 0)
        (effects (font (size 1.27 1.27) (thickness 0.15)) (justify left bottom) hide)
      )
      (property "Manufacturer" "Murata" (id 5) (at 31.75 -17.78 0)
        (effects (font (size 1.27 1.27) (thickness 0.15)) (justify left bottom) hide)
      )
      (property "Author" "Antmicro" (id 6) (at 31.75 -20.32 0)
        (effects (font (size 1.27 1.27) (thickness 0.15)) (justify left bottom) hide)
      )
      (property "License" "Apache-2.0" (id 7) (at 31.75 -22.86 0)
        (effects (font (size 1.27 1.27) (thickness 0.15)) (justify left bottom) hide)
      )
      (property "ki_description" "Common mode filter" (id 8) (at 0 0 0)
        (effects (font (size 1.27 1.27)) hide)
      )
      (symbol "NFP0QHB242HS2D_9_1_1"
        (polyline
          (pts
            (xy 2.54 -2.921)
            (xy 12.7 -2.921)
          )
          (stroke (width 0.254) (type default) (color 0 0 0 0))
          (fill (type none))
        )
        (polyline
          (pts
            (xy 12.7 -2.032)
            (xy 2.54 -2.032)
          )
          (stroke (width 0.254) (type default) (color 0 0 0 0))
          (fill (type none))
        )
        (circle (center 1.905 -3.429) (radius 0.2032)
          (stroke (width 0.254) (type default) (color 0 0 0 0))
          (fill (type none))
        )
        (circle (center 1.905 -1.651) (radius 0.2032)
          (stroke (width 0.254) (type default) (color 0 0 0 0))
          (fill (type none))
        )
        (arc (start 2.54 0) (mid 3.81 -1.27) (end 5.08 0)
          (stroke (width 0.254) (type default) (color 0 0 0 0))
          (fill (type none))
        )
        (arc (start 5.08 -5.08) (mid 3.81 -3.81) (end 2.54 -5.08)
          (stroke (width 0.254) (type default) (color 0 0 0 0))
          (fill (type none))
        )
        (arc (start 5.08 0) (mid 6.35 -1.27) (end 7.62 0)
          (stroke (width 0.254) (type default) (color 0 0 0 0))
          (fill (type none))
        )
        (arc (start 7.62 -5.08) (mid 6.35 -3.81) (end 5.08 -5.08)
          (stroke (width 0.254) (type default) (color 0 0 0 0))
          (fill (type none))
        )
        (arc (start 7.62 0) (mid 8.89 -1.27) (end 10.16 0)
          (stroke (width 0.254) (type default) (color 0 0 0 0))
          (fill (type none))
        )
        (arc (start 10.16 -5.08) (mid 8.89 -3.81) (end 7.62 -5.08)
          (stroke (width 0.254) (type default) (color 0 0 0 0))
          (fill (type none))
        )
        (arc (start 10.16 0) (mid 11.43 -1.27) (end 12.7 0)
          (stroke (width 0.254) (type default) (color 0 0 0 0))
          (fill (type none))
        )
        (arc (start 12.7 -5.08) (mid 11.43 -3.81) (end 10.16 -5.08)
          (stroke (width 0.254) (type default) (color 0 0 0 0))
          (fill (type none))
        )
        (pin passive line (at 0 0 0) (length 2.54)
          (name "1" (effects (font (size 1.27 1.27))))
          (number "1" (effects (font (size 1.27 1.27))))
        )
        (pin passive line (at 15.24 0 180) (length 2.54)
          (name "2" (effects (font (size 1.27 1.27))))
          (number "2" (effects (font (size 1.27 1.27))))
        )
        (pin passive line (at 15.24 -5.08 180) (length 2.54)
          (name "3" (effects (font (size 1.27 1.27))))
          (number "3" (effects (font (size 1.27 1.27))))
        )
        (pin passive line (at 0 -5.08 0) (length 2.54)
          (name "4" (effects (font (size 1.27 1.27))))
          (number "4" (effects (font (size 1.27 1.27))))
        )
      )
    )
	(symbol "Si7223DN_1" (pin_names (offset 0)) (in_bom yes) (on_board yes)
      (property "Reference" "Q" (id 0) (at 22.86 5.08 0)
        (effects (font (size 1.27 1.27) (thickness 0.15)) (justify left bottom))
      )
      (property "Value" "Si7223DN_1" (id 1) (at 22.86 0 0)
        (effects (font (size 1.27 1.27) (thickness 0.15)) (justify left bottom) hide)
      )
      (property "Footprint" "antmicro-footprints:PowerPak-1212" (id 2) (at 22.86 -2.54 0)
        (effects (font (size 1.27 1.27) (thickness 0.15)) (justify left bottom) hide)
      )
      (property "Datasheet" "https://www.farnell.com/datasheets/2606257.pdf" (id 3) (at 22.86 -5.08 0)
        (effects (font (size 1.27 1.27) (thickness 0.15)) (justify left bottom) hide)
      )
      (property "MPN" "SI7223DN-T1-GE3" (id 4) (at 22.86 2.54 0)
        (effects (font (size 1.27 1.27) (thickness 0.15)) (justify left bottom))
      )
      (property "Manufacturer" "Vishay" (id 5) (at 22.86 -7.62 0)
        (effects (font (size 1.27 1.27) (thickness 0.15)) (justify left bottom) hide)
      )
      (property "Author" "Antmicro" (id 6) (at 22.86 -10.16 0)
        (effects (font (size 1.27 1.27) (thickness 0.15)) (justify left bottom) hide)
      )
      (property "License" "Apache-2.0" (id 7) (at 22.86 -12.7 0)
        (effects (font (size 1.27 1.27) (thickness 0.15)) (justify left bottom) hide)
      )
      (property "ki_description" "Dual MOSFET, P Channel, 30 V, 6 A, 0.022 ohm, PowerPAK 1212, Surface Mount" (id 8) (at 0 0 0)
        (effects (font (size 1.27 1.27)) hide)
      )
      (symbol "Si7223DN_1_1_1"
        (polyline
          (pts
            (xy 2.54 -8.89)
            (xy 5.08 -8.89)
          )
          (stroke (width 0.254) (type default) (color 0 0 0 0))
          (fill (type background))
        )
        (polyline
          (pts
            (xy 2.54 0)
            (xy 5.08 0)
          )
          (stroke (width 0.254) (type default) (color 0 0 0 0))
          (fill (type background))
        )
        (polyline
          (pts
            (xy 5.08 -5.08)
            (xy 5.08 -10.16)
          )
          (stroke (width 0.254) (type default) (color 0 0 0 0))
          (fill (type background))
        )
        (polyline
          (pts
            (xy 5.08 3.81)
            (xy 5.08 -1.27)
          )
          (stroke (width 0.254) (type default) (color 0 0 0 0))
          (fill (type background))
        )
        (polyline
          (pts
            (xy 5.715 -8.89)
            (xy 5.715 -10.16)
          )
          (stroke (width 0.254) (type default) (color 0 0 0 0))
          (fill (type background))
        )
        (polyline
          (pts
            (xy 5.715 -8.255)
            (xy 5.715 -6.985)
          )
          (stroke (width 0.254) (type default) (color 0 0 0 0))
          (fill (type background))
        )
        (polyline
          (pts
            (xy 5.715 -6.35)
            (xy 5.715 -5.08)
          )
          (stroke (width 0.254) (type default) (color 0 0 0 0))
          (fill (type background))
        )
        (polyline
          (pts
            (xy 5.715 -5.715)
            (xy 8.89 -5.715)
          )
          (stroke (width 0.254) (type default) (color 0 0 0 0))
          (fill (type background))
        )
        (polyline
          (pts
            (xy 5.715 0)
            (xy 5.715 -1.27)
          )
          (stroke (width 0.254) (type default) (color 0 0 0 0))
          (fill (type background))
        )
        (polyline
          (pts
            (xy 5.715 0.635)
            (xy 5.715 1.905)
          )
          (stroke (width 0.254) (type default) (color 0 0 0 0))
          (fill (type background))
        )
        (polyline
          (pts
            (xy 5.715 2.54)
            (xy 5.715 3.81)
          )
          (stroke (width 0.254) (type default) (color 0 0 0 0))
          (fill (type background))
        )
        (polyline
          (pts
            (xy 5.715 3.175)
            (xy 8.89 3.175)
          )
          (stroke (width 0.254) (type default) (color 0 0 0 0))
          (fill (type background))
        )
        (polyline
          (pts
            (xy 7.62 -9.525)
            (xy 8.89 -9.525)
          )
          (stroke (width 0.254) (type default) (color 0 0 0 0))
          (fill (type background))
        )
        (polyline
          (pts
            (xy 7.62 -0.635)
            (xy 8.89 -0.635)
          )
          (stroke (width 0.254) (type default) (color 0 0 0 0))
          (fill (type background))
        )
        (polyline
          (pts
            (xy 8.255 -8.255)
            (xy 9.525 -8.255)
          )
          (stroke (width 0.254) (type default) (color 0 0 0 0))
          (fill (type background))
        )
        (polyline
          (pts
            (xy 8.255 0.635)
            (xy 9.525 0.635)
          )
          (stroke (width 0.254) (type default) (color 0 0 0 0))
          (fill (type background))
        )
        (polyline
          (pts
            (xy 8.89 -10.16)
            (xy 11.43 -10.16)
          )
          (stroke (width 0.254) (type default) (color 0 0 0 0))
          (fill (type background))
        )
        (polyline
          (pts
            (xy 8.89 -8.89)
            (xy 8.89 -10.16)
          )
          (stroke (width 0.254) (type default) (color 0 0 0 0))
          (fill (type background))
        )
        (polyline
          (pts
            (xy 8.89 -8.89)
            (xy 8.89 -5.08)
          )
          (stroke (width 0.254) (type default) (color 0 0 0 0))
          (fill (type background))
        )
        (polyline
          (pts
            (xy 8.89 -5.08)
            (xy 11.43 -5.08)
          )
          (stroke (width 0.254) (type default) (color 0 0 0 0))
          (fill (type background))
        )
        (polyline
          (pts
            (xy 8.89 -1.27)
            (xy 11.43 -1.27)
          )
          (stroke (width 0.254) (type default) (color 0 0 0 0))
          (fill (type background))
        )
        (polyline
          (pts
            (xy 8.89 0)
            (xy 8.89 -1.27)
          )
          (stroke (width 0.254) (type default) (color 0 0 0 0))
          (fill (type background))
        )
        (polyline
          (pts
            (xy 8.89 0)
            (xy 8.89 3.81)
          )
          (stroke (width 0.254) (type default) (color 0 0 0 0))
          (fill (type background))
        )
        (polyline
          (pts
            (xy 8.89 3.81)
            (xy 11.43 3.81)
          )
          (stroke (width 0.254) (type default) (color 0 0 0 0))
          (fill (type background))
        )
        (polyline
          (pts
            (xy 6.35 -6.985)
            (xy 7.62 -7.62)
            (xy 6.35 -8.255)
            (xy 6.35 -6.985)
          )
          (stroke (width 0.254) (type default) (color 0 0 0 0))
          (fill (type outline))
        )
        (polyline
          (pts
            (xy 6.35 1.905)
            (xy 7.62 1.27)
            (xy 6.35 0.635)
            (xy 6.35 1.905)
          )
          (stroke (width 0.254) (type default) (color 0 0 0 0))
          (fill (type outline))
        )
        (polyline
          (pts
            (xy 6.985 -7.62)
            (xy 7.62 -7.62)
            (xy 7.62 -9.525)
            (xy 5.715 -9.525)
          )
          (stroke (width 0.254) (type default) (color 0 0 0 0))
          (fill (type background))
        )
        (polyline
          (pts
            (xy 6.985 1.27)
            (xy 7.62 1.27)
            (xy 7.62 -0.635)
            (xy 5.715 -0.635)
          )
          (stroke (width 0.254) (type default) (color 0 0 0 0))
          (fill (type background))
        )
        (polyline
          (pts
            (xy 9.525 -6.985)
            (xy 8.89 -8.255)
            (xy 8.255 -6.985)
            (xy 9.525 -6.985)
          )
          (stroke (width 0.254) (type default) (color 0 0 0 0))
          (fill (type outline))
        )
        (polyline
          (pts
            (xy 9.525 1.905)
            (xy 8.89 0.635)
            (xy 8.255 1.905)
            (xy 9.525 1.905)
          )
          (stroke (width 0.254) (type default) (color 0 0 0 0))
          (fill (type outline))
        )
        (rectangle (start 2.54 6.35) (end 11.43 -12.7)
          (stroke (width 0.254) (type default) (color 0 0 0 0))
          (fill (type background))
        )
        (pin passive line (at 13.97 -1.27 180) (length 2.54)
          (name "S1" (effects (font (size 1.27 1.27))))
          (number "1" (effects (font (size 1.27 1.27))))
        )
        (pin passive line (at 0 0 0) (length 2.54)
          (name "G1" (effects (font (size 1.27 1.27))))
          (number "2" (effects (font (size 1.27 1.27))))
        )
        (pin passive line (at 13.97 -10.16 180) (length 2.54)
          (name "S2" (effects (font (size 1.27 1.27))))
          (number "3" (effects (font (size 1.27 1.27))))
        )
        (pin passive line (at 0 -8.89 0) (length 2.54)
          (name "G2" (effects (font (size 1.27 1.27))))
          (number "4" (effects (font (size 1.27 1.27))))
        )
        (pin passive line (at 13.97 -5.08 180) (length 2.54)
          (name "D2" (effects (font (size 1.27 1.27))))
          (number "5" (effects (font (size 1.27 1.27))))
        )
        (pin passive line (at 13.97 -5.08 180) (length 2.54) hide
          (name "D2" (effects (font (size 1.27 1.27))))
          (number "6" (effects (font (size 1.27 1.27))))
        )
        (pin passive line (at 13.97 3.81 180) (length 2.54)
          (name "D1" (effects (font (size 1.27 1.27))))
          (number "7" (effects (font (size 1.27 1.27))))
        )
        (pin passive line (at 13.97 3.81 180) (length 2.54) hide
          (name "D1" (effects (font (size 1.27 1.27))))
          (number "8" (effects (font (size 1.27 1.27))))
        )
      )
    )
	(symbol "Si7223DN_2" (pin_names (offset 0)) (in_bom yes) (on_board yes)
      (property "Reference" "Q" (id 0) (at 22.86 5.08 0)
        (effects (font (size 1.27 1.27) (thickness 0.15)) (justify left bottom))
      )
      (property "Value" "Si7223DN_2" (id 1) (at 22.86 0 0)
        (effects (font (size 1.27 1.27) (thickness 0.15)) (justify left bottom) hide)
      )
      (property "Footprint" "antmicro-footprints:PowerPak-1212" (id 2) (at 22.86 -2.54 0)
        (effects (font (size 1.27 1.27) (thickness 0.15)) (justify left bottom) hide)
      )
      (property "Datasheet" "https://www.farnell.com/datasheets/2606257.pdf" (id 3) (at 22.86 -5.08 0)
        (effects (font (size 1.27 1.27) (thickness 0.15)) (justify left bottom) hide)
      )
      (property "MPN" "SI7223DN-T1-GE3" (id 4) (at 22.86 2.54 0)
        (effects (font (size 1.27 1.27) (thickness 0.15)) (justify left bottom))
      )
      (property "Manufacturer" "Vishay" (id 5) (at 22.86 -7.62 0)
        (effects (font (size 1.27 1.27) (thickness 0.15)) (justify left bottom) hide)
      )
      (property "Author" "Antmicro" (id 6) (at 22.86 -10.16 0)
        (effects (font (size 1.27 1.27) (thickness 0.15)) (justify left bottom) hide)
      )
      (property "License" "Apache-2.0" (id 7) (at 22.86 -12.7 0)
        (effects (font (size 1.27 1.27) (thickness 0.15)) (justify left bottom) hide)
      )
      (property "ki_description" "Dual MOSFET, P Channel, 30 V, 6 A, 0.022 ohm, PowerPAK 1212, Surface Mount" (id 8) (at 0 0 0)
        (effects (font (size 1.27 1.27)) hide)
      )
      (symbol "Si7223DN_2_1_1"
        (polyline
          (pts
            (xy 2.54 -8.89)
            (xy 5.08 -8.89)
          )
          (stroke (width 0.254) (type default) (color 0 0 0 0))
          (fill (type background))
        )
        (polyline
          (pts
            (xy 2.54 0)
            (xy 5.08 0)
          )
          (stroke (width 0.254) (type default) (color 0 0 0 0))
          (fill (type background))
        )
        (polyline
          (pts
            (xy 5.08 -5.08)
            (xy 5.08 -10.16)
          )
          (stroke (width 0.254) (type default) (color 0 0 0 0))
          (fill (type background))
        )
        (polyline
          (pts
            (xy 5.08 3.81)
            (xy 5.08 -1.27)
          )
          (stroke (width 0.254) (type default) (color 0 0 0 0))
          (fill (type background))
        )
        (polyline
          (pts
            (xy 5.715 -8.89)
            (xy 5.715 -10.16)
          )
          (stroke (width 0.254) (type default) (color 0 0 0 0))
          (fill (type background))
        )
        (polyline
          (pts
            (xy 5.715 -8.255)
            (xy 5.715 -6.985)
          )
          (stroke (width 0.254) (type default) (color 0 0 0 0))
          (fill (type background))
        )
        (polyline
          (pts
            (xy 5.715 -6.35)
            (xy 5.715 -5.08)
          )
          (stroke (width 0.254) (type default) (color 0 0 0 0))
          (fill (type background))
        )
        (polyline
          (pts
            (xy 5.715 -5.715)
            (xy 8.89 -5.715)
          )
          (stroke (width 0.254) (type default) (color 0 0 0 0))
          (fill (type background))
        )
        (polyline
          (pts
            (xy 5.715 0)
            (xy 5.715 -1.27)
          )
          (stroke (width 0.254) (type default) (color 0 0 0 0))
          (fill (type background))
        )
        (polyline
          (pts
            (xy 5.715 0.635)
            (xy 5.715 1.905)
          )
          (stroke (width 0.254) (type default) (color 0 0 0 0))
          (fill (type background))
        )
        (polyline
          (pts
            (xy 5.715 2.54)
            (xy 5.715 3.81)
          )
          (stroke (width 0.254) (type default) (color 0 0 0 0))
          (fill (type background))
        )
        (polyline
          (pts
            (xy 5.715 3.175)
            (xy 8.89 3.175)
          )
          (stroke (width 0.254) (type default) (color 0 0 0 0))
          (fill (type background))
        )
        (polyline
          (pts
            (xy 7.62 -9.525)
            (xy 8.89 -9.525)
          )
          (stroke (width 0.254) (type default) (color 0 0 0 0))
          (fill (type background))
        )
        (polyline
          (pts
            (xy 7.62 -0.635)
            (xy 8.89 -0.635)
          )
          (stroke (width 0.254) (type default) (color 0 0 0 0))
          (fill (type background))
        )
        (polyline
          (pts
            (xy 8.255 -8.255)
            (xy 9.525 -8.255)
          )
          (stroke (width 0.254) (type default) (color 0 0 0 0))
          (fill (type background))
        )
        (polyline
          (pts
            (xy 8.255 0.635)
            (xy 9.525 0.635)
          )
          (stroke (width 0.254) (type default) (color 0 0 0 0))
          (fill (type background))
        )
        (polyline
          (pts
            (xy 8.89 -10.16)
            (xy 11.43 -10.16)
          )
          (stroke (width 0.254) (type default) (color 0 0 0 0))
          (fill (type background))
        )
        (polyline
          (pts
            (xy 8.89 -8.89)
            (xy 8.89 -10.16)
          )
          (stroke (width 0.254) (type default) (color 0 0 0 0))
          (fill (type background))
        )
        (polyline
          (pts
            (xy 8.89 -8.89)
            (xy 8.89 -5.08)
          )
          (stroke (width 0.254) (type default) (color 0 0 0 0))
          (fill (type background))
        )
        (polyline
          (pts
            (xy 8.89 -5.08)
            (xy 11.43 -5.08)
          )
          (stroke (width 0.254) (type default) (color 0 0 0 0))
          (fill (type background))
        )
        (polyline
          (pts
            (xy 8.89 -1.27)
            (xy 11.43 -1.27)
          )
          (stroke (width 0.254) (type default) (color 0 0 0 0))
          (fill (type background))
        )
        (polyline
          (pts
            (xy 8.89 0)
            (xy 8.89 -1.27)
          )
          (stroke (width 0.254) (type default) (color 0 0 0 0))
          (fill (type background))
        )
        (polyline
          (pts
            (xy 8.89 0)
            (xy 8.89 3.81)
          )
          (stroke (width 0.254) (type default) (color 0 0 0 0))
          (fill (type background))
        )
        (polyline
          (pts
            (xy 8.89 3.81)
            (xy 11.43 3.81)
          )
          (stroke (width 0.254) (type default) (color 0 0 0 0))
          (fill (type background))
        )
        (polyline
          (pts
            (xy 6.35 -6.985)
            (xy 7.62 -7.62)
            (xy 6.35 -8.255)
            (xy 6.35 -6.985)
          )
          (stroke (width 0.254) (type default) (color 0 0 0 0))
          (fill (type outline))
        )
        (polyline
          (pts
            (xy 6.35 1.905)
            (xy 7.62 1.27)
            (xy 6.35 0.635)
            (xy 6.35 1.905)
          )
          (stroke (width 0.254) (type default) (color 0 0 0 0))
          (fill (type outline))
        )
        (polyline
          (pts
            (xy 6.985 -7.62)
            (xy 7.62 -7.62)
            (xy 7.62 -9.525)
            (xy 5.715 -9.525)
          )
          (stroke (width 0.254) (type default) (color 0 0 0 0))
          (fill (type background))
        )
        (polyline
          (pts
            (xy 6.985 1.27)
            (xy 7.62 1.27)
            (xy 7.62 -0.635)
            (xy 5.715 -0.635)
          )
          (stroke (width 0.254) (type default) (color 0 0 0 0))
          (fill (type background))
        )
        (polyline
          (pts
            (xy 9.525 -6.985)
            (xy 8.89 -8.255)
            (xy 8.255 -6.985)
            (xy 9.525 -6.985)
          )
          (stroke (width 0.254) (type default) (color 0 0 0 0))
          (fill (type outline))
        )
        (polyline
          (pts
            (xy 9.525 1.905)
            (xy 8.89 0.635)
            (xy 8.255 1.905)
            (xy 9.525 1.905)
          )
          (stroke (width 0.254) (type default) (color 0 0 0 0))
          (fill (type outline))
        )
        (rectangle (start 2.54 6.35) (end 11.43 -12.7)
          (stroke (width 0.254) (type default) (color 0 0 0 0))
          (fill (type background))
        )
        (pin passive line (at 13.97 -1.27 180) (length 2.54)
          (name "S1" (effects (font (size 1.27 1.27))))
          (number "1" (effects (font (size 1.27 1.27))))
        )
        (pin passive line (at 0 0 0) (length 2.54)
          (name "G1" (effects (font (size 1.27 1.27))))
          (number "2" (effects (font (size 1.27 1.27))))
        )
        (pin passive line (at 13.97 -10.16 180) (length 2.54)
          (name "S2" (effects (font (size 1.27 1.27))))
          (number "3" (effects (font (size 1.27 1.27))))
        )
        (pin passive line (at 0 -8.89 0) (length 2.54)
          (name "G2" (effects (font (size 1.27 1.27))))
          (number "4" (effects (font (size 1.27 1.27))))
        )
        (pin passive line (at 13.97 -5.08 180) (length 2.54)
          (name "D2" (effects (font (size 1.27 1.27))))
          (number "5" (effects (font (size 1.27 1.27))))
        )
        (pin passive line (at 13.97 -5.08 180) (length 2.54) hide
          (name "D2" (effects (font (size 1.27 1.27))))
          (number "6" (effects (font (size 1.27 1.27))))
        )
        (pin passive line (at 13.97 3.81 180) (length 2.54)
          (name "D1" (effects (font (size 1.27 1.27))))
          (number "7" (effects (font (size 1.27 1.27))))
        )
        (pin passive line (at 13.97 3.81 180) (length 2.54) hide
          (name "D1" (effects (font (size 1.27 1.27))))
          (number "8" (effects (font (size 1.27 1.27))))
        )
      )
    )
	(symbol "Spacer_H6mm_9774060151_1" (in_bom yes) (on_board yes)
      (property "Reference" "H" (id 0) (at 22.86 -2.54 0)
        (effects (font (size 1.27 1.27) (thickness 0.15)) (justify left bottom))
      )
      (property "Value" "Spacer_H6mm_9774060151_1" (id 1) (at 22.86 -5.08 0)
        (effects (font (size 1.27 1.27) (thickness 0.15)) (justify left bottom))
      )
      (property "Footprint" "antmicro-footprints:Spacer_SMD_M2.5_H6mm_Wurth_9774060151" (id 2) (at 22.86 -7.62 0)
        (effects (font (size 1.27 1.27) (thickness 0.15)) (justify left bottom) hide)
      )
      (property "Datasheet" "https://www.we-online.com/catalog/datasheet/9774060151.pdf" (id 3) (at 22.86 -10.16 0)
        (effects (font (size 1.27 1.27) (thickness 0.15)) (justify left bottom) hide)
      )
      (property "Manufacturer" "Würth Elektronik" (id 4) (at 22.86 -12.7 0)
        (effects (font (size 1.27 1.27) (thickness 0.15)) (justify left bottom) hide)
      )
      (property "MPN" "9774060151" (id 5) (at 22.86 -15.24 0)
        (effects (font (size 1.27 1.27) (thickness 0.15)) (justify left bottom) hide)
      )
      (property "Author" "Antmicro" (id 6) (at 22.86 -17.78 0)
        (effects (font (size 1.27 1.27) (thickness 0.15)) (justify left bottom) hide)
      )
      (property "License" "Apache-2.0" (id 7) (at 22.86 -20.32 0)
        (effects (font (size 1.27 1.27) (thickness 0.15)) (justify left bottom) hide)
      )
      (property "ki_keywords" "Standoffs & Spacers" (id 8) (at 0 0 0)
        (effects (font (size 1.27 1.27)) hide)
      )
      (property "ki_description" "Standoffs & Spacers" (id 9) (at 0 0 0)
        (effects (font (size 1.27 1.27)) hide)
      )
      (symbol "Spacer_H6mm_9774060151_1_1_1"
        (rectangle (start 2.54 -2.54) (end 7.62 2.54)
          (stroke (width 0.254) (type default) (color 0 0 0 0))
          (fill (type background))
        )
        (rectangle (start 3.81 -1.27) (end 6.35 1.27)
          (stroke (width 0.254) (type default) (color 0 0 0 0))
          (fill (type background))
        )
        (pin passive line (at 0 0 0) (length 2.54)
          (name "~" (effects (font (size 1.27 1.27))))
          (number "1" (effects (font (size 1.27 1.27))))
        )
      )
    )
	(symbol "Spacer_H6mm_9774060151_2" (in_bom yes) (on_board yes)
      (property "Reference" "H" (id 0) (at 22.86 -2.54 0)
        (effects (font (size 1.27 1.27) (thickness 0.15)) (justify left bottom))
      )
      (property "Value" "Spacer_H6mm_9774060151_2" (id 1) (at 22.86 -5.08 0)
        (effects (font (size 1.27 1.27) (thickness 0.15)) (justify left bottom))
      )
      (property "Footprint" "antmicro-footprints:Spacer_SMD_M2.5_H6mm_Wurth_9774060151" (id 2) (at 22.86 -7.62 0)
        (effects (font (size 1.27 1.27) (thickness 0.15)) (justify left bottom) hide)
      )
      (property "Datasheet" "https://www.we-online.com/catalog/datasheet/9774060151.pdf" (id 3) (at 22.86 -10.16 0)
        (effects (font (size 1.27 1.27) (thickness 0.15)) (justify left bottom) hide)
      )
      (property "Manufacturer" "Würth Elektronik" (id 4) (at 22.86 -12.7 0)
        (effects (font (size 1.27 1.27) (thickness 0.15)) (justify left bottom) hide)
      )
      (property "MPN" "9774060151" (id 5) (at 22.86 -15.24 0)
        (effects (font (size 1.27 1.27) (thickness 0.15)) (justify left bottom) hide)
      )
      (property "Author" "Antmicro" (id 6) (at 22.86 -17.78 0)
        (effects (font (size 1.27 1.27) (thickness 0.15)) (justify left bottom) hide)
      )
      (property "License" "Apache-2.0" (id 7) (at 22.86 -20.32 0)
        (effects (font (size 1.27 1.27) (thickness 0.15)) (justify left bottom) hide)
      )
      (property "ki_keywords" "Standoffs & Spacers" (id 8) (at 0 0 0)
        (effects (font (size 1.27 1.27)) hide)
      )
      (property "ki_description" "Standoffs & Spacers" (id 9) (at 0 0 0)
        (effects (font (size 1.27 1.27)) hide)
      )
      (symbol "Spacer_H6mm_9774060151_2_1_1"
        (rectangle (start 2.54 -2.54) (end 7.62 2.54)
          (stroke (width 0.254) (type default) (color 0 0 0 0))
          (fill (type background))
        )
        (rectangle (start 3.81 -1.27) (end 6.35 1.27)
          (stroke (width 0.254) (type default) (color 0 0 0 0))
          (fill (type background))
        )
        (pin passive line (at 0 0 0) (length 2.54)
          (name "~" (effects (font (size 1.27 1.27))))
          (number "1" (effects (font (size 1.27 1.27))))
        )
      )
    )
	(symbol "Spacer_H6mm_9774060151_3" (in_bom yes) (on_board yes)
      (property "Reference" "H" (id 0) (at 22.86 -2.54 0)
        (effects (font (size 1.27 1.27) (thickness 0.15)) (justify left bottom))
      )
      (property "Value" "Spacer_H6mm_9774060151_3" (id 1) (at 22.86 -5.08 0)
        (effects (font (size 1.27 1.27) (thickness 0.15)) (justify left bottom))
      )
      (property "Footprint" "antmicro-footprints:Spacer_SMD_M2.5_H6mm_Wurth_9774060151" (id 2) (at 22.86 -7.62 0)
        (effects (font (size 1.27 1.27) (thickness 0.15)) (justify left bottom) hide)
      )
      (property "Datasheet" "https://www.we-online.com/catalog/datasheet/9774060151.pdf" (id 3) (at 22.86 -10.16 0)
        (effects (font (size 1.27 1.27) (thickness 0.15)) (justify left bottom) hide)
      )
      (property "Manufacturer" "Würth Elektronik" (id 4) (at 22.86 -12.7 0)
        (effects (font (size 1.27 1.27) (thickness 0.15)) (justify left bottom) hide)
      )
      (property "MPN" "9774060151" (id 5) (at 22.86 -15.24 0)
        (effects (font (size 1.27 1.27) (thickness 0.15)) (justify left bottom) hide)
      )
      (property "Author" "Antmicro" (id 6) (at 22.86 -17.78 0)
        (effects (font (size 1.27 1.27) (thickness 0.15)) (justify left bottom) hide)
      )
      (property "License" "Apache-2.0" (id 7) (at 22.86 -20.32 0)
        (effects (font (size 1.27 1.27) (thickness 0.15)) (justify left bottom) hide)
      )
      (property "ki_keywords" "Standoffs & Spacers" (id 8) (at 0 0 0)
        (effects (font (size 1.27 1.27)) hide)
      )
      (property "ki_description" "Standoffs & Spacers" (id 9) (at 0 0 0)
        (effects (font (size 1.27 1.27)) hide)
      )
      (symbol "Spacer_H6mm_9774060151_3_1_1"
        (rectangle (start 2.54 -2.54) (end 7.62 2.54)
          (stroke (width 0.254) (type default) (color 0 0 0 0))
          (fill (type background))
        )
        (rectangle (start 3.81 -1.27) (end 6.35 1.27)
          (stroke (width 0.254) (type default) (color 0 0 0 0))
          (fill (type background))
        )
        (pin passive line (at 0 0 0) (length 2.54)
          (name "~" (effects (font (size 1.27 1.27))))
          (number "1" (effects (font (size 1.27 1.27))))
        )
      )
    )
	(symbol "sa800u-baseboard-hw:12401598E4_2A" (in_bom yes) (on_board yes)
      (property "Reference" "J" (id 0) (at 33.02 -2.54 0)
        (effects (font (size 1.27 1.27) (thickness 0.15)) (justify left bottom))
      )
      (property "Value" "12401598E4_2A" (id 1) (at 33.02 -7.62 0)
        (effects (font (size 1.27 1.27) (thickness 0.15)) (justify left bottom) hide)
      )
      (property "Footprint" "antmicro-footprints:USB-C_12401610E4_2A" (id 2) (at 33.02 -10.16 0)
        (effects (font (size 1.27 1.27) (thickness 0.15)) (justify left bottom) hide)
      )
      (property "Datasheet" "http://www.amphenol-icc.com/media/wysiwyg/files/drawing/12401598xxx2a.pdf" (id 3) (at 33.02 -12.7 0)
        (effects (font (size 1.27 1.27) (thickness 0.15)) (justify left bottom) hide)
      )
      (property "MPN" "12401598E4#2A" (id 4) (at 33.02 -5.08 0)
        (effects (font (size 1.27 1.27) (thickness 0.15)) (justify left bottom))
      )
      (property "Manufacturer" "Amphenol" (id 5) (at 33.02 -15.24 0)
        (effects (font (size 1.27 1.27) (thickness 0.15)) (justify left bottom) hide)
      )
      (property "Author" "Antmicro" (id 6) (at 33.02 -17.78 0)
        (effects (font (size 1.27 1.27) (thickness 0.15)) (justify left bottom) hide)
      )
      (property "License" "Apache-2.0" (id 7) (at 33.02 -20.32 0)
        (effects (font (size 1.27 1.27) (thickness 0.15)) (justify left bottom) hide)
      )
      (symbol "12401598E4_2A_1_1"
        (polyline
          (pts
            (xy 4.445 -14.605)
            (xy 4.445 -13.462)
          )
          (stroke (width 0) (type default) (color 0 0 0 0))
          (fill (type none))
        )
        (polyline
          (pts
            (xy 4.953 -29.083)
            (xy 9.398 -29.083)
          )
          (stroke (width 0) (type default) (color 0 0 0 0))
          (fill (type none))
        )
        (polyline
          (pts
            (xy 4.953 -26.162)
            (xy 4.953 -14.097)
          )
          (stroke (width 0) (type default) (color 0 0 0 0))
          (fill (type none))
        )
        (polyline
          (pts
            (xy 4.953 -14.605)
            (xy 4.953 -13.462)
          )
          (stroke (width 0) (type default) (color 0 0 0 0))
          (fill (type none))
        )
        (polyline
          (pts
            (xy 4.953 -2.032)
            (xy 4.953 -14.097)
          )
          (stroke (width 0) (type default) (color 0 0 0 0))
          (fill (type none))
        )
        (polyline
          (pts
            (xy 4.953 0.889)
            (xy 9.398 0.889)
          )
          (stroke (width 0) (type default) (color 0 0 0 0))
          (fill (type none))
        )
        (polyline
          (pts
            (xy 5.461 -25.527)
            (xy 5.461 -25.019)
          )
          (stroke (width 0) (type default) (color 0 0 0 0))
          (fill (type none))
        )
        (polyline
          (pts
            (xy 5.461 -20.447)
            (xy 5.461 -20.955)
          )
          (stroke (width 0) (type default) (color 0 0 0 0))
          (fill (type none))
        )
        (polyline
          (pts
            (xy 5.461 -7.747)
            (xy 5.461 -7.239)
          )
          (stroke (width 0) (type default) (color 0 0 0 0))
          (fill (type none))
        )
        (polyline
          (pts
            (xy 5.461 -2.667)
            (xy 5.461 -3.175)
          )
          (stroke (width 0) (type default) (color 0 0 0 0))
          (fill (type none))
        )
        (polyline
          (pts
            (xy 5.715 -28.575)
            (xy 5.715 -25.527)
          )
          (stroke (width 0) (type default) (color 0 0 0 0))
          (fill (type none))
        )
        (polyline
          (pts
            (xy 5.715 -20.447)
            (xy 5.715 -14.097)
          )
          (stroke (width 0) (type default) (color 0 0 0 0))
          (fill (type none))
        )
        (polyline
          (pts
            (xy 5.715 -14.605)
            (xy 5.715 -13.462)
          )
          (stroke (width 0) (type default) (color 0 0 0 0))
          (fill (type none))
        )
        (polyline
          (pts
            (xy 5.715 -7.747)
            (xy 5.715 -14.097)
          )
          (stroke (width 0) (type default) (color 0 0 0 0))
          (fill (type none))
        )
        (polyline
          (pts
            (xy 5.715 0.381)
            (xy 5.715 -2.667)
          )
          (stroke (width 0) (type default) (color 0 0 0 0))
          (fill (type none))
        )
        (polyline
          (pts
            (xy 5.969 -25.527)
            (xy 5.969 -25.146)
          )
          (stroke (width 0) (type default) (color 0 0 0 0))
          (fill (type none))
        )
        (polyline
          (pts
            (xy 5.969 -20.701)
            (xy 5.969 -20.828)
          )
          (stroke (width 0) (type default) (color 0 0 0 0))
          (fill (type none))
        )
        (polyline
          (pts
            (xy 5.969 -20.447)
            (xy 5.969 -20.701)
          )
          (stroke (width 0) (type default) (color 0 0 0 0))
          (fill (type none))
        )
        (polyline
          (pts
            (xy 5.969 -7.747)
            (xy 5.969 -7.493)
          )
          (stroke (width 0) (type default) (color 0 0 0 0))
          (fill (type none))
        )
        (polyline
          (pts
            (xy 5.969 -7.493)
            (xy 5.969 -7.366)
          )
          (stroke (width 0) (type default) (color 0 0 0 0))
          (fill (type none))
        )
        (polyline
          (pts
            (xy 5.969 -2.667)
            (xy 5.969 -3.048)
          )
          (stroke (width 0) (type default) (color 0 0 0 0))
          (fill (type none))
        )
        (polyline
          (pts
            (xy 8.001 -14.605)
            (xy 8.001 -13.462)
          )
          (stroke (width 0) (type default) (color 0 0 0 0))
          (fill (type none))
        )
        (polyline
          (pts
            (xy 8.001 -14.097)
            (xy 8.001 -26.035)
          )
          (stroke (width 0) (type default) (color 0 0 0 0))
          (fill (type none))
        )
        (polyline
          (pts
            (xy 8.001 -14.097)
            (xy 8.001 -2.159)
          )
          (stroke (width 0) (type default) (color 0 0 0 0))
          (fill (type none))
        )
        (polyline
          (pts
            (xy 8.509 -14.605)
            (xy 8.509 -13.462)
          )
          (stroke (width 0) (type default) (color 0 0 0 0))
          (fill (type none))
        )
        (polyline
          (pts
            (xy 8.509 -14.097)
            (xy 8.509 -28.575)
          )
          (stroke (width 0) (type default) (color 0 0 0 0))
          (fill (type none))
        )
        (polyline
          (pts
            (xy 8.509 -14.097)
            (xy 8.509 0.381)
          )
          (stroke (width 0) (type default) (color 0 0 0 0))
          (fill (type none))
        )
        (polyline
          (pts
            (xy 8.763 -28.575)
            (xy 8.763 -14.097)
          )
          (stroke (width 0) (type default) (color 0 0 0 0))
          (fill (type none))
        )
        (polyline
          (pts
            (xy 8.763 -14.605)
            (xy 8.763 -13.462)
          )
          (stroke (width 0) (type default) (color 0 0 0 0))
          (fill (type none))
        )
        (polyline
          (pts
            (xy 8.763 0.381)
            (xy 8.763 -14.097)
          )
          (stroke (width 0) (type default) (color 0 0 0 0))
          (fill (type none))
        )
        (polyline
          (pts
            (xy 9.398 -28.575)
            (xy 4.953 -28.575)
          )
          (stroke (width 0) (type default) (color 0 0 0 0))
          (fill (type none))
        )
        (polyline
          (pts
            (xy 9.398 -14.605)
            (xy 9.398 -13.462)
          )
          (stroke (width 0) (type default) (color 0 0 0 0))
          (fill (type none))
        )
        (polyline
          (pts
            (xy 9.398 -14.097)
            (xy 9.398 -28.702)
          )
          (stroke (width 0) (type default) (color 0 0 0 0))
          (fill (type none))
        )
        (polyline
          (pts
            (xy 9.398 -14.097)
            (xy 9.398 0.508)
          )
          (stroke (width 0) (type default) (color 0 0 0 0))
          (fill (type none))
        )
        (polyline
          (pts
            (xy 9.398 0.381)
            (xy 4.953 0.381)
          )
          (stroke (width 0) (type default) (color 0 0 0 0))
          (fill (type none))
        )
        (polyline
          (pts
            (xy 9.525 -35.687)
            (xy 11.303 -35.687)
          )
          (stroke (width 0) (type default) (color 0 0 0 0))
          (fill (type background))
        )
        (polyline
          (pts
            (xy 9.525 -35.179)
            (xy 9.525 -35.56)
          )
          (stroke (width 0) (type default) (color 0 0 0 0))
          (fill (type none))
        )
        (polyline
          (pts
            (xy 9.525 -35.179)
            (xy 11.303 -35.179)
          )
          (stroke (width 0) (type default) (color 0 0 0 0))
          (fill (type none))
        )
        (polyline
          (pts
            (xy 9.525 6.985)
            (xy 9.525 7.366)
          )
          (stroke (width 0) (type default) (color 0 0 0 0))
          (fill (type none))
        )
        (polyline
          (pts
            (xy 9.525 6.985)
            (xy 11.303 6.985)
          )
          (stroke (width 0) (type default) (color 0 0 0 0))
          (fill (type none))
        )
        (polyline
          (pts
            (xy 9.525 7.493)
            (xy 11.303 7.493)
          )
          (stroke (width 0) (type default) (color 0 0 0 0))
          (fill (type background))
        )
        (polyline
          (pts
            (xy 9.779 -34.798)
            (xy 9.779 -35.179)
          )
          (stroke (width 0) (type default) (color 0 0 0 0))
          (fill (type none))
        )
        (polyline
          (pts
            (xy 9.779 -34.671)
            (xy 11.303 -34.671)
          )
          (stroke (width 0) (type default) (color 0 0 0 0))
          (fill (type none))
        )
        (polyline
          (pts
            (xy 9.779 -14.605)
            (xy 9.779 -13.462)
          )
          (stroke (width 0) (type default) (color 0 0 0 0))
          (fill (type none))
        )
        (polyline
          (pts
            (xy 9.779 6.477)
            (xy 11.303 6.477)
          )
          (stroke (width 0) (type default) (color 0 0 0 0))
          (fill (type none))
        )
        (polyline
          (pts
            (xy 9.779 6.604)
            (xy 9.779 6.985)
          )
          (stroke (width 0) (type default) (color 0 0 0 0))
          (fill (type none))
        )
        (polyline
          (pts
            (xy 10.287 -29.083)
            (xy 9.779 -29.591)
          )
          (stroke (width 0) (type default) (color 0 0 0 0))
          (fill (type none))
        )
        (polyline
          (pts
            (xy 10.287 -14.605)
            (xy 10.287 -13.462)
          )
          (stroke (width 0) (type default) (color 0 0 0 0))
          (fill (type none))
        )
        (polyline
          (pts
            (xy 10.287 0.889)
            (xy 9.779 1.397)
          )
          (stroke (width 0) (type default) (color 0 0 0 0))
          (fill (type none))
        )
        (polyline
          (pts
            (xy 11.303 -30.861)
            (xy 9.779 -30.861)
          )
          (stroke (width 0) (type default) (color 0 0 0 0))
          (fill (type none))
        )
        (polyline
          (pts
            (xy 11.303 -30.861)
            (xy 12.827 -30.861)
          )
          (stroke (width 0) (type default) (color 0 0 0 0))
          (fill (type none))
        )
        (polyline
          (pts
            (xy 11.303 2.667)
            (xy 9.779 2.667)
          )
          (stroke (width 0) (type default) (color 0 0 0 0))
          (fill (type none))
        )
        (polyline
          (pts
            (xy 11.303 2.667)
            (xy 12.827 2.667)
          )
          (stroke (width 0) (type default) (color 0 0 0 0))
          (fill (type none))
        )
        (polyline
          (pts
            (xy 12.319 -29.083)
            (xy 12.827 -29.591)
          )
          (stroke (width 0) (type default) (color 0 0 0 0))
          (fill (type none))
        )
        (polyline
          (pts
            (xy 12.319 -14.605)
            (xy 12.319 -13.462)
          )
          (stroke (width 0) (type default) (color 0 0 0 0))
          (fill (type none))
        )
        (polyline
          (pts
            (xy 12.319 0.889)
            (xy 12.827 1.397)
          )
          (stroke (width 0) (type default) (color 0 0 0 0))
          (fill (type none))
        )
        (polyline
          (pts
            (xy 12.827 -34.798)
            (xy 12.827 -35.179)
          )
          (stroke (width 0) (type default) (color 0 0 0 0))
          (fill (type none))
        )
        (polyline
          (pts
            (xy 12.827 -34.671)
            (xy 11.303 -34.671)
          )
          (stroke (width 0) (type default) (color 0 0 0 0))
          (fill (type none))
        )
        (polyline
          (pts
            (xy 12.827 -14.605)
            (xy 12.827 -13.462)
          )
          (stroke (width 0) (type default) (color 0 0 0 0))
          (fill (type none))
        )
        (polyline
          (pts
            (xy 12.827 6.477)
            (xy 11.303 6.477)
          )
          (stroke (width 0) (type default) (color 0 0 0 0))
          (fill (type none))
        )
        (polyline
          (pts
            (xy 12.827 6.604)
            (xy 12.827 6.985)
          )
          (stroke (width 0) (type default) (color 0 0 0 0))
          (fill (type none))
        )
        (polyline
          (pts
            (xy 13.081 -35.687)
            (xy 11.303 -35.687)
          )
          (stroke (width 0) (type default) (color 0 0 0 0))
          (fill (type background))
        )
        (polyline
          (pts
            (xy 13.081 -35.179)
            (xy 11.303 -35.179)
          )
          (stroke (width 0) (type default) (color 0 0 0 0))
          (fill (type none))
        )
        (polyline
          (pts
            (xy 13.081 -35.179)
            (xy 13.081 -35.56)
          )
          (stroke (width 0) (type default) (color 0 0 0 0))
          (fill (type none))
        )
        (polyline
          (pts
            (xy 13.081 6.985)
            (xy 11.303 6.985)
          )
          (stroke (width 0) (type default) (color 0 0 0 0))
          (fill (type none))
        )
        (polyline
          (pts
            (xy 13.081 6.985)
            (xy 13.081 7.366)
          )
          (stroke (width 0) (type default) (color 0 0 0 0))
          (fill (type none))
        )
        (polyline
          (pts
            (xy 13.081 7.493)
            (xy 11.303 7.493)
          )
          (stroke (width 0) (type default) (color 0 0 0 0))
          (fill (type background))
        )
        (polyline
          (pts
            (xy 13.208 -28.575)
            (xy 17.653 -28.575)
          )
          (stroke (width 0) (type default) (color 0 0 0 0))
          (fill (type none))
        )
        (polyline
          (pts
            (xy 13.208 -14.605)
            (xy 13.208 -13.462)
          )
          (stroke (width 0) (type default) (color 0 0 0 0))
          (fill (type none))
        )
        (polyline
          (pts
            (xy 13.208 -14.097)
            (xy 13.208 -28.702)
          )
          (stroke (width 0) (type default) (color 0 0 0 0))
          (fill (type none))
        )
        (polyline
          (pts
            (xy 13.208 -14.097)
            (xy 13.208 0.508)
          )
          (stroke (width 0) (type default) (color 0 0 0 0))
          (fill (type none))
        )
        (polyline
          (pts
            (xy 13.208 0.381)
            (xy 17.653 0.381)
          )
          (stroke (width 0) (type default) (color 0 0 0 0))
          (fill (type none))
        )
        (polyline
          (pts
            (xy 13.843 -28.575)
            (xy 13.843 -14.097)
          )
          (stroke (width 0) (type default) (color 0 0 0 0))
          (fill (type none))
        )
        (polyline
          (pts
            (xy 13.843 -14.605)
            (xy 13.843 -13.462)
          )
          (stroke (width 0) (type default) (color 0 0 0 0))
          (fill (type none))
        )
        (polyline
          (pts
            (xy 13.843 0.381)
            (xy 13.843 -14.097)
          )
          (stroke (width 0) (type default) (color 0 0 0 0))
          (fill (type none))
        )
        (polyline
          (pts
            (xy 14.097 -14.605)
            (xy 14.097 -13.462)
          )
          (stroke (width 0) (type default) (color 0 0 0 0))
          (fill (type none))
        )
        (polyline
          (pts
            (xy 14.097 -14.097)
            (xy 14.097 -28.575)
          )
          (stroke (width 0) (type default) (color 0 0 0 0))
          (fill (type none))
        )
        (polyline
          (pts
            (xy 14.097 -14.097)
            (xy 14.097 0.381)
          )
          (stroke (width 0) (type default) (color 0 0 0 0))
          (fill (type none))
        )
        (polyline
          (pts
            (xy 14.605 -14.605)
            (xy 14.605 -13.462)
          )
          (stroke (width 0) (type default) (color 0 0 0 0))
          (fill (type none))
        )
        (polyline
          (pts
            (xy 14.605 -14.097)
            (xy 14.605 -26.035)
          )
          (stroke (width 0) (type default) (color 0 0 0 0))
          (fill (type none))
        )
        (polyline
          (pts
            (xy 14.605 -14.097)
            (xy 14.605 -2.159)
          )
          (stroke (width 0) (type default) (color 0 0 0 0))
          (fill (type none))
        )
        (polyline
          (pts
            (xy 16.637 -25.527)
            (xy 16.637 -25.146)
          )
          (stroke (width 0) (type default) (color 0 0 0 0))
          (fill (type none))
        )
        (polyline
          (pts
            (xy 16.637 -20.701)
            (xy 16.637 -20.828)
          )
          (stroke (width 0) (type default) (color 0 0 0 0))
          (fill (type none))
        )
        (polyline
          (pts
            (xy 16.637 -20.447)
            (xy 16.637 -20.701)
          )
          (stroke (width 0) (type default) (color 0 0 0 0))
          (fill (type none))
        )
        (polyline
          (pts
            (xy 16.637 -7.747)
            (xy 16.637 -7.493)
          )
          (stroke (width 0) (type default) (color 0 0 0 0))
          (fill (type none))
        )
        (polyline
          (pts
            (xy 16.637 -7.493)
            (xy 16.637 -7.366)
          )
          (stroke (width 0) (type default) (color 0 0 0 0))
          (fill (type none))
        )
        (polyline
          (pts
            (xy 16.637 -2.667)
            (xy 16.637 -3.048)
          )
          (stroke (width 0) (type default) (color 0 0 0 0))
          (fill (type none))
        )
        (polyline
          (pts
            (xy 16.891 -28.575)
            (xy 16.891 -25.527)
          )
          (stroke (width 0) (type default) (color 0 0 0 0))
          (fill (type none))
        )
        (polyline
          (pts
            (xy 16.891 -20.447)
            (xy 16.891 -14.097)
          )
          (stroke (width 0) (type default) (color 0 0 0 0))
          (fill (type none))
        )
        (polyline
          (pts
            (xy 16.891 -14.605)
            (xy 16.891 -13.462)
          )
          (stroke (width 0) (type default) (color 0 0 0 0))
          (fill (type none))
        )
        (polyline
          (pts
            (xy 16.891 -7.747)
            (xy 16.891 -14.097)
          )
          (stroke (width 0) (type default) (color 0 0 0 0))
          (fill (type none))
        )
        (polyline
          (pts
            (xy 16.891 0.381)
            (xy 16.891 -2.667)
          )
          (stroke (width 0) (type default) (color 0 0 0 0))
          (fill (type none))
        )
        (polyline
          (pts
            (xy 17.145 -25.527)
            (xy 17.145 -25.019)
          )
          (stroke (width 0) (type default) (color 0 0 0 0))
          (fill (type none))
        )
        (polyline
          (pts
            (xy 17.145 -20.447)
            (xy 17.145 -20.955)
          )
          (stroke (width 0) (type default) (color 0 0 0 0))
          (fill (type none))
        )
        (polyline
          (pts
            (xy 17.145 -7.747)
            (xy 17.145 -7.239)
          )
          (stroke (width 0) (type default) (color 0 0 0 0))
          (fill (type none))
        )
        (polyline
          (pts
            (xy 17.145 -2.667)
            (xy 17.145 -3.175)
          )
          (stroke (width 0) (type default) (color 0 0 0 0))
          (fill (type none))
        )
        (polyline
          (pts
            (xy 17.653 -29.083)
            (xy 13.208 -29.083)
          )
          (stroke (width 0) (type default) (color 0 0 0 0))
          (fill (type none))
        )
        (polyline
          (pts
            (xy 17.653 -26.162)
            (xy 17.653 -14.097)
          )
          (stroke (width 0) (type default) (color 0 0 0 0))
          (fill (type none))
        )
        (polyline
          (pts
            (xy 17.653 -14.605)
            (xy 17.653 -13.462)
          )
          (stroke (width 0) (type default) (color 0 0 0 0))
          (fill (type none))
        )
        (polyline
          (pts
            (xy 17.653 -2.032)
            (xy 17.653 -14.097)
          )
          (stroke (width 0) (type default) (color 0 0 0 0))
          (fill (type none))
        )
        (polyline
          (pts
            (xy 17.653 0.889)
            (xy 13.208 0.889)
          )
          (stroke (width 0) (type default) (color 0 0 0 0))
          (fill (type none))
        )
        (polyline
          (pts
            (xy 18.161 -14.605)
            (xy 18.161 -13.462)
          )
          (stroke (width 0) (type default) (color 0 0 0 0))
          (fill (type none))
        )
        (polyline
          (pts
            (xy 18.669 -14.605)
            (xy 18.669 -13.462)
          )
          (stroke (width 0) (type default) (color 0 0 0 0))
          (fill (type none))
        )
        (polyline
          (pts
            (xy 4.953 -30.607)
            (xy 4.445 -30.607)
            (xy 4.445 -14.097)
          )
          (stroke (width 0) (type default) (color 0 0 0 0))
          (fill (type none))
        )
        (polyline
          (pts
            (xy 4.953 -25.781)
            (xy 4.953 -29.972)
            (xy 4.953 -30.607)
          )
          (stroke (width 0) (type default) (color 0 0 0 0))
          (fill (type none))
        )
        (polyline
          (pts
            (xy 4.953 -2.413)
            (xy 4.953 1.778)
            (xy 4.953 2.413)
          )
          (stroke (width 0) (type default) (color 0 0 0 0))
          (fill (type none))
        )
        (polyline
          (pts
            (xy 4.953 2.413)
            (xy 4.445 2.413)
            (xy 4.445 -14.097)
          )
          (stroke (width 0) (type default) (color 0 0 0 0))
          (fill (type none))
        )
        (polyline
          (pts
            (xy 5.461 -29.083)
            (xy 5.461 -30.099)
            (xy 4.953 -30.099)
          )
          (stroke (width 0) (type default) (color 0 0 0 0))
          (fill (type none))
        )
        (polyline
          (pts
            (xy 5.461 0.889)
            (xy 5.461 1.905)
            (xy 4.953 1.905)
          )
          (stroke (width 0) (type default) (color 0 0 0 0))
          (fill (type none))
        )
        (polyline
          (pts
            (xy 9.779 -14.097)
            (xy 9.779 -29.591)
            (xy 11.303 -29.591)
          )
          (stroke (width 0) (type default) (color 0 0 0 0))
          (fill (type none))
        )
        (polyline
          (pts
            (xy 9.779 -14.097)
            (xy 9.779 1.397)
            (xy 11.303 1.397)
          )
          (stroke (width 0) (type default) (color 0 0 0 0))
          (fill (type none))
        )
        (polyline
          (pts
            (xy 10.287 -14.097)
            (xy 10.287 -29.083)
            (xy 11.303 -29.083)
          )
          (stroke (width 0) (type default) (color 0 0 0 0))
          (fill (type none))
        )
        (polyline
          (pts
            (xy 10.287 -14.097)
            (xy 10.287 0.889)
            (xy 11.303 0.889)
          )
          (stroke (width 0) (type default) (color 0 0 0 0))
          (fill (type none))
        )
        (polyline
          (pts
            (xy 12.319 -14.097)
            (xy 12.319 -29.083)
            (xy 11.303 -29.083)
          )
          (stroke (width 0) (type default) (color 0 0 0 0))
          (fill (type none))
        )
        (polyline
          (pts
            (xy 12.319 -14.097)
            (xy 12.319 0.889)
            (xy 11.303 0.889)
          )
          (stroke (width 0) (type default) (color 0 0 0 0))
          (fill (type none))
        )
        (polyline
          (pts
            (xy 12.827 -14.097)
            (xy 12.827 -29.591)
            (xy 11.303 -29.591)
          )
          (stroke (width 0) (type default) (color 0 0 0 0))
          (fill (type none))
        )
        (polyline
          (pts
            (xy 12.827 -14.097)
            (xy 12.827 1.397)
            (xy 11.303 1.397)
          )
          (stroke (width 0) (type default) (color 0 0 0 0))
          (fill (type none))
        )
        (polyline
          (pts
            (xy 17.145 -29.083)
            (xy 17.145 -30.099)
            (xy 17.653 -30.099)
          )
          (stroke (width 0) (type default) (color 0 0 0 0))
          (fill (type none))
        )
        (polyline
          (pts
            (xy 17.145 0.889)
            (xy 17.145 1.905)
            (xy 17.653 1.905)
          )
          (stroke (width 0) (type default) (color 0 0 0 0))
          (fill (type none))
        )
        (polyline
          (pts
            (xy 17.653 -30.607)
            (xy 18.161 -30.607)
            (xy 18.161 -14.097)
          )
          (stroke (width 0) (type default) (color 0 0 0 0))
          (fill (type none))
        )
        (polyline
          (pts
            (xy 17.653 -25.781)
            (xy 17.653 -29.972)
            (xy 17.653 -30.607)
          )
          (stroke (width 0) (type default) (color 0 0 0 0))
          (fill (type none))
        )
        (polyline
          (pts
            (xy 17.653 -2.413)
            (xy 17.653 1.778)
            (xy 17.653 2.413)
          )
          (stroke (width 0) (type default) (color 0 0 0 0))
          (fill (type none))
        )
        (polyline
          (pts
            (xy 17.653 2.413)
            (xy 18.161 2.413)
            (xy 18.161 -14.097)
          )
          (stroke (width 0) (type default) (color 0 0 0 0))
          (fill (type none))
        )
        (polyline
          (pts
            (xy 4.953 -25.527)
            (xy 6.3754 -24.1046)
            (xy 6.6294 -23.5966)
            (xy 6.731 -22.987)
          )
          (stroke (width 0) (type default) (color 0 0 0 0))
          (fill (type none))
        )
        (polyline
          (pts
            (xy 4.953 -24.257)
            (xy 5.461 -23.6982)
            (xy 5.5626 -23.368)
            (xy 5.588 -23.0124)
          )
          (stroke (width 0) (type default) (color 0 0 0 0))
          (fill (type none))
        )
        (polyline
          (pts
            (xy 4.953 -21.717)
            (xy 5.461 -22.2758)
            (xy 5.5626 -22.606)
            (xy 5.588 -22.9616)
          )
          (stroke (width 0) (type default) (color 0 0 0 0))
          (fill (type none))
        )
        (polyline
          (pts
            (xy 4.953 -20.447)
            (xy 6.3754 -21.8694)
            (xy 6.6294 -22.3774)
            (xy 6.731 -22.987)
          )
          (stroke (width 0) (type default) (color 0 0 0 0))
          (fill (type none))
        )
        (polyline
          (pts
            (xy 4.953 -7.747)
            (xy 6.3754 -6.3246)
            (xy 6.6294 -5.8166)
            (xy 6.731 -5.207)
          )
          (stroke (width 0) (type default) (color 0 0 0 0))
          (fill (type none))
        )
        (polyline
          (pts
            (xy 4.953 -6.477)
            (xy 5.461 -5.9182)
            (xy 5.5626 -5.588)
            (xy 5.588 -5.2324)
          )
          (stroke (width 0) (type default) (color 0 0 0 0))
          (fill (type none))
        )
        (polyline
          (pts
            (xy 4.953 -3.937)
            (xy 5.461 -4.4958)
            (xy 5.5626 -4.826)
            (xy 5.588 -5.1816)
          )
          (stroke (width 0) (type default) (color 0 0 0 0))
          (fill (type none))
        )
        (polyline
          (pts
            (xy 4.953 -2.667)
            (xy 6.3754 -4.0894)
            (xy 6.6294 -4.5974)
            (xy 6.731 -5.207)
          )
          (stroke (width 0) (type default) (color 0 0 0 0))
          (fill (type none))
        )
        (polyline
          (pts
            (xy 9.398 -28.702)
            (xy 9.398 -29.083)
            (xy 9.525 -29.337)
            (xy 9.779 -29.591)
          )
          (stroke (width 0) (type default) (color 0 0 0 0))
          (fill (type none))
        )
        (polyline
          (pts
            (xy 9.398 0.508)
            (xy 9.398 0.889)
            (xy 9.525 1.143)
            (xy 9.779 1.397)
          )
          (stroke (width 0) (type default) (color 0 0 0 0))
          (fill (type none))
        )
        (polyline
          (pts
            (xy 11.303 -30.607)
            (xy 9.906 -30.607)
            (xy 9.779 -30.607)
            (xy 9.779 -29.591)
          )
          (stroke (width 0) (type default) (color 0 0 0 0))
          (fill (type none))
        )
        (polyline
          (pts
            (xy 11.303 -30.607)
            (xy 12.7 -30.607)
            (xy 12.827 -30.607)
            (xy 12.827 -29.591)
          )
          (stroke (width 0) (type default) (color 0 0 0 0))
          (fill (type none))
        )
        (polyline
          (pts
            (xy 11.303 2.413)
            (xy 9.906 2.413)
            (xy 9.779 2.413)
            (xy 9.779 1.397)
          )
          (stroke (width 0) (type default) (color 0 0 0 0))
          (fill (type none))
        )
        (polyline
          (pts
            (xy 11.303 2.413)
            (xy 12.7 2.413)
            (xy 12.827 2.413)
            (xy 12.827 1.397)
          )
          (stroke (width 0) (type default) (color 0 0 0 0))
          (fill (type none))
        )
        (polyline
          (pts
            (xy 13.208 -28.702)
            (xy 13.208 -29.083)
            (xy 13.081 -29.337)
            (xy 12.827 -29.591)
          )
          (stroke (width 0) (type default) (color 0 0 0 0))
          (fill (type none))
        )
        (polyline
          (pts
            (xy 13.208 0.508)
            (xy 13.208 0.889)
            (xy 13.081 1.143)
            (xy 12.827 1.397)
          )
          (stroke (width 0) (type default) (color 0 0 0 0))
          (fill (type none))
        )
        (polyline
          (pts
            (xy 17.653 -25.527)
            (xy 16.2306 -24.1046)
            (xy 15.9766 -23.5966)
            (xy 15.875 -22.987)
          )
          (stroke (width 0) (type default) (color 0 0 0 0))
          (fill (type none))
        )
        (polyline
          (pts
            (xy 17.653 -24.257)
            (xy 17.145 -23.6982)
            (xy 17.0434 -23.368)
            (xy 17.018 -23.0124)
          )
          (stroke (width 0) (type default) (color 0 0 0 0))
          (fill (type none))
        )
        (polyline
          (pts
            (xy 17.653 -21.717)
            (xy 17.145 -22.2758)
            (xy 17.0434 -22.606)
            (xy 17.018 -22.9616)
          )
          (stroke (width 0) (type default) (color 0 0 0 0))
          (fill (type none))
        )
        (polyline
          (pts
            (xy 17.653 -20.447)
            (xy 16.2306 -21.8694)
            (xy 15.9766 -22.3774)
            (xy 15.875 -22.987)
          )
          (stroke (width 0) (type default) (color 0 0 0 0))
          (fill (type none))
        )
        (polyline
          (pts
            (xy 17.653 -7.747)
            (xy 16.2306 -6.3246)
            (xy 15.9766 -5.8166)
            (xy 15.875 -5.207)
          )
          (stroke (width 0) (type default) (color 0 0 0 0))
          (fill (type none))
        )
        (polyline
          (pts
            (xy 17.653 -6.477)
            (xy 17.145 -5.9182)
            (xy 17.0434 -5.588)
            (xy 17.018 -5.2324)
          )
          (stroke (width 0) (type default) (color 0 0 0 0))
          (fill (type none))
        )
        (polyline
          (pts
            (xy 17.653 -3.937)
            (xy 17.145 -4.4958)
            (xy 17.0434 -4.826)
            (xy 17.018 -5.1816)
          )
          (stroke (width 0) (type default) (color 0 0 0 0))
          (fill (type none))
        )
        (polyline
          (pts
            (xy 17.653 -2.667)
            (xy 16.2306 -4.0894)
            (xy 15.9766 -4.5974)
            (xy 15.875 -5.207)
          )
          (stroke (width 0) (type default) (color 0 0 0 0))
          (fill (type none))
        )
        (polyline
          (pts
            (xy 5.461 -25.527)
            (xy 6.5278 -24.5618)
            (xy 6.858 -24.2062)
            (xy 7.0866 -23.7236)
            (xy 7.239 -22.987)
          )
          (stroke (width 0) (type default) (color 0 0 0 0))
          (fill (type none))
        )
        (polyline
          (pts
            (xy 5.461 -20.447)
            (xy 6.5278 -21.4122)
            (xy 6.858 -21.7678)
            (xy 7.0866 -22.2504)
            (xy 7.239 -22.987)
          )
          (stroke (width 0) (type default) (color 0 0 0 0))
          (fill (type none))
        )
        (polyline
          (pts
            (xy 5.461 -7.747)
            (xy 6.5278 -6.7818)
            (xy 6.858 -6.4262)
            (xy 7.0866 -5.9436)
            (xy 7.239 -5.207)
          )
          (stroke (width 0) (type default) (color 0 0 0 0))
          (fill (type none))
        )
        (polyline
          (pts
            (xy 5.461 -2.667)
            (xy 6.5278 -3.6322)
            (xy 6.858 -3.9878)
            (xy 7.0866 -4.4704)
            (xy 7.239 -5.207)
          )
          (stroke (width 0) (type default) (color 0 0 0 0))
          (fill (type none))
        )
        (polyline
          (pts
            (xy 17.145 -25.527)
            (xy 16.0782 -24.5618)
            (xy 15.748 -24.2062)
            (xy 15.5194 -23.7236)
            (xy 15.367 -22.987)
          )
          (stroke (width 0) (type default) (color 0 0 0 0))
          (fill (type none))
        )
        (polyline
          (pts
            (xy 17.145 -20.447)
            (xy 16.0782 -21.4122)
            (xy 15.748 -21.7678)
            (xy 15.5194 -22.2504)
            (xy 15.367 -22.987)
          )
          (stroke (width 0) (type default) (color 0 0 0 0))
          (fill (type none))
        )
        (polyline
          (pts
            (xy 17.145 -7.747)
            (xy 16.0782 -6.7818)
            (xy 15.748 -6.4262)
            (xy 15.5194 -5.9436)
            (xy 15.367 -5.207)
          )
          (stroke (width 0) (type default) (color 0 0 0 0))
          (fill (type none))
        )
        (polyline
          (pts
            (xy 17.145 -2.667)
            (xy 16.0782 -3.6322)
            (xy 15.748 -3.9878)
            (xy 15.5194 -4.4704)
            (xy 15.367 -5.207)
          )
          (stroke (width 0) (type default) (color 0 0 0 0))
          (fill (type none))
        )
        (polyline
          (pts
            (xy 4.953 -25.527)
            (xy 5.969 -25.527)
            (xy 7.239 -24.257)
            (xy 7.239 -21.717)
            (xy 5.969 -20.447)
            (xy 4.953 -20.447)
          )
          (stroke (width 0) (type default) (color 0 0 0 0))
          (fill (type none))
        )
        (polyline
          (pts
            (xy 4.953 -2.667)
            (xy 5.969 -2.667)
            (xy 7.239 -3.937)
            (xy 7.239 -6.477)
            (xy 5.969 -7.747)
            (xy 4.953 -7.747)
          )
          (stroke (width 0) (type default) (color 0 0 0 0))
          (fill (type none))
        )
        (polyline
          (pts
            (xy 8.509 -29.083)
            (xy 8.5598 -29.4894)
            (xy 8.6614 -29.8958)
            (xy 8.9154 -30.3022)
            (xy 9.3218 -30.6578)
            (xy 9.779 -30.861)
          )
          (stroke (width 0) (type default) (color 0 0 0 0))
          (fill (type none))
        )
        (polyline
          (pts
            (xy 8.509 -27.559)
            (xy 8.001 -27.559)
            (xy 7.747 -27.305)
            (xy 7.747 -26.289)
            (xy 8.001 -26.035)
            (xy 8.509 -26.035)
          )
          (stroke (width 0) (type default) (color 0 0 0 0))
          (fill (type none))
        )
        (polyline
          (pts
            (xy 8.509 -0.635)
            (xy 8.001 -0.635)
            (xy 7.747 -0.889)
            (xy 7.747 -1.905)
            (xy 8.001 -2.159)
            (xy 8.509 -2.159)
          )
          (stroke (width 0) (type default) (color 0 0 0 0))
          (fill (type none))
        )
        (polyline
          (pts
            (xy 8.509 0.889)
            (xy 8.5598 1.2954)
            (xy 8.6614 1.7018)
            (xy 8.9154 2.1082)
            (xy 9.3218 2.4638)
            (xy 9.779 2.667)
          )
          (stroke (width 0) (type default) (color 0 0 0 0))
          (fill (type none))
        )
        (polyline
          (pts
            (xy 14.097 -29.083)
            (xy 14.0462 -29.4894)
            (xy 13.9446 -29.8958)
            (xy 13.6906 -30.3022)
            (xy 13.2842 -30.6578)
            (xy 12.827 -30.861)
          )
          (stroke (width 0) (type default) (color 0 0 0 0))
          (fill (type none))
        )
        (polyline
          (pts
            (xy 14.097 -27.559)
            (xy 14.605 -27.559)
            (xy 14.859 -27.305)
            (xy 14.859 -26.289)
            (xy 14.605 -26.035)
            (xy 14.097 -26.035)
          )
          (stroke (width 0) (type default) (color 0 0 0 0))
          (fill (type none))
        )
        (polyline
          (pts
            (xy 14.097 -0.635)
            (xy 14.605 -0.635)
            (xy 14.859 -0.889)
            (xy 14.859 -1.905)
            (xy 14.605 -2.159)
            (xy 14.097 -2.159)
          )
          (stroke (width 0) (type default) (color 0 0 0 0))
          (fill (type none))
        )
        (polyline
          (pts
            (xy 14.097 0.889)
            (xy 14.0462 1.2954)
            (xy 13.9446 1.7018)
            (xy 13.6906 2.1082)
            (xy 13.2842 2.4638)
            (xy 12.827 2.667)
          )
          (stroke (width 0) (type default) (color 0 0 0 0))
          (fill (type none))
        )
        (polyline
          (pts
            (xy 17.653 -25.527)
            (xy 16.637 -25.527)
            (xy 15.367 -24.257)
            (xy 15.367 -21.717)
            (xy 16.637 -20.447)
            (xy 17.653 -20.447)
          )
          (stroke (width 0) (type default) (color 0 0 0 0))
          (fill (type none))
        )
        (polyline
          (pts
            (xy 17.653 -2.667)
            (xy 16.637 -2.667)
            (xy 15.367 -3.937)
            (xy 15.367 -6.477)
            (xy 16.637 -7.747)
            (xy 17.653 -7.747)
          )
          (stroke (width 0) (type default) (color 0 0 0 0))
          (fill (type none))
        )
        (polyline
          (pts
            (xy 18.669 -14.097)
            (xy 18.796 -31.115)
            (xy 18.796 -31.115)
            (xy 18.669 -31.623)
            (xy 18.5674 -32.131)
            (xy 18.3642 -32.8422)
            (xy 18.0086 -33.6042)
            (xy 17.6022 -34.2138)
            (xy 17.1958 -34.671)
            (xy 16.6878 -35.1282)
            (xy 15.9766 -35.5854)
            (xy 15.2654 -35.8902)
            (xy 14.5542 -36.0934)
            (xy 13.843 -36.195)
            (xy 9.017 -36.195)
            (xy 7.8994 -36.0934)
            (xy 7.0358 -35.7886)
            (xy 5.969 -35.179)
            (xy 4.953 -34.1122)
            (xy 4.3942 -33.0962)
            (xy 4.0386 -32.0802)
            (xy 3.937 -31.75)
            (xy 3.81 -31.115)
            (xy 3.81 -14.097)
          )
          (stroke (width 0.254) (type default) (color 0 0 0 0))
          (fill (type background))
        )
        (polyline
          (pts
            (xy 18.669 -14.097)
            (xy 18.796 2.921)
            (xy 18.796 3.175)
            (xy 18.669 3.683)
            (xy 18.5674 3.937)
            (xy 18.3642 4.6482)
            (xy 18.0086 5.4102)
            (xy 17.6022 6.0198)
            (xy 17.1958 6.477)
            (xy 16.6878 6.9342)
            (xy 15.9766 7.3914)
            (xy 15.2654 7.6962)
            (xy 14.5542 7.8994)
            (xy 13.843 8.001)
            (xy 9.017 8.001)
            (xy 7.8994 7.8994)
            (xy 7.0358 7.5946)
            (xy 5.969 6.985)
            (xy 4.953 5.9182)
            (xy 4.3942 4.9022)
            (xy 4.0386 3.8862)
            (xy 3.937 3.429)
            (xy 3.81 2.794)
            (xy 3.81 -14.097)
          )
          (stroke (width 0.254) (type default) (color 0 0 0 0))
          (fill (type background))
        )
        (arc (start 4.445 -30.607) (mid 5.8538 -34.2782) (end 9.525 -35.687)
          (stroke (width 0) (type default) (color 0 0 0 0))
          (fill (type none))
        )
        (arc (start 4.953 -30.607) (mid 6.3281 -33.8039) (end 9.525 -35.179)
          (stroke (width 0) (type default) (color 0 0 0 0))
          (fill (type none))
        )
        (arc (start 5.461 -30.099) (mid 6.604 -33.3447) (end 9.779 -34.671)
          (stroke (width 0) (type default) (color 0 0 0 0))
          (fill (type none))
        )
        (rectangle (start 9.525 -28.702) (end 9.779 -27.432)
          (stroke (width 0) (type default) (color 0 0 0 0))
          (fill (type outline))
        )
        (rectangle (start 9.525 -26.162) (end 9.779 -24.892)
          (stroke (width 0) (type default) (color 0 0 0 0))
          (fill (type outline))
        )
        (rectangle (start 9.525 -23.622) (end 9.779 -22.352)
          (stroke (width 0) (type default) (color 0 0 0 0))
          (fill (type outline))
        )
        (rectangle (start 9.525 -21.082) (end 9.779 -19.812)
          (stroke (width 0) (type default) (color 0 0 0 0))
          (fill (type outline))
        )
        (rectangle (start 9.525 -18.542) (end 9.779 -17.272)
          (stroke (width 0) (type default) (color 0 0 0 0))
          (fill (type outline))
        )
        (rectangle (start 9.525 -16.002) (end 9.779 -14.732)
          (stroke (width 0) (type default) (color 0 0 0 0))
          (fill (type outline))
        )
        (rectangle (start 9.525 -12.192) (end 9.779 -13.462)
          (stroke (width 0) (type default) (color 0 0 0 0))
          (fill (type outline))
        )
        (rectangle (start 9.525 -9.652) (end 9.779 -10.922)
          (stroke (width 0) (type default) (color 0 0 0 0))
          (fill (type outline))
        )
        (rectangle (start 9.525 -7.112) (end 9.779 -8.382)
          (stroke (width 0) (type default) (color 0 0 0 0))
          (fill (type outline))
        )
        (rectangle (start 9.525 -4.572) (end 9.779 -5.842)
          (stroke (width 0) (type default) (color 0 0 0 0))
          (fill (type outline))
        )
        (rectangle (start 9.525 -2.032) (end 9.779 -3.302)
          (stroke (width 0) (type default) (color 0 0 0 0))
          (fill (type outline))
        )
        (rectangle (start 9.525 0.508) (end 9.779 -0.762)
          (stroke (width 0) (type default) (color 0 0 0 0))
          (fill (type outline))
        )
        (arc (start 9.525 6.985) (mid 6.3281 5.6099) (end 4.953 2.413)
          (stroke (width 0) (type default) (color 0 0 0 0))
          (fill (type none))
        )
        (arc (start 9.525 7.493) (mid 5.8538 6.0842) (end 4.445 2.413)
          (stroke (width 0) (type default) (color 0 0 0 0))
          (fill (type none))
        )
        (arc (start 9.779 6.477) (mid 6.6129 5.1421) (end 5.461 1.905)
          (stroke (width 0) (type default) (color 0 0 0 0))
          (fill (type none))
        )
        (arc (start 12.827 -34.671) (mid 15.9931 -33.3361) (end 17.145 -30.099)
          (stroke (width 0) (type default) (color 0 0 0 0))
          (fill (type none))
        )
        (arc (start 13.081 -35.687) (mid 16.7522 -34.2782) (end 18.161 -30.607)
          (stroke (width 0) (type default) (color 0 0 0 0))
          (fill (type none))
        )
        (arc (start 13.081 -35.179) (mid 16.2779 -33.8039) (end 17.653 -30.607)
          (stroke (width 0) (type default) (color 0 0 0 0))
          (fill (type none))
        )
        (rectangle (start 13.081 -28.702) (end 12.827 -27.432)
          (stroke (width 0) (type default) (color 0 0 0 0))
          (fill (type outline))
        )
        (rectangle (start 13.081 -26.162) (end 12.827 -24.892)
          (stroke (width 0) (type default) (color 0 0 0 0))
          (fill (type outline))
        )
        (rectangle (start 13.081 -23.622) (end 12.827 -22.352)
          (stroke (width 0) (type default) (color 0 0 0 0))
          (fill (type outline))
        )
        (rectangle (start 13.081 -21.082) (end 12.827 -19.812)
          (stroke (width 0) (type default) (color 0 0 0 0))
          (fill (type outline))
        )
        (rectangle (start 13.081 -18.542) (end 12.827 -17.272)
          (stroke (width 0) (type default) (color 0 0 0 0))
          (fill (type outline))
        )
        (rectangle (start 13.081 -16.002) (end 12.827 -14.732)
          (stroke (width 0) (type default) (color 0 0 0 0))
          (fill (type outline))
        )
        (rectangle (start 13.081 -12.192) (end 12.827 -13.462)
          (stroke (width 0) (type default) (color 0 0 0 0))
          (fill (type outline))
        )
        (rectangle (start 13.081 -9.652) (end 12.827 -10.922)
          (stroke (width 0) (type default) (color 0 0 0 0))
          (fill (type outline))
        )
        (rectangle (start 13.081 -7.112) (end 12.827 -8.382)
          (stroke (width 0) (type default) (color 0 0 0 0))
          (fill (type outline))
        )
        (rectangle (start 13.081 -4.572) (end 12.827 -5.842)
          (stroke (width 0) (type default) (color 0 0 0 0))
          (fill (type outline))
        )
        (rectangle (start 13.081 -2.032) (end 12.827 -3.302)
          (stroke (width 0) (type default) (color 0 0 0 0))
          (fill (type outline))
        )
        (rectangle (start 13.081 0.508) (end 12.827 -0.762)
          (stroke (width 0) (type default) (color 0 0 0 0))
          (fill (type outline))
        )
        (arc (start 17.145 1.905) (mid 16.002 5.1507) (end 12.827 6.477)
          (stroke (width 0) (type default) (color 0 0 0 0))
          (fill (type none))
        )
        (arc (start 17.653 2.413) (mid 16.2779 5.6099) (end 13.081 6.985)
          (stroke (width 0) (type default) (color 0 0 0 0))
          (fill (type none))
        )
        (arc (start 18.161 2.413) (mid 16.7522 6.0842) (end 13.081 7.493)
          (stroke (width 0) (type default) (color 0 0 0 0))
          (fill (type none))
        )
        (pin passive line (at 22.86 0 180) (length 3.81)
          (name "~" (effects (font (size 1.27 1.27))))
          (number "A1" (effects (font (size 1.27 1.27))))
        )
        (pin passive line (at 22.86 -22.86 180) (length 3.81)
          (name "~" (effects (font (size 1.27 1.27))))
          (number "A10" (effects (font (size 1.27 1.27))))
        )
        (pin passive line (at 22.86 -25.4 180) (length 3.81)
          (name "~" (effects (font (size 1.27 1.27))))
          (number "A11" (effects (font (size 1.27 1.27))))
        )
        (pin passive line (at 22.86 -27.94 180) (length 3.81)
          (name "~" (effects (font (size 1.27 1.27))))
          (number "A12" (effects (font (size 1.27 1.27))))
        )
        (pin passive line (at 22.86 -2.54 180) (length 3.81)
          (name "~" (effects (font (size 1.27 1.27))))
          (number "A2" (effects (font (size 1.27 1.27))))
        )
        (pin passive line (at 22.86 -5.08 180) (length 3.81)
          (name "~" (effects (font (size 1.27 1.27))))
          (number "A3" (effects (font (size 1.27 1.27))))
        )
        (pin passive line (at 22.86 -7.62 180) (length 3.81)
          (name "~" (effects (font (size 1.27 1.27))))
          (number "A4" (effects (font (size 1.27 1.27))))
        )
        (pin passive line (at 22.86 -10.16 180) (length 3.81)
          (name "~" (effects (font (size 1.27 1.27))))
          (number "A5" (effects (font (size 1.27 1.27))))
        )
        (pin passive line (at 22.86 -12.7 180) (length 3.81)
          (name "~" (effects (font (size 1.27 1.27))))
          (number "A6" (effects (font (size 1.27 1.27))))
        )
        (pin passive line (at 22.86 -15.24 180) (length 3.81)
          (name "~" (effects (font (size 1.27 1.27))))
          (number "A7" (effects (font (size 1.27 1.27))))
        )
        (pin passive line (at 22.86 -17.78 180) (length 3.81)
          (name "~" (effects (font (size 1.27 1.27))))
          (number "A8" (effects (font (size 1.27 1.27))))
        )
        (pin passive line (at 22.86 -20.32 180) (length 3.81)
          (name "~" (effects (font (size 1.27 1.27))))
          (number "A9" (effects (font (size 1.27 1.27))))
        )
        (pin passive line (at 0 -27.94 0) (length 3.81)
          (name "~" (effects (font (size 1.27 1.27))))
          (number "B1" (effects (font (size 1.27 1.27))))
        )
        (pin passive line (at 0 -5.08 0) (length 3.81)
          (name "~" (effects (font (size 1.27 1.27))))
          (number "B10" (effects (font (size 1.27 1.27))))
        )
        (pin passive line (at 0 -2.54 0) (length 3.81)
          (name "~" (effects (font (size 1.27 1.27))))
          (number "B11" (effects (font (size 1.27 1.27))))
        )
        (pin passive line (at 0 0 0) (length 3.81)
          (name "~" (effects (font (size 1.27 1.27))))
          (number "B12" (effects (font (size 1.27 1.27))))
        )
        (pin passive line (at 0 -25.4 0) (length 3.81)
          (name "~" (effects (font (size 1.27 1.27))))
          (number "B2" (effects (font (size 1.27 1.27))))
        )
        (pin passive line (at 0 -22.86 0) (length 3.81)
          (name "~" (effects (font (size 1.27 1.27))))
          (number "B3" (effects (font (size 1.27 1.27))))
        )
        (pin passive line (at 0 -20.32 0) (length 3.81)
          (name "~" (effects (font (size 1.27 1.27))))
          (number "B4" (effects (font (size 1.27 1.27))))
        )
        (pin passive line (at 0 -17.78 0) (length 3.81)
          (name "~" (effects (font (size 1.27 1.27))))
          (number "B5" (effects (font (size 1.27 1.27))))
        )
        (pin passive line (at 0 -15.24 0) (length 3.81)
          (name "~" (effects (font (size 1.27 1.27))))
          (number "B6" (effects (font (size 1.27 1.27))))
        )
        (pin passive line (at 0 -12.7 0) (length 3.81)
          (name "~" (effects (font (size 1.27 1.27))))
          (number "B7" (effects (font (size 1.27 1.27))))
        )
        (pin passive line (at 0 -10.16 0) (length 3.81)
          (name "~" (effects (font (size 1.27 1.27))))
          (number "B8" (effects (font (size 1.27 1.27))))
        )
        (pin passive line (at 0 -7.62 0) (length 3.81)
          (name "~" (effects (font (size 1.27 1.27))))
          (number "B9" (effects (font (size 1.27 1.27))))
        )
        (pin input line (at 6.35 -39.37 90) (length 3.81)
          (name "~" (effects (font (size 1.27 1.27))))
          (number "SH" (effects (font (size 1.27 1.27))))
        )
      )
    )
	(symbol "sa800u-baseboard-hw:1N4148WS" (pin_numbers hide) (pin_names hide) (in_bom yes) (on_board yes)
      (property "Reference" "D" (id 0) (at 21.59 -5.08 0)
        (effects (font (size 1.27 1.27) (thickness 0.15)) (justify left bottom))
      )
      (property "Value" "1N4148WS" (id 1) (at 21.59 -7.62 0)
        (effects (font (size 1.27 1.27) (thickness 0.15)) (justify left bottom))
      )
      (property "Footprint" "sa800u-baseboard-hw-footprints:D_SOD-323F" (id 2) (at 21.59 -10.16 0)
        (effects (font (size 1.27 1.27) (thickness 0.15)) (justify left bottom) hide)
      )
      (property "Datasheet" "https://www.onsemi.com/pub/Collateral/1N914BWS-D.pdf" (id 3) (at 21.59 -12.7 0)
        (effects (font (size 1.27 1.27) (thickness 0.15)) (justify left bottom) hide)
      )
      (property "MPN" "1N4148WS" (id 4) (at 21.59 -15.24 0)
        (effects (font (size 1.27 1.27) (thickness 0.15)) (justify left bottom) hide)
      )
      (property "Manufacturer" "ON Semiconductor" (id 5) (at 21.59 -17.78 0)
        (effects (font (size 1.27 1.27) (thickness 0.15)) (justify left bottom) hide)
      )
      (property "Author" "Antmicro" (id 6) (at 21.59 -20.32 0)
        (effects (font (size 1.27 1.27) (thickness 0.15)) (justify left bottom) hide)
      )
      (property "License" "Apache-2.0" (id 7) (at 21.59 -22.86 0)
        (effects (font (size 1.27 1.27) (thickness 0.15)) (justify left bottom) hide)
      )
      (property "ki_description" "Small Signal Fast Switching Diode" (id 8) (at 0 0 0)
        (effects (font (size 1.27 1.27)) hide)
      )
      (symbol "1N4148WS_1_1"
        (polyline
          (pts
            (xy 5.08 1.27)
            (xy 5.08 -1.27)
          )
          (stroke (width 0.254) (type default) (color 0 0 0 0))
          (fill (type none))
        )
        (polyline
          (pts
            (xy 2.54 1.27)
            (xy 2.54 -1.27)
            (xy 5.08 0)
            (xy 2.54 1.27)
          )
          (stroke (width 0.254) (type default) (color 0 0 0 0))
          (fill (type outline))
        )
        (pin passive line (at 0 0 0) (length 2.54)
          (name "A" (effects (font (size 1.27 1.27))))
          (number "A" (effects (font (size 1.27 1.27))))
        )
        (pin passive line (at 7.62 0 180) (length 2.54)
          (name "K" (effects (font (size 1.27 1.27))))
          (number "K" (effects (font (size 1.27 1.27))))
        )
      )
    )
	(symbol "sa800u-baseboard-hw:ABM8G-24.000MHZ-18-D2Y-T" (pin_names hide) (in_bom yes) (on_board yes)
      (property "Reference" "Y" (id 0) (at 24.13 -2.54 0)
        (effects (font (size 1.27 1.27) (thickness 0.15)) (justify left bottom))
      )
      (property "Value" "ABM8G-24.000MHZ-18-D2Y-T" (id 1) (at 24.13 -5.08 0)
        (effects (font (size 1.27 1.27) (thickness 0.15)) (justify left bottom))
      )
      (property "Footprint" "sa800u-baseboard-hw-footprints:Oscillator_SMD_Geyer_KX-7-4Pin_3.2x2.5mm" (id 2) (at 24.13 -7.62 0)
        (effects (font (size 1.27 1.27) (thickness 0.15)) (justify left bottom) hide)
      )
      (property "Datasheet" "https://www.farnell.com/datasheets/1883677.pdf" (id 3) (at 24.13 -10.16 0)
        (effects (font (size 1.27 1.27) (thickness 0.15)) (justify left bottom) hide)
      )
      (property "MPN" "ABM8G-24.000MHZ-18-D2Y-T" (id 4) (at 24.13 -12.7 0)
        (effects (font (size 1.27 1.27) (thickness 0.15)) (justify left bottom) hide)
      )
      (property "Manufacturer" "Abracon" (id 5) (at 24.13 -15.24 0)
        (effects (font (size 1.27 1.27) (thickness 0.15)) (justify left bottom) hide)
      )
      (property "Val" "24.000MHz" (id 6) (at 24.13 -17.78 0)
        (effects (font (size 1.27 1.27) (thickness 0.15)) (justify left bottom) hide)
      )
      (property "Author" "Antmicro" (id 7) (at 24.13 -20.32 0)
        (effects (font (size 1.27 1.27) (thickness 0.15)) (justify left bottom) hide)
      )
      (property "License" "Apache-2.0" (id 8) (at 24.13 -22.86 0)
        (effects (font (size 1.27 1.27) (thickness 0.15)) (justify left bottom) hide)
      )
      (property "ki_description" "24 MHz ±20ppm Crystal 18pF 60 Ohms 4-SMD, No Lead" (id 9) (at 0 0 0)
        (effects (font (size 1.27 1.27)) hide)
      )
      (symbol "ABM8G-24.000MHZ-18-D2Y-T_1_1"
        (polyline
          (pts
            (xy 2.54 1.27)
            (xy 2.54 -1.27)
          )
          (stroke (width 0.254) (type default) (color 0 0 0 0))
          (fill (type background))
        )
        (polyline
          (pts
            (xy 5.08 1.27)
            (xy 5.08 -1.27)
          )
          (stroke (width 0.254) (type default) (color 0 0 0 0))
          (fill (type background))
        )
        (polyline
          (pts
            (xy 1.905 -1.905)
            (xy 1.905 -2.54)
            (xy 5.715 -2.54)
            (xy 5.715 -1.905)
          )
          (stroke (width 0.254) (type default) (color 0 0 0 0))
          (fill (type none))
        )
        (polyline
          (pts
            (xy 1.905 1.905)
            (xy 1.905 2.54)
            (xy 5.715 2.54)
            (xy 5.715 1.905)
          )
          (stroke (width 0.254) (type default) (color 0 0 0 0))
          (fill (type none))
        )
        (rectangle (start 3.175 1.905) (end 4.445 -1.905)
          (stroke (width 0.254) (type default) (color 0 0 0 0))
          (fill (type background))
        )
        (pin passive line (at 0 0 0) (length 2.54)
          (name "~" (effects (font (size 1.27 1.27))))
          (number "1" (effects (font (size 1.27 1.27))))
        )
        (pin passive line (at 3.81 -5.08 90) (length 2.54)
          (name "SH" (effects (font (size 1.27 1.27))))
          (number "2" (effects (font (size 1.27 1.27))))
        )
        (pin passive line (at 7.62 0 180) (length 2.54)
          (name "~" (effects (font (size 1.27 1.27))))
          (number "3" (effects (font (size 1.27 1.27))))
        )
        (pin passive line (at 3.81 -5.08 90) (length 2.54) hide
          (name "SH" (effects (font (size 1.27 1.27))))
          (number "4" (effects (font (size 1.27 1.27))))
        )
      )
    )
	(symbol "sa800u-baseboard-hw:AP2114H-3.3TRG1" (in_bom yes) (on_board yes)
      (property "Reference" "U" (id 0) (at 33.02 -2.54 0)
        (effects (font (size 1.27 1.27) (thickness 0.15)) (justify left bottom))
      )
      (property "Value" "AP2114H-3.3TRG1" (id 1) (at 33.02 -7.62 0)
        (effects (font (size 1.27 1.27) (thickness 0.15)) (justify left bottom) hide)
      )
      (property "Footprint" "sa800u-baseboard-hw-footprints:SOT-223" (id 2) (at 33.02 -10.16 0)
        (effects (font (size 1.27 1.27) (thickness 0.15)) (justify left bottom) hide)
      )
      (property "Datasheet" "https://www.diodes.com/assets/Datasheets/AP2114.pdf" (id 3) (at 33.02 -12.7 0)
        (effects (font (size 1.27 1.27) (thickness 0.15)) (justify left bottom) hide)
      )
      (property "MPN" "AP2114H-3.3TRG1" (id 4) (at 33.02 -5.08 0)
        (effects (font (size 1.27 1.27) (thickness 0.15)) (justify left bottom))
      )
      (property "Manufacturer" "Diodes Incorporated" (id 5) (at 33.02 -15.24 0)
        (effects (font (size 1.27 1.27) (thickness 0.15)) (justify left bottom) hide)
      )
      (property "Author" "Antmicro" (id 6) (at 33.02 -17.78 0)
        (effects (font (size 1.27 1.27) (thickness 0.15)) (justify left bottom) hide)
      )
      (property "License" "Apache-2.0" (id 7) (at 33.02 -20.32 0)
        (effects (font (size 1.27 1.27) (thickness 0.15)) (justify left bottom) hide)
      )
      (symbol "AP2114H-3.3TRG1_1_1"
        (rectangle (start 2.54 2.54) (end 13.97 -5.08)
          (stroke (width 0.254) (type default) (color 0 0 0 0))
          (fill (type background))
        )
        (pin power_in line (at 0 -2.54 0) (length 2.54)
          (name "GND" (effects (font (size 1.27 1.27))))
          (number "1" (effects (font (size 1.27 1.27))))
        )
        (pin output line (at 16.51 0 180) (length 2.54)
          (name "VOUT" (effects (font (size 1.27 1.27))))
          (number "2" (effects (font (size 1.27 1.27))))
        )
        (pin input line (at 0 0 0) (length 2.54)
          (name "IN" (effects (font (size 1.27 1.27))))
          (number "3" (effects (font (size 1.27 1.27))))
        )
        (pin passive line (at 16.51 0 180) (length 2.54) hide
          (name "VOUT" (effects (font (size 1.27 1.27))))
          (number "4" (effects (font (size 1.27 1.27))))
        )
      )
    )
	(symbol "sa800u-baseboard-hw:AP62301WU-7" (in_bom yes) (on_board yes)
      (property "Reference" "U" (id 0) (at 35.56 -2.54 0)
        (effects (font (size 1.27 1.27) (thickness 0.15)) (justify left bottom))
      )
      (property "Value" "AP62301WU-7" (id 1) (at 35.56 -7.62 0)
        (effects (font (size 1.27 1.27) (thickness 0.15)) (justify left bottom) hide)
      )
      (property "Footprint" "sa800u-baseboard-hw-footprints:AP62301WU-7-TSOT23-6" (id 2) (at 35.56 -10.16 0)
        (effects (font (size 1.27 1.27) (thickness 0.15)) (justify left bottom) hide)
      )
      (property "Datasheet" "https://www.diodes.com/assets/Datasheets/AP62300_AP62301_AP62300T.pdf" (id 3) (at 35.56 -12.7 0)
        (effects (font (size 1.27 1.27) (thickness 0.15)) (justify left bottom) hide)
      )
      (property "MPN" "AP62301WU-7" (id 4) (at 35.56 -5.08 0)
        (effects (font (size 1.27 1.27) (thickness 0.15)) (justify left bottom))
      )
      (property "Manufacturer" "Diodes Incorporated" (id 5) (at 35.56 -15.24 0)
        (effects (font (size 1.27 1.27) (thickness 0.15)) (justify left bottom) hide)
      )
      (property "Author" "Antmicro" (id 6) (at 35.56 -17.78 0)
        (effects (font (size 1.27 1.27) (thickness 0.15)) (justify left bottom) hide)
      )
      (property "License" "Apache-2.0" (id 7) (at 35.56 -20.32 0)
        (effects (font (size 1.27 1.27) (thickness 0.15)) (justify left bottom) hide)
      )
      (symbol "AP62301WU-7_1_1"
        (rectangle (start 2.54 2.54) (end 17.78 -12.7)
          (stroke (width 0.254) (type default) (color 0 0 0 0))
          (fill (type background))
        )
        (pin power_in line (at 0 -10.16 0) (length 2.54)
          (name "GND" (effects (font (size 1.27 1.27))))
          (number "1" (effects (font (size 1.27 1.27))))
        )
        (pin power_out line (at 20.32 0 180) (length 2.54)
          (name "SW" (effects (font (size 1.27 1.27))))
          (number "2" (effects (font (size 1.27 1.27))))
        )
        (pin power_in line (at 0 0 0) (length 2.54)
          (name "VIN" (effects (font (size 1.27 1.27))))
          (number "3" (effects (font (size 1.27 1.27))))
        )
        (pin input line (at 20.32 -10.16 180) (length 2.54)
          (name "FB" (effects (font (size 1.27 1.27))))
          (number "4" (effects (font (size 1.27 1.27))))
        )
        (pin input line (at 0 -5.08 0) (length 2.54)
          (name "EN" (effects (font (size 1.27 1.27))))
          (number "5" (effects (font (size 1.27 1.27))))
        )
        (pin output line (at 20.32 -5.08 180) (length 2.54)
          (name "BST" (effects (font (size 1.27 1.27))))
          (number "6" (effects (font (size 1.27 1.27))))
        )
      )
    )
	(symbol "sa800u-baseboard-hw:ASMB-TTF0-0A20B" (pin_names hide) (in_bom yes) (on_board yes)
      (property "Reference" "D" (id 0) (at 27.94 -2.54 0)
        (effects (font (size 1.27 1.27) (thickness 0.15)) (justify left bottom))
      )
      (property "Value" "ASMB-TTF0-0A20B" (id 1) (at 27.94 -5.08 0)
        (effects (font (size 1.27 1.27) (thickness 0.15)) (justify left bottom) hide)
      )
      (property "Footprint" "sa800u-baseboard-hw-footprints:PLCC6_3.5x3.7mm" (id 2) (at 27.94 -7.62 0)
        (effects (font (size 1.27 1.27) (thickness 0.15)) (justify left bottom) hide)
      )
      (property "Datasheet" "https://docs.broadcom.com/doc/ASMB-TTF0-0A20B-DS101" (id 3) (at 27.94 -10.16 0)
        (effects (font (size 1.27 1.27) (thickness 0.15)) (justify left bottom) hide)
      )
      (property "MPN" "ASMB-TTF0-0A20B" (id 4) (at 27.94 -12.7 0)
        (effects (font (size 1.27 1.27) (thickness 0.15)) (justify left bottom) hide)
      )
      (property "Manufacturer" "Broadcom" (id 5) (at 27.94 -15.24 0)
        (effects (font (size 1.27 1.27) (thickness 0.15)) (justify left bottom) hide)
      )
      (property "Author" "Antmicro" (id 6) (at 27.94 -17.78 0)
        (effects (font (size 1.27 1.27) (thickness 0.15)) (justify left bottom) hide)
      )
      (property "License" "Apache-2.0" (id 7) (at 27.94 -20.32 0)
        (effects (font (size 1.27 1.27) (thickness 0.15)) (justify left bottom) hide)
      )
      (symbol "ASMB-TTF0-0A20B_1_1"
        (polyline
          (pts
            (xy 2.54 -10.16)
            (xy 12.7 -10.16)
          )
          (stroke (width 0) (type default) (color 0 0 0 0))
          (fill (type none))
        )
        (polyline
          (pts
            (xy 2.54 0)
            (xy 12.7 0)
          )
          (stroke (width 0) (type default) (color 0 0 0 0))
          (fill (type none))
        )
        (polyline
          (pts
            (xy 8.89 -8.89)
            (xy 8.89 -11.43)
          )
          (stroke (width 0.254) (type default) (color 0 0 0 0))
          (fill (type none))
        )
        (polyline
          (pts
            (xy 8.89 -3.81)
            (xy 8.89 -6.35)
          )
          (stroke (width 0.254) (type default) (color 0 0 0 0))
          (fill (type none))
        )
        (polyline
          (pts
            (xy 8.89 1.27)
            (xy 8.89 -1.27)
          )
          (stroke (width 0.254) (type default) (color 0 0 0 0))
          (fill (type none))
        )
        (polyline
          (pts
            (xy 12.7 -5.08)
            (xy 2.54 -5.08)
          )
          (stroke (width 0) (type default) (color 0 0 0 0))
          (fill (type none))
        )
        (polyline
          (pts
            (xy 6.35 -8.89)
            (xy 6.35 -11.43)
            (xy 8.89 -10.16)
            (xy 6.35 -8.89)
          )
          (stroke (width 0.254) (type default) (color 0 0 0 0))
          (fill (type outline))
        )
        (polyline
          (pts
            (xy 6.35 -3.81)
            (xy 6.35 -6.35)
            (xy 8.89 -5.08)
            (xy 6.35 -3.81)
          )
          (stroke (width 0.254) (type default) (color 0 0 0 0))
          (fill (type outline))
        )
        (polyline
          (pts
            (xy 6.35 1.27)
            (xy 6.35 -1.27)
            (xy 8.89 0)
            (xy 6.35 1.27)
          )
          (stroke (width 0.254) (type default) (color 0 0 0 0))
          (fill (type outline))
        )
        (polyline
          (pts
            (xy 9.525 -8.89)
            (xy 10.795 -7.62)
            (xy 10.16 -7.62)
            (xy 10.795 -7.62)
            (xy 10.795 -8.255)
          )
          (stroke (width 0.254) (type default) (color 0 0 0 0))
          (fill (type none))
        )
        (polyline
          (pts
            (xy 9.525 -3.81)
            (xy 10.795 -2.54)
            (xy 10.16 -2.54)
            (xy 10.795 -2.54)
            (xy 10.795 -3.175)
          )
          (stroke (width 0.254) (type default) (color 0 0 0 0))
          (fill (type none))
        )
        (polyline
          (pts
            (xy 9.525 1.27)
            (xy 10.795 2.54)
            (xy 10.16 2.54)
            (xy 10.795 2.54)
            (xy 10.795 1.905)
          )
          (stroke (width 0.254) (type default) (color 0 0 0 0))
          (fill (type none))
        )
        (polyline
          (pts
            (xy 8.89 -7.62)
            (xy 8.89 -8.255)
            (xy 8.89 -7.62)
            (xy 8.255 -7.62)
            (xy 8.89 -7.62)
            (xy 7.62 -8.89)
          )
          (stroke (width 0.254) (type default) (color 0 0 0 0))
          (fill (type none))
        )
        (polyline
          (pts
            (xy 8.89 -2.54)
            (xy 8.89 -3.175)
            (xy 8.89 -2.54)
            (xy 8.255 -2.54)
            (xy 8.89 -2.54)
            (xy 7.62 -3.81)
          )
          (stroke (width 0.254) (type default) (color 0 0 0 0))
          (fill (type none))
        )
        (polyline
          (pts
            (xy 8.89 2.54)
            (xy 8.89 1.905)
            (xy 8.89 2.54)
            (xy 8.255 2.54)
            (xy 8.89 2.54)
            (xy 7.62 1.27)
          )
          (stroke (width 0.254) (type default) (color 0 0 0 0))
          (fill (type none))
        )
        (rectangle (start 2.54 3.81) (end 12.7 -13.97)
          (stroke (width 0.254) (type default) (color 0 0 0 0))
          (fill (type background))
        )
        (pin passive line (at 15.24 -10.16 180) (length 2.54)
          (name "1" (effects (font (size 1.27 1.27))))
          (number "1" (effects (font (size 1.27 1.27))))
        )
        (pin passive line (at 15.24 -5.08 180) (length 2.54)
          (name "2" (effects (font (size 1.27 1.27))))
          (number "2" (effects (font (size 1.27 1.27))))
        )
        (pin passive line (at 15.24 0 180) (length 2.54)
          (name "3" (effects (font (size 1.27 1.27))))
          (number "3" (effects (font (size 1.27 1.27))))
        )
        (pin passive line (at 0 0 0) (length 2.54)
          (name "4" (effects (font (size 1.27 1.27))))
          (number "4" (effects (font (size 1.27 1.27))))
        )
        (pin passive line (at 0 -5.08 0) (length 2.54)
          (name "5" (effects (font (size 1.27 1.27))))
          (number "5" (effects (font (size 1.27 1.27))))
        )
        (pin passive line (at 0 -10.16 0) (length 2.54)
          (name "6" (effects (font (size 1.27 1.27))))
          (number "6" (effects (font (size 1.27 1.27))))
        )
      )
    )
	(symbol "sa800u-baseboard-hw:BM04B-SRSS-TB-LF-SN" (pin_names hide) (in_bom yes) (on_board yes)
      (property "Reference" "J" (id 0) (at 20.32 -5.08 0)
        (effects (font (size 1.27 1.27) (thickness 0.15)) (justify left bottom))
      )
      (property "Value" "BM04B-SRSS-TB-LF-SN" (id 1) (at 20.32 -7.62 0)
        (effects (font (size 1.27 1.27) (thickness 0.15)) (justify left bottom))
      )
      (property "Footprint" "sa800u-baseboard-hw-footprints:BM04B-SRSS-TB-LF-SN" (id 2) (at 20.32 -10.16 0)
        (effects (font (size 1.27 1.27) (thickness 0.15)) (justify left bottom) hide)
      )
      (property "Datasheet" "https://www.jst-mfg.com/product/pdf/eng/eSH.pdf" (id 3) (at 20.32 -12.7 0)
        (effects (font (size 1.27 1.27) (thickness 0.15)) (justify left bottom) hide)
      )
      (property "MPN" "BM04B-SRSS-TB(LF)(SN) " (id 4) (at 20.32 -15.24 0)
        (effects (font (size 1.27 1.27) (thickness 0.15)) (justify left bottom) hide)
      )
      (property "Manufacturer" "JST" (id 5) (at 20.32 -17.78 0)
        (effects (font (size 1.27 1.27) (thickness 0.15)) (justify left bottom) hide)
      )
      (property "Author" "Antmicro" (id 6) (at 20.32 -20.32 0)
        (effects (font (size 1.27 1.27) (thickness 0.15)) (justify left bottom) hide)
      )
      (property "License" "Apache-2.0" (id 7) (at 20.32 -22.86 0)
        (effects (font (size 1.27 1.27) (thickness 0.15)) (justify left bottom) hide)
      )
      (property "ki_keywords" "QWIIC" (id 8) (at 0 0 0)
        (effects (font (size 1.27 1.27)) hide)
      )
      (property "ki_description" "Connector Header Surface Mount Vertical 4 position 0.039\" (1.00mm)" (id 9) (at 0 0 0)
        (effects (font (size 1.27 1.27)) hide)
      )
      (symbol "BM04B-SRSS-TB-LF-SN_1_1"
        (rectangle (start 2.54 -7.493) (end 3.81 -7.747)
          (stroke (width 0.254) (type default) (color 0 0 0 0))
          (fill (type background))
        )
        (rectangle (start 2.54 -4.953) (end 3.81 -5.207)
          (stroke (width 0.254) (type default) (color 0 0 0 0))
          (fill (type background))
        )
        (rectangle (start 2.54 -2.413) (end 3.81 -2.667)
          (stroke (width 0.254) (type default) (color 0 0 0 0))
          (fill (type background))
        )
        (rectangle (start 2.54 0.127) (end 3.81 -0.127)
          (stroke (width 0.254) (type default) (color 0 0 0 0))
          (fill (type background))
        )
        (rectangle (start 2.54 1.27) (end 5.08 -11.43)
          (stroke (width 0.254) (type default) (color 0 0 0 0))
          (fill (type background))
        )
        (pin passive line (at 0 0 0) (length 2.54)
          (name "Pin_1" (effects (font (size 1.27 1.27))))
          (number "1" (effects (font (size 1.27 1.27))))
        )
        (pin passive line (at 0 -2.54 0) (length 2.54)
          (name "Pin_2" (effects (font (size 1.27 1.27))))
          (number "2" (effects (font (size 1.27 1.27))))
        )
        (pin passive line (at 0 -5.08 0) (length 2.54)
          (name "Pin_3" (effects (font (size 1.27 1.27))))
          (number "3" (effects (font (size 1.27 1.27))))
        )
        (pin passive line (at 0 -7.62 0) (length 2.54)
          (name "Pin_4" (effects (font (size 1.27 1.27))))
          (number "4" (effects (font (size 1.27 1.27))))
        )
        (pin passive line (at 0 -10.16 0) (length 2.54)
          (name "MP" (effects (font (size 1.27 1.27))))
          (number "MP" (effects (font (size 1.27 1.27))))
        )
      )
    )
	(symbol "sa800u-baseboard-hw:BSS138PW" (pin_names (offset 0)) (in_bom yes) (on_board yes)
      (property "Reference" "Q" (id 0) (at 3.81 -6.35 0)
        (effects (font (size 1.27 1.27) (thickness 0.15)) (justify left bottom))
      )
      (property "Value" "BSS138PW" (id 1) (at 22.86 -8.89 0)
        (effects (font (size 1.27 1.27) (thickness 0.15)) (justify left bottom))
      )
      (property "Footprint" "sa800u-baseboard-hw-footprints:SC70-3" (id 2) (at 22.86 -11.43 0)
        (effects (font (size 1.27 1.27) (thickness 0.15)) (justify left bottom) hide)
      )
      (property "Datasheet" "https://assets.nexperia.com/documents/data-sheet/BSS138PW.pdf" (id 3) (at 22.86 -13.97 0)
        (effects (font (size 1.27 1.27) (thickness 0.15)) (justify left bottom) hide)
      )
      (property "MPN" "BSS138PW" (id 4) (at 22.86 -16.51 0)
        (effects (font (size 1.27 1.27) (thickness 0.15)) (justify left bottom) hide)
      )
      (property "Manufacturer" "Nexperia" (id 5) (at 22.86 -19.05 0)
        (effects (font (size 1.27 1.27) (thickness 0.15)) (justify left bottom) hide)
      )
      (property "Author" "Antmicro" (id 6) (at 22.86 -21.59 0)
        (effects (font (size 1.27 1.27) (thickness 0.15)) (justify left bottom) hide)
      )
      (property "License" "Apache-2.0" (id 7) (at 22.86 -24.13 0)
        (effects (font (size 1.27 1.27) (thickness 0.15)) (justify left bottom) hide)
      )
      (property "ki_keywords" "n-channel enhancement mosfet sc70 sc-70 sot-323 sot323" (id 8) (at 0 0 0)
        (effects (font (size 1.27 1.27)) hide)
      )
      (property "ki_description" "60 V, 320 mA N-channel enhancement mode Trench MOSFET, SC-70-3 aka SOT-323 package" (id 9) (at 0 0 0)
        (effects (font (size 1.27 1.27)) hide)
      )
      (symbol "BSS138PW_1_1"
        (polyline
          (pts
            (xy 5.08 1.143)
            (xy 5.08 0.635)
          )
          (stroke (width 0.254) (type default) (color 0 0 0 0))
          (fill (type background))
        )
        (polyline
          (pts
            (xy 5.08 1.143)
            (xy 5.08 1.651)
          )
          (stroke (width 0.254) (type default) (color 0 0 0 0))
          (fill (type background))
        )
        (polyline
          (pts
            (xy 5.08 2.54)
            (xy 5.08 2.032)
          )
          (stroke (width 0.254) (type default) (color 0 0 0 0))
          (fill (type background))
        )
        (polyline
          (pts
            (xy 5.08 2.54)
            (xy 5.08 3.048)
          )
          (stroke (width 0.254) (type default) (color 0 0 0 0))
          (fill (type background))
        )
        (polyline
          (pts
            (xy 5.08 4.445)
            (xy 5.08 3.429)
          )
          (stroke (width 0.254) (type default) (color 0 0 0 0))
          (fill (type background))
        )
        (polyline
          (pts
            (xy 7.62 1.143)
            (xy 5.08 1.143)
          )
          (stroke (width 0.254) (type default) (color 0 0 0 0))
          (fill (type background))
        )
        (polyline
          (pts
            (xy 9.144 3.048)
            (xy 8.128 3.048)
          )
          (stroke (width 0.254) (type default) (color 0 0 0 0))
          (fill (type background))
        )
        (polyline
          (pts
            (xy 2.54 0)
            (xy 4.572 0)
            (xy 4.572 3.937)
          )
          (stroke (width 0.254) (type default) (color 0 0 0 0))
          (fill (type none))
        )
        (polyline
          (pts
            (xy 7.62 -1.27)
            (xy 7.62 2.54)
            (xy 5.08 2.54)
          )
          (stroke (width 0.254) (type default) (color 0 0 0 0))
          (fill (type background))
        )
        (polyline
          (pts
            (xy 7.62 6.35)
            (xy 7.62 3.937)
            (xy 5.08 3.937)
          )
          (stroke (width 0.254) (type default) (color 0 0 0 0))
          (fill (type background))
        )
        (polyline
          (pts
            (xy 5.08 2.54)
            (xy 5.842 3.048)
            (xy 5.842 2.032)
            (xy 5.08 2.54)
          )
          (stroke (width 0.254) (type default) (color 0 0 0 0))
          (fill (type outline))
        )
        (polyline
          (pts
            (xy 8.636 3.048)
            (xy 8.128 2.286)
            (xy 9.144 2.286)
            (xy 8.636 3.048)
          )
          (stroke (width 0.254) (type default) (color 0 0 0 0))
          (fill (type outline))
        )
        (polyline
          (pts
            (xy 7.493 0.635)
            (xy 8.636 0.635)
            (xy 8.636 3.937)
            (xy 8.636 4.445)
            (xy 7.493 4.445)
          )
          (stroke (width 0.254) (type default) (color 0 0 0 0))
          (fill (type background))
        )
        (circle (center 6.35 2.54) (radius 3.302)
          (stroke (width 0.254) (type default) (color 0 0 0 0))
          (fill (type background))
        )
        (circle (center 7.62 0.635) (radius 0.127)
          (stroke (width 0.254) (type default) (color 0 0 0 0))
          (fill (type background))
        )
        (circle (center 7.62 1.143) (radius 0.127)
          (stroke (width 0.254) (type default) (color 0 0 0 0))
          (fill (type background))
        )
        (circle (center 7.62 4.445) (radius 0.127)
          (stroke (width 0.254) (type default) (color 0 0 0 0))
          (fill (type background))
        )
        (pin bidirectional line (at 0 0 0) (length 2.54)
          (name "G" (effects (font (size 1.27 1.27))))
          (number "1" (effects (font (size 1.27 1.27))))
        )
        (pin bidirectional line (at 7.62 -3.81 90) (length 2.54)
          (name "S" (effects (font (size 1.27 1.27))))
          (number "2" (effects (font (size 1.27 1.27))))
        )
        (pin bidirectional line (at 7.62 8.89 270) (length 2.54)
          (name "D" (effects (font (size 1.27 1.27))))
          (number "3" (effects (font (size 1.27 1.27))))
        )
      )
    )
	(symbol "sa800u-baseboard-hw:BSS84" (pin_names (offset 0)) (in_bom yes) (on_board yes)
      (property "Reference" "Q" (id 0) (at 16.51 -2.54 0)
        (effects (font (size 1.27 1.27) (thickness 0.15)) (justify left bottom))
      )
      (property "Value" "BSS84" (id 1) (at 16.51 -7.62 0)
        (effects (font (size 1.27 1.27) (thickness 0.15)) (justify left bottom) hide)
      )
      (property "Footprint" "sa800u-baseboard-hw-footprints:SOT-23-3" (id 2) (at 16.51 -10.16 0)
        (effects (font (size 1.27 1.27) (thickness 0.15)) (justify left bottom) hide)
      )
      (property "Datasheet" "https://www.onsemi.com/pub/Collateral/BSS84-D.PDF" (id 3) (at 16.51 -12.7 0)
        (effects (font (size 1.27 1.27) (thickness 0.15)) (justify left bottom) hide)
      )
      (property "MPN" "BSS84" (id 4) (at 16.51 -5.08 0)
        (effects (font (size 1.27 1.27) (thickness 0.15)) (justify left bottom))
      )
      (property "Manufacturer" "ON Semiconductor" (id 5) (at 16.51 -15.24 0)
        (effects (font (size 1.27 1.27) (thickness 0.15)) (justify left bottom) hide)
      )
      (property "Author" "Antmicro" (id 6) (at 16.51 -17.78 0)
        (effects (font (size 1.27 1.27) (thickness 0.15)) (justify left bottom) hide)
      )
      (property "License" "Apache-2.0" (id 7) (at 16.51 -20.32 0)
        (effects (font (size 1.27 1.27) (thickness 0.15)) (justify left bottom) hide)
      )
      (symbol "BSS84_1_1"
        (polyline
          (pts
            (xy 5.08 1.143)
            (xy 5.08 0.635)
          )
          (stroke (width 0.254) (type default) (color 0 0 0 0))
          (fill (type background))
        )
        (polyline
          (pts
            (xy 5.08 1.143)
            (xy 5.08 1.651)
          )
          (stroke (width 0.254) (type default) (color 0 0 0 0))
          (fill (type background))
        )
        (polyline
          (pts
            (xy 5.08 2.54)
            (xy 5.08 2.032)
          )
          (stroke (width 0.254) (type default) (color 0 0 0 0))
          (fill (type background))
        )
        (polyline
          (pts
            (xy 5.08 2.54)
            (xy 5.08 3.048)
          )
          (stroke (width 0.254) (type default) (color 0 0 0 0))
          (fill (type background))
        )
        (polyline
          (pts
            (xy 5.08 4.445)
            (xy 5.08 3.429)
          )
          (stroke (width 0.254) (type default) (color 0 0 0 0))
          (fill (type background))
        )
        (polyline
          (pts
            (xy 7.62 1.143)
            (xy 5.08 1.143)
          )
          (stroke (width 0.254) (type default) (color 0 0 0 0))
          (fill (type background))
        )
        (polyline
          (pts
            (xy 9.144 2.3368)
            (xy 8.128 2.3368)
          )
          (stroke (width 0.254) (type default) (color 0 0 0 0))
          (fill (type background))
        )
        (polyline
          (pts
            (xy 2.54 0)
            (xy 4.572 0)
            (xy 4.572 3.937)
          )
          (stroke (width 0.254) (type default) (color 0 0 0 0))
          (fill (type none))
        )
        (polyline
          (pts
            (xy 7.62 -1.27)
            (xy 7.62 2.54)
            (xy 5.08 2.54)
          )
          (stroke (width 0.254) (type default) (color 0 0 0 0))
          (fill (type none))
        )
        (polyline
          (pts
            (xy 7.62 6.35)
            (xy 7.62 3.937)
            (xy 5.08 3.937)
          )
          (stroke (width 0.254) (type default) (color 0 0 0 0))
          (fill (type none))
        )
        (polyline
          (pts
            (xy 7.239 2.54)
            (xy 6.477 3.048)
            (xy 6.477 2.032)
            (xy 7.239 2.54)
          )
          (stroke (width 0.254) (type default) (color 0 0 0 0))
          (fill (type outline))
        )
        (polyline
          (pts
            (xy 8.636 2.286)
            (xy 9.144 3.048)
            (xy 8.128 3.048)
            (xy 8.636 2.286)
          )
          (stroke (width 0.254) (type default) (color 0 0 0 0))
          (fill (type outline))
        )
        (polyline
          (pts
            (xy 7.493 0.635)
            (xy 8.636 0.635)
            (xy 8.636 3.937)
            (xy 8.636 4.445)
            (xy 7.493 4.445)
          )
          (stroke (width 0.254) (type default) (color 0 0 0 0))
          (fill (type background))
        )
        (circle (center 6.35 2.54) (radius 3.302)
          (stroke (width 0.254) (type default) (color 0 0 0 0))
          (fill (type background))
        )
        (circle (center 7.62 0.635) (radius 0.127)
          (stroke (width 0.254) (type default) (color 0 0 0 0))
          (fill (type background))
        )
        (circle (center 7.62 1.143) (radius 0.127)
          (stroke (width 0.254) (type default) (color 0 0 0 0))
          (fill (type background))
        )
        (circle (center 7.62 4.445) (radius 0.127)
          (stroke (width 0.254) (type default) (color 0 0 0 0))
          (fill (type background))
        )
        (pin bidirectional line (at 0 0 0) (length 2.54)
          (name "G" (effects (font (size 1.27 1.27))))
          (number "1" (effects (font (size 1.27 1.27))))
        )
        (pin bidirectional line (at 7.62 8.89 270) (length 2.54)
          (name "D" (effects (font (size 1.27 1.27))))
          (number "2" (effects (font (size 1.27 1.27))))
        )
        (pin bidirectional line (at 7.62 -3.81 90) (length 2.54)
          (name "S" (effects (font (size 1.27 1.27))))
          (number "3" (effects (font (size 1.27 1.27))))
        )
      )
    )
	(symbol "sa800u-baseboard-hw:BSS84PH6327XTSA2" (pin_names (offset 0)) (in_bom yes) (on_board yes)
      (property "Reference" "Q" (id 0) (at 12.7 -2.54 0)
        (effects (font (size 1.27 1.27) (thickness 0.15)) (justify left bottom))
      )
      (property "Value" "BSS84PH6327XTSA2" (id 1) (at 12.7 -7.62 0)
        (effects (font (size 1.27 1.27) (thickness 0.15)) (justify left bottom) hide)
      )
      (property "Footprint" "sa800u-baseboard-hw-footprints:SOT-23-3" (id 2) (at 12.7 -10.16 0)
        (effects (font (size 1.27 1.27) (thickness 0.15)) (justify left bottom) hide)
      )
      (property "Datasheet" "https://www.mouser.pl/datasheet/2/196/Infineon-BSS84PW-DS-v02_00-EN-1225586.pdf" (id 3) (at 12.7 -12.7 0)
        (effects (font (size 1.27 1.27) (thickness 0.15)) (justify left bottom) hide)
      )
      (property "MPN" "BSS84PH6327XTSA2" (id 4) (at 12.7 -5.08 0)
        (effects (font (size 1.27 1.27) (thickness 0.15)) (justify left bottom))
      )
      (property "Manufacturer" "Infineon Technologies" (id 5) (at 12.7 -15.24 0)
        (effects (font (size 1.27 1.27) (thickness 0.15)) (justify left bottom) hide)
      )
      (property "Author" "Antmicro" (id 6) (at 12.7 -17.78 0)
        (effects (font (size 1.27 1.27) (thickness 0.15)) (justify left bottom) hide)
      )
      (property "License" "Apache-2.0" (id 7) (at 12.7 -20.32 0)
        (effects (font (size 1.27 1.27) (thickness 0.15)) (justify left bottom) hide)
      )
      (symbol "BSS84PH6327XTSA2_1_1"
        (polyline
          (pts
            (xy 5.08 1.143)
            (xy 5.08 0.635)
          )
          (stroke (width 0.254) (type default) (color 0 0 0 0))
          (fill (type background))
        )
        (polyline
          (pts
            (xy 5.08 1.143)
            (xy 5.08 1.651)
          )
          (stroke (width 0.254) (type default) (color 0 0 0 0))
          (fill (type background))
        )
        (polyline
          (pts
            (xy 5.08 2.54)
            (xy 5.08 2.032)
          )
          (stroke (width 0.254) (type default) (color 0 0 0 0))
          (fill (type background))
        )
        (polyline
          (pts
            (xy 5.08 2.54)
            (xy 5.08 3.048)
          )
          (stroke (width 0.254) (type default) (color 0 0 0 0))
          (fill (type background))
        )
        (polyline
          (pts
            (xy 5.08 4.445)
            (xy 5.08 3.429)
          )
          (stroke (width 0.254) (type default) (color 0 0 0 0))
          (fill (type background))
        )
        (polyline
          (pts
            (xy 7.62 1.143)
            (xy 5.08 1.143)
          )
          (stroke (width 0.254) (type default) (color 0 0 0 0))
          (fill (type background))
        )
        (polyline
          (pts
            (xy 9.144 2.3368)
            (xy 8.128 2.3368)
          )
          (stroke (width 0.254) (type default) (color 0 0 0 0))
          (fill (type background))
        )
        (polyline
          (pts
            (xy 2.54 0)
            (xy 4.572 0)
            (xy 4.572 3.937)
          )
          (stroke (width 0.254) (type default) (color 0 0 0 0))
          (fill (type none))
        )
        (polyline
          (pts
            (xy 7.62 -1.27)
            (xy 7.62 2.54)
            (xy 5.08 2.54)
          )
          (stroke (width 0.254) (type default) (color 0 0 0 0))
          (fill (type none))
        )
        (polyline
          (pts
            (xy 7.62 6.35)
            (xy 7.62 3.937)
            (xy 5.08 3.937)
          )
          (stroke (width 0.254) (type default) (color 0 0 0 0))
          (fill (type none))
        )
        (polyline
          (pts
            (xy 7.239 2.54)
            (xy 6.477 3.048)
            (xy 6.477 2.032)
            (xy 7.239 2.54)
          )
          (stroke (width 0.254) (type default) (color 0 0 0 0))
          (fill (type outline))
        )
        (polyline
          (pts
            (xy 8.636 2.286)
            (xy 9.144 3.048)
            (xy 8.128 3.048)
            (xy 8.636 2.286)
          )
          (stroke (width 0.254) (type default) (color 0 0 0 0))
          (fill (type outline))
        )
        (polyline
          (pts
            (xy 7.493 0.635)
            (xy 8.636 0.635)
            (xy 8.636 3.937)
            (xy 8.636 4.445)
            (xy 7.493 4.445)
          )
          (stroke (width 0.254) (type default) (color 0 0 0 0))
          (fill (type background))
        )
        (circle (center 6.35 2.54) (radius 3.302)
          (stroke (width 0.254) (type default) (color 0 0 0 0))
          (fill (type background))
        )
        (circle (center 7.62 0.635) (radius 0.127)
          (stroke (width 0.254) (type default) (color 0 0 0 0))
          (fill (type background))
        )
        (circle (center 7.62 1.143) (radius 0.127)
          (stroke (width 0.254) (type default) (color 0 0 0 0))
          (fill (type background))
        )
        (circle (center 7.62 4.445) (radius 0.127)
          (stroke (width 0.254) (type default) (color 0 0 0 0))
          (fill (type background))
        )
        (pin bidirectional line (at 0 0 0) (length 2.54)
          (name "G" (effects (font (size 1.27 1.27))))
          (number "1" (effects (font (size 1.27 1.27))))
        )
        (pin bidirectional line (at 7.62 8.89 270) (length 2.54)
          (name "D" (effects (font (size 1.27 1.27))))
          (number "2" (effects (font (size 1.27 1.27))))
        )
        (pin bidirectional line (at 7.62 -3.81 90) (length 2.54)
          (name "S" (effects (font (size 1.27 1.27))))
          (number "3" (effects (font (size 1.27 1.27))))
        )
      )
    )
	(symbol "sa800u-baseboard-hw:Battery_Holder_MS621FE-FL11E" (pin_names hide) (in_bom yes) (on_board yes)
      (property "Reference" "BAT" (id 0) (at 17.78 -6.35 0)
        (effects (font (size 1.27 1.27) (thickness 0.15)) (justify left bottom))
      )
      (property "Value" "Battery_Holder_MS621FE-FL11E" (id 1) (at 17.78 -8.89 0)
        (effects (font (size 1.27 1.27) (thickness 0.15)) (justify left bottom))
      )
      (property "Footprint" "sa800u-baseboard-hw-footprints:MS621FE-FL11E" (id 2) (at 17.78 -11.43 0)
        (effects (font (size 1.27 1.27) (thickness 0.15)) (justify left bottom) hide)
      )
      (property "Datasheet" "https://www.sii.co.jp/en/me/datasheets/ms-rechargeable/ms621fe/" (id 3) (at 17.78 -13.97 0)
        (effects (font (size 1.27 1.27) (thickness 0.15)) (justify left bottom) hide)
      )
      (property "Manufacturer" "Seiko" (id 4) (at 17.78 -16.51 0)
        (effects (font (size 1.27 1.27) (thickness 0.15)) (justify left bottom) hide)
      )
      (property "MPN" "MS621FE-FL11E" (id 5) (at 17.78 -19.05 0)
        (effects (font (size 1.27 1.27) (thickness 0.15)) (justify left bottom) hide)
      )
      (property "Author" "Antmicro" (id 6) (at 17.78 -21.59 0)
        (effects (font (size 1.27 1.27) (thickness 0.15)) (justify left bottom) hide)
      )
      (property "License" "Apache-2.0" (id 7) (at 17.78 -24.13 0)
        (effects (font (size 1.27 1.27) (thickness 0.15)) (justify left bottom) hide)
      )
      (symbol "Battery_Holder_MS621FE-FL11E_0_1"
        (rectangle (start -1.27 -5.08) (end 1.27 -4.826)
          (stroke (width 0.254) (type default) (color 0 0 0 0))
          (fill (type outline))
        )
        (polyline
          (pts
            (xy 0 -2.54)
            (xy 0 -3.81)
          )
          (stroke (width 0.254) (type default) (color 0 0 0 0))
          (fill (type none))
        )
      )
      (symbol "Battery_Holder_MS621FE-FL11E_1_1"
        (polyline
          (pts
            (xy -2.54 -3.81)
            (xy 2.54 -3.81)
          )
          (stroke (width 0.254) (type default) (color 0 0 0 0))
          (fill (type background))
        )
        (polyline
          (pts
            (xy 0 -6.35)
            (xy 0 -5.08)
          )
          (stroke (width 0.254) (type default) (color 0 0 0 0))
          (fill (type background))
        )
        (pin passive line (at 0 0 270) (length 2.54)
          (name "+" (effects (font (size 1.27 1.27))))
          (number "+" (effects (font (size 1.27 1.27))))
        )
        (pin passive line (at 0 -8.89 90) (length 2.54)
          (name "-" (effects (font (size 1.27 1.27))))
          (number "-" (effects (font (size 1.27 1.27))))
        )
      )
    )
	(symbol "sa800u-baseboard-hw:Bus_M.2_MDT580M01001" (in_bom yes) (on_board yes)
      (property "Reference" "U" (id 0) (at 52.07 -2.54 0)
        (effects (font (size 1.27 1.27) (thickness 0.15)) (justify left bottom))
      )
      (property "Value" "Bus_M.2_MDT580M01001" (id 1) (at 52.07 -5.08 0)
        (effects (font (size 1.27 1.27) (thickness 0.15)) (justify left bottom))
      )
      (property "Footprint" "sa800u-baseboard-hw-footprints:Bus_M.2_Socket_Key_M_Amphenol_MDT580M01001" (id 2) (at 52.07 -7.62 0)
        (effects (font (size 1.27 1.27) (thickness 0.15)) (justify left bottom) hide)
      )
      (property "Datasheet" "https://cdn.amphenol-cs.com/media/wysiwyg/files/documentation/gs-12-1248.pdf" (id 3) (at 52.07 -10.16 0)
        (effects (font (size 1.27 1.27) (thickness 0.15)) (justify left bottom) hide)
      )
      (property "MPN" "MDT580M01001" (id 4) (at 52.07 -12.7 0)
        (effects (font (size 1.27 1.27) (thickness 0.15)) (justify left bottom) hide)
      )
      (property "Manufacturer" "Amphenol" (id 5) (at 52.07 -15.24 0)
        (effects (font (size 1.27 1.27) (thickness 0.15)) (justify left bottom) hide)
      )
      (property "Author" "Antmicro" (id 6) (at 52.07 -17.78 0)
        (effects (font (size 1.27 1.27) (thickness 0.15)) (justify left bottom) hide)
      )
      (property "License" "Apache-2.0" (id 7) (at 52.07 -20.32 0)
        (effects (font (size 1.27 1.27) (thickness 0.15)) (justify left bottom) hide)
      )
      (property "ki_description" "PCI Express / PCI Connectors M.2 RA M Key 5.80H" (id 8) (at 0 0 0)
        (effects (font (size 1.27 1.27)) hide)
      )
      (symbol "Bus_M.2_MDT580M01001_0_0"
        (text "KEY-M" (at 19.05 -10.16 0)
          (effects (font (size 1.27 1.27) bold))
        )
      )
      (symbol "Bus_M.2_MDT580M01001_1_1"
        (rectangle (start 3.81 2.54) (end 34.29 -67.31)
          (stroke (width 0.254) (type default) (color 0 0 0 0))
          (fill (type background))
        )
        (pin passive line (at 0 -64.77 0) (length 3.81)
          (name "GND" (effects (font (size 1.27 1.27))))
          (number "1" (effects (font (size 1.27 1.27))))
        )
        (pin passive line (at 0 -39.37 0) (length 3.81)
          (name "LED" (effects (font (size 1.27 1.27))))
          (number "10" (effects (font (size 1.27 1.27))))
        )
        (pin passive line (at 38.1 -57.15 180) (length 3.81)
          (name "PET3_N" (effects (font (size 1.27 1.27))))
          (number "11" (effects (font (size 1.27 1.27))))
        )
        (pin passive line (at 0 0 0) (length 3.81)
          (name "3V3" (effects (font (size 1.27 1.27))))
          (number "12" (effects (font (size 1.27 1.27))))
        )
        (pin passive line (at 38.1 -54.61 180) (length 3.81)
          (name "PET3_P" (effects (font (size 1.27 1.27))))
          (number "13" (effects (font (size 1.27 1.27))))
        )
        (pin passive line (at 0 0 0) (length 3.81) hide
          (name "3V3" (effects (font (size 1.27 1.27))))
          (number "14" (effects (font (size 1.27 1.27))))
        )
        (pin passive line (at 0 -64.77 0) (length 3.81) hide
          (name "GND" (effects (font (size 1.27 1.27))))
          (number "15" (effects (font (size 1.27 1.27))))
        )
        (pin passive line (at 0 0 0) (length 3.81) hide
          (name "3V3" (effects (font (size 1.27 1.27))))
          (number "16" (effects (font (size 1.27 1.27))))
        )
        (pin passive line (at 38.1 -49.53 180) (length 3.81)
          (name "PER2_N" (effects (font (size 1.27 1.27))))
          (number "17" (effects (font (size 1.27 1.27))))
        )
        (pin passive line (at 0 0 0) (length 3.81) hide
          (name "3V3" (effects (font (size 1.27 1.27))))
          (number "18" (effects (font (size 1.27 1.27))))
        )
        (pin passive line (at 38.1 -46.99 180) (length 3.81)
          (name "PER2_P" (effects (font (size 1.27 1.27))))
          (number "19" (effects (font (size 1.27 1.27))))
        )
        (pin passive line (at 0 0 0) (length 3.81) hide
          (name "3V3" (effects (font (size 1.27 1.27))))
          (number "2" (effects (font (size 1.27 1.27))))
        )
        (pin no_connect line (at 3.81 -59.69 0) (length 3.81) hide
          (name "NC" (effects (font (size 1.27 1.27))))
          (number "20" (effects (font (size 1.27 1.27))))
        )
        (pin passive line (at 0 -64.77 0) (length 3.81) hide
          (name "GND" (effects (font (size 1.27 1.27))))
          (number "21" (effects (font (size 1.27 1.27))))
        )
        (pin no_connect line (at 3.81 -59.69 0) (length 3.81) hide
          (name "NC" (effects (font (size 1.27 1.27))))
          (number "22" (effects (font (size 1.27 1.27))))
        )
        (pin passive line (at 38.1 -41.91 180) (length 3.81)
          (name "PET2_N" (effects (font (size 1.27 1.27))))
          (number "23" (effects (font (size 1.27 1.27))))
        )
        (pin no_connect line (at 3.81 -59.69 0) (length 3.81) hide
          (name "NC" (effects (font (size 1.27 1.27))))
          (number "24" (effects (font (size 1.27 1.27))))
        )
        (pin passive line (at 38.1 -39.37 180) (length 3.81)
          (name "PET2_P" (effects (font (size 1.27 1.27))))
          (number "25" (effects (font (size 1.27 1.27))))
        )
        (pin no_connect line (at 3.81 -59.69 0) (length 3.81) hide
          (name "NC" (effects (font (size 1.27 1.27))))
          (number "26" (effects (font (size 1.27 1.27))))
        )
        (pin passive line (at 0 -64.77 0) (length 3.81) hide
          (name "GND" (effects (font (size 1.27 1.27))))
          (number "27" (effects (font (size 1.27 1.27))))
        )
        (pin no_connect line (at 3.81 -59.69 0) (length 3.81) hide
          (name "NC" (effects (font (size 1.27 1.27))))
          (number "28" (effects (font (size 1.27 1.27))))
        )
        (pin passive line (at 38.1 -34.29 180) (length 3.81)
          (name "PER1_N" (effects (font (size 1.27 1.27))))
          (number "29" (effects (font (size 1.27 1.27))))
        )
        (pin passive line (at 0 -64.77 0) (length 3.81) hide
          (name "GND" (effects (font (size 1.27 1.27))))
          (number "3" (effects (font (size 1.27 1.27))))
        )
        (pin no_connect line (at 3.81 -59.69 0) (length 3.81) hide
          (name "NC" (effects (font (size 1.27 1.27))))
          (number "30" (effects (font (size 1.27 1.27))))
        )
        (pin passive line (at 38.1 -31.75 180) (length 3.81)
          (name "PER1_P" (effects (font (size 1.27 1.27))))
          (number "31" (effects (font (size 1.27 1.27))))
        )
        (pin no_connect line (at 3.81 -59.69 0) (length 3.81) hide
          (name "NC" (effects (font (size 1.27 1.27))))
          (number "32" (effects (font (size 1.27 1.27))))
        )
        (pin passive line (at 0 -64.77 0) (length 3.81) hide
          (name "GND" (effects (font (size 1.27 1.27))))
          (number "33" (effects (font (size 1.27 1.27))))
        )
        (pin no_connect line (at 3.81 -59.69 0) (length 3.81) hide
          (name "NC" (effects (font (size 1.27 1.27))))
          (number "34" (effects (font (size 1.27 1.27))))
        )
        (pin passive line (at 38.1 -26.67 180) (length 3.81)
          (name "PET1_N" (effects (font (size 1.27 1.27))))
          (number "35" (effects (font (size 1.27 1.27))))
        )
        (pin no_connect line (at 3.81 -59.69 0) (length 3.81) hide
          (name "NC" (effects (font (size 1.27 1.27))))
          (number "36" (effects (font (size 1.27 1.27))))
        )
        (pin passive line (at 38.1 -24.13 180) (length 3.81)
          (name "PET1_P" (effects (font (size 1.27 1.27))))
          (number "37" (effects (font (size 1.27 1.27))))
        )
        (pin no_connect line (at 3.81 -59.69 0) (length 3.81) hide
          (name "NC" (effects (font (size 1.27 1.27))))
          (number "38" (effects (font (size 1.27 1.27))))
        )
        (pin passive line (at 0 -64.77 0) (length 3.81) hide
          (name "GND" (effects (font (size 1.27 1.27))))
          (number "39" (effects (font (size 1.27 1.27))))
        )
        (pin passive line (at 0 0 0) (length 3.81) hide
          (name "3V3" (effects (font (size 1.27 1.27))))
          (number "4" (effects (font (size 1.27 1.27))))
        )
        (pin passive line (at 0 -36.83 0) (length 3.81)
          (name "SMB_CLK" (effects (font (size 1.27 1.27))))
          (number "40" (effects (font (size 1.27 1.27))))
        )
        (pin passive line (at 38.1 -19.05 180) (length 3.81)
          (name "PER0_N" (effects (font (size 1.27 1.27))))
          (number "41" (effects (font (size 1.27 1.27))))
        )
        (pin passive line (at 0 -34.29 0) (length 3.81)
          (name "SMB_DATA" (effects (font (size 1.27 1.27))))
          (number "42" (effects (font (size 1.27 1.27))))
        )
        (pin passive line (at 38.1 -16.51 180) (length 3.81)
          (name "PER0_P" (effects (font (size 1.27 1.27))))
          (number "43" (effects (font (size 1.27 1.27))))
        )
        (pin passive line (at 0 -31.75 0) (length 3.81)
          (name "ALERT" (effects (font (size 1.27 1.27))))
          (number "44" (effects (font (size 1.27 1.27))))
        )
        (pin passive line (at 0 -64.77 0) (length 3.81) hide
          (name "GND" (effects (font (size 1.27 1.27))))
          (number "45" (effects (font (size 1.27 1.27))))
        )
        (pin no_connect line (at 3.81 -59.69 0) (length 3.81) hide
          (name "NC" (effects (font (size 1.27 1.27))))
          (number "46" (effects (font (size 1.27 1.27))))
        )
        (pin passive line (at 38.1 -11.43 180) (length 3.81)
          (name "PET0_N" (effects (font (size 1.27 1.27))))
          (number "47" (effects (font (size 1.27 1.27))))
        )
        (pin no_connect line (at 3.81 -59.69 0) (length 3.81) hide
          (name "NC" (effects (font (size 1.27 1.27))))
          (number "48" (effects (font (size 1.27 1.27))))
        )
        (pin passive line (at 38.1 -8.89 180) (length 3.81)
          (name "PET0_P" (effects (font (size 1.27 1.27))))
          (number "49" (effects (font (size 1.27 1.27))))
        )
        (pin passive line (at 38.1 -64.77 180) (length 3.81)
          (name "PER3_N" (effects (font (size 1.27 1.27))))
          (number "5" (effects (font (size 1.27 1.27))))
        )
        (pin passive line (at 0 -29.21 0) (length 3.81)
          (name "PERST#" (effects (font (size 1.27 1.27))))
          (number "50" (effects (font (size 1.27 1.27))))
        )
        (pin passive line (at 0 -64.77 0) (length 3.81) hide
          (name "GND" (effects (font (size 1.27 1.27))))
          (number "51" (effects (font (size 1.27 1.27))))
        )
        (pin passive line (at 0 -26.67 0) (length 3.81)
          (name "CLKREQ#" (effects (font (size 1.27 1.27))))
          (number "52" (effects (font (size 1.27 1.27))))
        )
        (pin passive line (at 38.1 -2.54 180) (length 3.81)
          (name "REFCLK_N" (effects (font (size 1.27 1.27))))
          (number "53" (effects (font (size 1.27 1.27))))
        )
        (pin passive line (at 0 -24.13 0) (length 3.81)
          (name "PEWAKE#" (effects (font (size 1.27 1.27))))
          (number "54" (effects (font (size 1.27 1.27))))
        )
        (pin passive line (at 38.1 0 180) (length 3.81)
          (name "REFCLK_P" (effects (font (size 1.27 1.27))))
          (number "55" (effects (font (size 1.27 1.27))))
        )
        (pin no_connect line (at 3.81 -59.69 0) (length 3.81) hide
          (name "NC" (effects (font (size 1.27 1.27))))
          (number "56" (effects (font (size 1.27 1.27))))
        )
        (pin passive line (at 0 -64.77 0) (length 3.81) hide
          (name "GND" (effects (font (size 1.27 1.27))))
          (number "57" (effects (font (size 1.27 1.27))))
        )
        (pin no_connect line (at 3.81 -59.69 0) (length 3.81) hide
          (name "NC" (effects (font (size 1.27 1.27))))
          (number "58" (effects (font (size 1.27 1.27))))
        )
        (pin no_connect line (at 3.81 -59.69 0) (length 3.81) hide
          (name "NC" (effects (font (size 1.27 1.27))))
          (number "6" (effects (font (size 1.27 1.27))))
        )
        (pin no_connect line (at 3.81 -59.69 0) (length 3.81) hide
          (name "NC" (effects (font (size 1.27 1.27))))
          (number "67" (effects (font (size 1.27 1.27))))
        )
        (pin passive line (at 0 -21.59 0) (length 3.81)
          (name "SUSCLK" (effects (font (size 1.27 1.27))))
          (number "68" (effects (font (size 1.27 1.27))))
        )
        (pin no_connect line (at 3.81 -59.69 0) (length 3.81) hide
          (name "NC" (effects (font (size 1.27 1.27))))
          (number "69" (effects (font (size 1.27 1.27))))
        )
        (pin passive line (at 38.1 -62.23 180) (length 3.81)
          (name "PER3_P" (effects (font (size 1.27 1.27))))
          (number "7" (effects (font (size 1.27 1.27))))
        )
        (pin passive line (at 0 0 0) (length 3.81) hide
          (name "3V3" (effects (font (size 1.27 1.27))))
          (number "70" (effects (font (size 1.27 1.27))))
        )
        (pin passive line (at 0 -64.77 0) (length 3.81) hide
          (name "GND" (effects (font (size 1.27 1.27))))
          (number "71" (effects (font (size 1.27 1.27))))
        )
        (pin passive line (at 0 0 0) (length 3.81) hide
          (name "3V3" (effects (font (size 1.27 1.27))))
          (number "72" (effects (font (size 1.27 1.27))))
        )
        (pin passive line (at 0 -64.77 0) (length 3.81) hide
          (name "GND" (effects (font (size 1.27 1.27))))
          (number "73" (effects (font (size 1.27 1.27))))
        )
        (pin passive line (at 0 0 0) (length 3.81) hide
          (name "3V3" (effects (font (size 1.27 1.27))))
          (number "74" (effects (font (size 1.27 1.27))))
        )
        (pin passive line (at 0 -64.77 0) (length 3.81) hide
          (name "GND" (effects (font (size 1.27 1.27))))
          (number "75" (effects (font (size 1.27 1.27))))
        )
        (pin no_connect line (at 3.81 -59.69 0) (length 3.81) hide
          (name "NC" (effects (font (size 1.27 1.27))))
          (number "8" (effects (font (size 1.27 1.27))))
        )
        (pin passive line (at 0 -64.77 0) (length 3.81) hide
          (name "GND" (effects (font (size 1.27 1.27))))
          (number "9" (effects (font (size 1.27 1.27))))
        )
        (pin passive line (at 0 -62.23 0) (length 3.81)
          (name "SHIELD" (effects (font (size 1.27 1.27))))
          (number "SH1" (effects (font (size 1.27 1.27))))
        )
        (pin passive line (at 0 -62.23 0) (length 3.81) hide
          (name "SHIELD" (effects (font (size 1.27 1.27))))
          (number "SH2" (effects (font (size 1.27 1.27))))
        )
      )
    )
	(symbol "sa800u-baseboard-hw:Bus_RJ45_5-2337992-8" (in_bom yes) (on_board yes)
      (property "Reference" "J" (id 0) (at 35.56 -2.54 0)
        (effects (font (size 1.27 1.27) (thickness 0.15)) (justify left bottom))
      )
      (property "Value" "Bus_RJ45_5-2337992-8" (id 1) (at 35.56 -5.08 0)
        (effects (font (size 1.27 1.27) (thickness 0.15)) (justify left bottom))
      )
      (property "Footprint" "sa800u-baseboard-hw-footprints:RJ45_5-2337992-8_Horizontal" (id 2) (at 35.56 -7.62 0)
        (effects (font (size 1.27 1.27) (thickness 0.15)) (justify left bottom) hide)
      )
      (property "Datasheet" "https://www.te.com/commerce/DocumentDelivery/DDEController?Action=showdoc&DocId=Customer+Drawing%7F5-2337992-8%7FA%7Fpdf%7FEnglish%7FENG_CD_5-2337992-8_A.pdf%7F5-2337992-8" (id 3) (at 35.56 -10.16 0)
        (effects (font (size 1.27 1.27) (thickness 0.15)) (justify left bottom) hide)
      )
      (property "MPN" "5-2337992-8" (id 4) (at 35.56 -12.7 0)
        (effects (font (size 1.27 1.27) (thickness 0.15)) (justify left bottom) hide)
      )
      (property "Manufacturer" "TE Connectivity" (id 5) (at 35.56 -15.24 0)
        (effects (font (size 1.27 1.27) (thickness 0.15)) (justify left bottom) hide)
      )
      (property "Author" "Antmicro" (id 6) (at 35.56 -17.78 0)
        (effects (font (size 1.27 1.27) (thickness 0.15)) (justify left bottom) hide)
      )
      (property "License" "Apache-2.0" (id 7) (at 35.56 -20.32 0)
        (effects (font (size 1.27 1.27) (thickness 0.15)) (justify left bottom) hide)
      )
      (property "ki_keywords" "RJ45 PoE Ethernet te connectivity magnetics gigabit power" (id 8) (at 0 0 0)
        (effects (font (size 1.27 1.27)) hide)
      )
      (property "ki_description" "RJ45 Gigabit Ethernet Jack w/ Magnetics and PoE, Single Port, 802.3at Power over Ethernet" (id 9) (at 0 0 0)
        (effects (font (size 1.27 1.27)) hide)
      )
      (property "ki_fp_filters" "CONN18_5-2337992-8_TEC" (id 10) (at 0 0 0)
        (effects (font (size 1.27 1.27)) hide)
      )
      (symbol "Bus_RJ45_5-2337992-8_1_1"
        (polyline
          (pts
            (xy 8.89 -13.97)
            (xy 13.97 -13.97)
          )
          (stroke (width 0.254) (type default) (color 0 0 0 0))
          (fill (type background))
        )
        (polyline
          (pts
            (xy 8.89 -1.27)
            (xy 8.89 -13.97)
          )
          (stroke (width 0.254) (type default) (color 0 0 0 0))
          (fill (type background))
        )
        (polyline
          (pts
            (xy 8.89 -1.27)
            (xy 13.97 -1.27)
          )
          (stroke (width 0.254) (type default) (color 0 0 0 0))
          (fill (type background))
        )
        (polyline
          (pts
            (xy 13.97 -13.97)
            (xy 13.97 -12.7)
          )
          (stroke (width 0.254) (type default) (color 0 0 0 0))
          (fill (type background))
        )
        (polyline
          (pts
            (xy 13.97 -12.7)
            (xy 15.24 -12.7)
          )
          (stroke (width 0.254) (type default) (color 0 0 0 0))
          (fill (type background))
        )
        (polyline
          (pts
            (xy 13.97 -2.54)
            (xy 15.24 -2.54)
          )
          (stroke (width 0.254) (type default) (color 0 0 0 0))
          (fill (type background))
        )
        (polyline
          (pts
            (xy 13.97 -1.27)
            (xy 13.97 -2.54)
          )
          (stroke (width 0.254) (type default) (color 0 0 0 0))
          (fill (type background))
        )
        (polyline
          (pts
            (xy 15.24 -12.7)
            (xy 15.24 -11.43)
          )
          (stroke (width 0.254) (type default) (color 0 0 0 0))
          (fill (type background))
        )
        (polyline
          (pts
            (xy 15.24 -11.43)
            (xy 16.51 -11.43)
          )
          (stroke (width 0.254) (type default) (color 0 0 0 0))
          (fill (type background))
        )
        (polyline
          (pts
            (xy 15.24 -3.81)
            (xy 16.51 -3.81)
          )
          (stroke (width 0.254) (type default) (color 0 0 0 0))
          (fill (type background))
        )
        (polyline
          (pts
            (xy 15.24 -2.54)
            (xy 15.24 -3.81)
          )
          (stroke (width 0.254) (type default) (color 0 0 0 0))
          (fill (type background))
        )
        (polyline
          (pts
            (xy 16.51 -3.81)
            (xy 16.51 -11.43)
          )
          (stroke (width 0.254) (type default) (color 0 0 0 0))
          (fill (type background))
        )
        (rectangle (start 2.54 2.54) (end 19.05 -38.1)
          (stroke (width 0.254) (type default) (color 0 0 0 0))
          (fill (type background))
        )
        (pin bidirectional line (at 0 0 0) (length 2.54)
          (name "P1" (effects (font (size 1.27 1.27))))
          (number "1" (effects (font (size 1.27 1.27))))
        )
        (pin bidirectional line (at 0 -17.78 0) (length 2.54)
          (name "P10" (effects (font (size 1.27 1.27))))
          (number "10" (effects (font (size 1.27 1.27))))
        )
        (pin bidirectional line (at 0 -27.94 0) (length 2.54)
          (name "VC1" (effects (font (size 1.27 1.27))))
          (number "11" (effects (font (size 1.27 1.27))))
        )
        (pin bidirectional line (at 0 -30.48 0) (length 2.54)
          (name "VC2" (effects (font (size 1.27 1.27))))
          (number "12" (effects (font (size 1.27 1.27))))
        )
        (pin bidirectional line (at 0 -33.02 0) (length 2.54)
          (name "VC3" (effects (font (size 1.27 1.27))))
          (number "13" (effects (font (size 1.27 1.27))))
        )
        (pin bidirectional line (at 0 -35.56 0) (length 2.54)
          (name "VC4" (effects (font (size 1.27 1.27))))
          (number "14" (effects (font (size 1.27 1.27))))
        )
        (pin passive line (at 21.59 -27.94 180) (length 2.54)
          (name "LED_GRN+" (effects (font (size 1.27 1.27))))
          (number "15" (effects (font (size 1.27 1.27))))
        )
        (pin passive line (at 21.59 -30.48 180) (length 2.54)
          (name "LED_GRN-" (effects (font (size 1.27 1.27))))
          (number "16" (effects (font (size 1.27 1.27))))
        )
        (pin passive line (at 21.59 -22.86 180) (length 2.54)
          (name "LED_YEL+" (effects (font (size 1.27 1.27))))
          (number "17" (effects (font (size 1.27 1.27))))
        )
        (pin passive line (at 21.59 -25.4 180) (length 2.54)
          (name "LED_YEL-" (effects (font (size 1.27 1.27))))
          (number "18" (effects (font (size 1.27 1.27))))
        )
        (pin passive line (at 21.59 -35.56 180) (length 2.54)
          (name "SHIELD" (effects (font (size 1.27 1.27))))
          (number "19" (effects (font (size 1.27 1.27))))
        )
        (pin bidirectional line (at 0 -2.54 0) (length 2.54)
          (name "P2" (effects (font (size 1.27 1.27))))
          (number "2" (effects (font (size 1.27 1.27))))
        )
        (pin passive line (at 21.59 -35.56 180) (length 2.54) hide
          (name "SHIELD" (effects (font (size 1.27 1.27))))
          (number "20" (effects (font (size 1.27 1.27))))
        )
        (pin bidirectional line (at 0 -5.08 0) (length 2.54)
          (name "P3" (effects (font (size 1.27 1.27))))
          (number "3" (effects (font (size 1.27 1.27))))
        )
        (pin bidirectional line (at 0 -22.86 0) (length 2.54)
          (name "P4" (effects (font (size 1.27 1.27))))
          (number "4" (effects (font (size 1.27 1.27))))
        )
        (pin bidirectional line (at 0 -25.4 0) (length 2.54)
          (name "P5" (effects (font (size 1.27 1.27))))
          (number "5" (effects (font (size 1.27 1.27))))
        )
        (pin bidirectional line (at 0 -7.62 0) (length 2.54)
          (name "P6" (effects (font (size 1.27 1.27))))
          (number "6" (effects (font (size 1.27 1.27))))
        )
        (pin bidirectional line (at 0 -10.16 0) (length 2.54)
          (name "P7" (effects (font (size 1.27 1.27))))
          (number "7" (effects (font (size 1.27 1.27))))
        )
        (pin bidirectional line (at 0 -12.7 0) (length 2.54)
          (name "P8" (effects (font (size 1.27 1.27))))
          (number "8" (effects (font (size 1.27 1.27))))
        )
        (pin bidirectional line (at 0 -15.24 0) (length 2.54)
          (name "P9" (effects (font (size 1.27 1.27))))
          (number "9" (effects (font (size 1.27 1.27))))
        )
      )
    )
	(symbol "sa800u-baseboard-hw:CBTL02043ABQ,115" (in_bom yes) (on_board yes)
      (property "Reference" "U" (id 0) (at 38.1 -3.81 0)
        (effects (font (size 1.27 1.27) (thickness 0.15)) (justify left bottom))
      )
      (property "Value" "CBTL02043ABQ,115" (id 1) (at 38.1 -8.89 0)
        (effects (font (size 1.27 1.27) (thickness 0.15)) (justify left bottom) hide)
      )
      (property "Footprint" "sa800u-baseboard-hw-footprints:DHVQFN-20-1EP_2.5x4.5_P0.5mm" (id 2) (at 38.1 -11.43 0)
        (effects (font (size 1.27 1.27) (thickness 0.15)) (justify left bottom) hide)
      )
      (property "Datasheet" "https://www.nxp.com/docs/en/data-sheet/CBTL02043A_CBTL02043B.pdf" (id 3) (at 38.1 -13.97 0)
        (effects (font (size 1.27 1.27) (thickness 0.15)) (justify left bottom) hide)
      )
      (property "MPN" "CBTL02043ABQ,115" (id 4) (at 38.1 -6.35 0)
        (effects (font (size 1.27 1.27) (thickness 0.15)) (justify left bottom))
      )
      (property "Manufacturer" "Nexperia" (id 5) (at 38.1 -16.51 0)
        (effects (font (size 1.27 1.27) (thickness 0.15)) (justify left bottom) hide)
      )
      (property "Author" "Antmicro" (id 6) (at 38.1 -19.05 0)
        (effects (font (size 1.27 1.27) (thickness 0.15)) (justify left bottom) hide)
      )
      (property "License" "Apache-2.0" (id 7) (at 38.1 -21.59 0)
        (effects (font (size 1.27 1.27) (thickness 0.15)) (justify left bottom) hide)
      )
      (symbol "CBTL02043ABQ,115_1_1"
        (rectangle (start 2.54 -35.56) (end 22.86 2.54)
          (stroke (width 0.254) (type default) (color 0 0 0 0))
          (fill (type background))
        )
        (pin power_in line (at 0 0 0) (length 2.54)
          (name "VDD" (effects (font (size 1.27 1.27))))
          (number "1" (effects (font (size 1.27 1.27))))
        )
        (pin passive line (at 0 0 0) (length 2.54) hide
          (name "VDD" (effects (font (size 1.27 1.27))))
          (number "10" (effects (font (size 1.27 1.27))))
        )
        (pin power_in line (at 0 -33.02 0) (length 2.54)
          (name "GND" (effects (font (size 1.27 1.27))))
          (number "11" (effects (font (size 1.27 1.27))))
        )
        (pin bidirectional line (at 25.4 -31.75 180) (length 2.54)
          (name "C1_N" (effects (font (size 1.27 1.27))))
          (number "12" (effects (font (size 1.27 1.27))))
        )
        (pin bidirectional line (at 25.4 -29.21 180) (length 2.54)
          (name "C1_P" (effects (font (size 1.27 1.27))))
          (number "13" (effects (font (size 1.27 1.27))))
        )
        (pin bidirectional line (at 25.4 -24.13 180) (length 2.54)
          (name "C0_N" (effects (font (size 1.27 1.27))))
          (number "14" (effects (font (size 1.27 1.27))))
        )
        (pin bidirectional line (at 25.4 -21.59 180) (length 2.54)
          (name "C0_P" (effects (font (size 1.27 1.27))))
          (number "15" (effects (font (size 1.27 1.27))))
        )
        (pin bidirectional line (at 25.4 -11.43 180) (length 2.54)
          (name "B1_N" (effects (font (size 1.27 1.27))))
          (number "16" (effects (font (size 1.27 1.27))))
        )
        (pin bidirectional line (at 25.4 -8.89 180) (length 2.54)
          (name "B1_P" (effects (font (size 1.27 1.27))))
          (number "17" (effects (font (size 1.27 1.27))))
        )
        (pin bidirectional line (at 25.4 -3.81 180) (length 2.54)
          (name "B0_N" (effects (font (size 1.27 1.27))))
          (number "18" (effects (font (size 1.27 1.27))))
        )
        (pin bidirectional line (at 25.4 -1.27 180) (length 2.54)
          (name "B0_P" (effects (font (size 1.27 1.27))))
          (number "19" (effects (font (size 1.27 1.27))))
        )
        (pin input line (at 0 -27.94 0) (length 2.54)
          (name "XSD" (effects (font (size 1.27 1.27))))
          (number "2" (effects (font (size 1.27 1.27))))
        )
        (pin passive line (at 0 -33.02 0) (length 2.54) hide
          (name "GND" (effects (font (size 1.27 1.27))))
          (number "20" (effects (font (size 1.27 1.27))))
        )
        (pin passive line (at 0 -33.02 0) (length 2.54) hide
          (name "GND" (effects (font (size 1.27 1.27))))
          (number "21" (effects (font (size 1.27 1.27))))
        )
        (pin bidirectional line (at 0 -6.35 0) (length 2.54)
          (name "A0_P" (effects (font (size 1.27 1.27))))
          (number "3" (effects (font (size 1.27 1.27))))
        )
        (pin bidirectional line (at 0 -8.89 0) (length 2.54)
          (name "A0_N" (effects (font (size 1.27 1.27))))
          (number "4" (effects (font (size 1.27 1.27))))
        )
        (pin passive line (at 0 -33.02 0) (length 2.54) hide
          (name "GND" (effects (font (size 1.27 1.27))))
          (number "5" (effects (font (size 1.27 1.27))))
        )
        (pin passive line (at 0 0 0) (length 2.54) hide
          (name "VDD" (effects (font (size 1.27 1.27))))
          (number "6" (effects (font (size 1.27 1.27))))
        )
        (pin bidirectional line (at 0 -13.97 0) (length 2.54)
          (name "A1_P" (effects (font (size 1.27 1.27))))
          (number "7" (effects (font (size 1.27 1.27))))
        )
        (pin bidirectional line (at 0 -16.51 0) (length 2.54)
          (name "A1_N" (effects (font (size 1.27 1.27))))
          (number "8" (effects (font (size 1.27 1.27))))
        )
        (pin input line (at 0 -22.86 0) (length 2.54)
          (name "SEL" (effects (font (size 1.27 1.27))))
          (number "9" (effects (font (size 1.27 1.27))))
        )
      )
    )
	(symbol "sa800u-baseboard-hw:C_100n_0402" (pin_numbers hide) (pin_names hide) (in_bom yes) (on_board yes)
      (property "Reference" "C" (id 0) (at 20.32 -5.08 0)
        (effects (font (size 1.27 1.27) (thickness 0.15)) (justify left bottom))
      )
      (property "Value" "C_100n_0402" (id 1) (at 20.32 -10.16 0)
        (effects (font (size 1.27 1.27) (thickness 0.15)) (justify left bottom) hide)
      )
      (property "Footprint" "sa800u-baseboard-hw-footprints:C_0402_1005Metric" (id 2) (at 20.32 -12.7 0)
        (effects (font (size 1.27 1.27) (thickness 0.15)) (justify left bottom) hide)
      )
      (property "Datasheet" "https://search.murata.co.jp/Ceramy/image/img/A01X/G101/ENG/GRM155R61H104KE14-01.pdf" (id 3) (at 20.32 -15.24 0)
        (effects (font (size 1.27 1.27) (thickness 0.15)) (justify left bottom) hide)
      )
      (property "MPN" "GRM155R61H104KE14D" (id 4) (at 20.32 -17.78 0)
        (effects (font (size 1.27 1.27) (thickness 0.15)) (justify left bottom) hide)
      )
      (property "Manufacturer" "Murata" (id 5) (at 20.32 -20.32 0)
        (effects (font (size 1.27 1.27) (thickness 0.15)) (justify left bottom) hide)
      )
      (property "License" "Apache-2.0" (id 6) (at 20.32 -22.86 0)
        (effects (font (size 1.27 1.27) (thickness 0.15)) (justify left bottom) hide)
      )
      (property "Author" "Antmicro" (id 7) (at 20.32 -25.4 0)
        (effects (font (size 1.27 1.27) (thickness 0.15)) (justify left bottom) hide)
      )
      (property "Val" "100n" (id 8) (at 20.32 -7.62 0)
        (effects (font (size 1.27 1.27) (thickness 0.15)) (justify left bottom))
      )
      (property "Voltage" "50V" (id 9) (at 20.32 -27.94 0)
        (effects (font (size 1.27 1.27)) (justify left bottom) hide)
      )
      (property "Dielectric" "X5R" (id 10) (at 20.32 -30.48 0)
        (effects (font (size 1.27 1.27)) (justify left bottom) hide)
      )
      (property "ki_description" " " (id 11) (at 0 0 0)
        (effects (font (size 1.27 1.27)) hide)
      )
      (symbol "C_100n_0402_0_1"
        (polyline
          (pts
            (xy 2.032 -1.524)
            (xy 2.032 1.524)
          )
          (stroke (width 0.3048) (type default) (color 0 0 0 0))
          (fill (type none))
        )
        (polyline
          (pts
            (xy 3.048 -1.524)
            (xy 3.048 1.524)
          )
          (stroke (width 0.3302) (type default) (color 0 0 0 0))
          (fill (type none))
        )
      )
      (symbol "C_100n_0402_1_1"
        (pin passive line (at 0 0 0) (length 2.032)
          (name "~" (effects (font (size 1.27 1.27))))
          (number "1" (effects (font (size 1.27 1.27))))
        )
        (pin passive line (at 5.08 0 180) (length 2.032)
          (name "~" (effects (font (size 1.27 1.27))))
          (number "2" (effects (font (size 1.27 1.27))))
        )
      )
    )
	(symbol "sa800u-baseboard-hw:C_100n_0402_10" (pin_numbers hide) (pin_names hide) (in_bom yes) (on_board yes)
      (property "Reference" "C" (id 0) (at 20.32 -5.08 0)
        (effects (font (size 1.27 1.27) (thickness 0.15)) (justify left bottom))
      )
      (property "Value" "C_100n_0402_10" (id 1) (at 20.32 -10.16 0)
        (effects (font (size 1.27 1.27) (thickness 0.15)) (justify left bottom) hide)
      )
      (property "Footprint" "sa800u-baseboard-hw-footprints:C_0402_1005Metric" (id 2) (at 20.32 -12.7 0)
        (effects (font (size 1.27 1.27) (thickness 0.15)) (justify left bottom) hide)
      )
      (property "Datasheet" "https://search.murata.co.jp/Ceramy/image/img/A01X/G101/ENG/GRM155R61H104KE14-01.pdf" (id 3) (at 20.32 -15.24 0)
        (effects (font (size 1.27 1.27) (thickness 0.15)) (justify left bottom) hide)
      )
      (property "MPN" "GRM155R61H104KE14D" (id 4) (at 20.32 -17.78 0)
        (effects (font (size 1.27 1.27) (thickness 0.15)) (justify left bottom) hide)
      )
      (property "Manufacturer" "Murata" (id 5) (at 20.32 -20.32 0)
        (effects (font (size 1.27 1.27) (thickness 0.15)) (justify left bottom) hide)
      )
      (property "License" "Apache-2.0" (id 6) (at 20.32 -22.86 0)
        (effects (font (size 1.27 1.27) (thickness 0.15)) (justify left bottom) hide)
      )
      (property "Author" "Antmicro" (id 7) (at 20.32 -25.4 0)
        (effects (font (size 1.27 1.27) (thickness 0.15)) (justify left bottom) hide)
      )
      (property "Val" "100n" (id 8) (at 20.32 -7.62 0)
        (effects (font (size 1.27 1.27) (thickness 0.15)) (justify left bottom))
      )
      (property "Voltage" "50V" (id 9) (at 20.32 -27.94 0)
        (effects (font (size 1.27 1.27)) (justify left bottom) hide)
      )
      (property "Dielectric" "X5R" (id 10) (at 20.32 -30.48 0)
        (effects (font (size 1.27 1.27)) (justify left bottom) hide)
      )
      (property "ki_description" " " (id 11) (at 0 0 0)
        (effects (font (size 1.27 1.27)) hide)
      )
      (symbol "C_100n_0402_10_0_1"
        (polyline
          (pts
            (xy 2.032 -1.524)
            (xy 2.032 1.524)
          )
          (stroke (width 0.3048) (type default) (color 0 0 0 0))
          (fill (type none))
        )
        (polyline
          (pts
            (xy 3.048 -1.524)
            (xy 3.048 1.524)
          )
          (stroke (width 0.3302) (type default) (color 0 0 0 0))
          (fill (type none))
        )
      )
      (symbol "C_100n_0402_10_1_1"
        (pin passive line (at 0 0 0) (length 2.032)
          (name "~" (effects (font (size 1.27 1.27))))
          (number "1" (effects (font (size 1.27 1.27))))
        )
        (pin passive line (at 5.08 0 180) (length 2.032)
          (name "~" (effects (font (size 1.27 1.27))))
          (number "2" (effects (font (size 1.27 1.27))))
        )
      )
    )
	(symbol "sa800u-baseboard-hw:C_100n_0402_11" (pin_numbers hide) (pin_names hide) (in_bom yes) (on_board yes)
      (property "Reference" "C" (id 0) (at 20.32 -5.08 0)
        (effects (font (size 1.27 1.27) (thickness 0.15)) (justify left bottom))
      )
      (property "Value" "C_100n_0402_11" (id 1) (at 20.32 -10.16 0)
        (effects (font (size 1.27 1.27) (thickness 0.15)) (justify left bottom) hide)
      )
      (property "Footprint" "sa800u-baseboard-hw-footprints:C_0402_1005Metric" (id 2) (at 20.32 -12.7 0)
        (effects (font (size 1.27 1.27) (thickness 0.15)) (justify left bottom) hide)
      )
      (property "Datasheet" "https://search.murata.co.jp/Ceramy/image/img/A01X/G101/ENG/GRM155R61H104KE14-01.pdf" (id 3) (at 20.32 -15.24 0)
        (effects (font (size 1.27 1.27) (thickness 0.15)) (justify left bottom) hide)
      )
      (property "MPN" "GRM155R61H104KE14D" (id 4) (at 20.32 -17.78 0)
        (effects (font (size 1.27 1.27) (thickness 0.15)) (justify left bottom) hide)
      )
      (property "Manufacturer" "Murata" (id 5) (at 20.32 -20.32 0)
        (effects (font (size 1.27 1.27) (thickness 0.15)) (justify left bottom) hide)
      )
      (property "License" "Apache-2.0" (id 6) (at 20.32 -22.86 0)
        (effects (font (size 1.27 1.27) (thickness 0.15)) (justify left bottom) hide)
      )
      (property "Author" "Antmicro" (id 7) (at 20.32 -25.4 0)
        (effects (font (size 1.27 1.27) (thickness 0.15)) (justify left bottom) hide)
      )
      (property "Val" "100n" (id 8) (at 20.32 -7.62 0)
        (effects (font (size 1.27 1.27) (thickness 0.15)) (justify left bottom))
      )
      (property "Voltage" "50V" (id 9) (at 20.32 -27.94 0)
        (effects (font (size 1.27 1.27)) (justify left bottom) hide)
      )
      (property "Dielectric" "X5R" (id 10) (at 20.32 -30.48 0)
        (effects (font (size 1.27 1.27)) (justify left bottom) hide)
      )
      (property "ki_description" " " (id 11) (at 0 0 0)
        (effects (font (size 1.27 1.27)) hide)
      )
      (symbol "C_100n_0402_11_0_1"
        (polyline
          (pts
            (xy 2.032 -1.524)
            (xy 2.032 1.524)
          )
          (stroke (width 0.3048) (type default) (color 0 0 0 0))
          (fill (type none))
        )
        (polyline
          (pts
            (xy 3.048 -1.524)
            (xy 3.048 1.524)
          )
          (stroke (width 0.3302) (type default) (color 0 0 0 0))
          (fill (type none))
        )
      )
      (symbol "C_100n_0402_11_1_1"
        (pin passive line (at 0 0 0) (length 2.032)
          (name "~" (effects (font (size 1.27 1.27))))
          (number "1" (effects (font (size 1.27 1.27))))
        )
        (pin passive line (at 5.08 0 180) (length 2.032)
          (name "~" (effects (font (size 1.27 1.27))))
          (number "2" (effects (font (size 1.27 1.27))))
        )
      )
    )
	(symbol "sa800u-baseboard-hw:C_100n_0402_12" (pin_numbers hide) (pin_names hide) (in_bom yes) (on_board yes)
      (property "Reference" "C" (id 0) (at 20.32 -5.08 0)
        (effects (font (size 1.27 1.27) (thickness 0.15)) (justify left bottom))
      )
      (property "Value" "C_100n_0402_12" (id 1) (at 20.32 -10.16 0)
        (effects (font (size 1.27 1.27) (thickness 0.15)) (justify left bottom) hide)
      )
      (property "Footprint" "sa800u-baseboard-hw-footprints:C_0402_1005Metric" (id 2) (at 20.32 -12.7 0)
        (effects (font (size 1.27 1.27) (thickness 0.15)) (justify left bottom) hide)
      )
      (property "Datasheet" "https://search.murata.co.jp/Ceramy/image/img/A01X/G101/ENG/GRM155R61H104KE14-01.pdf" (id 3) (at 20.32 -15.24 0)
        (effects (font (size 1.27 1.27) (thickness 0.15)) (justify left bottom) hide)
      )
      (property "MPN" "GRM155R61H104KE14D" (id 4) (at 20.32 -17.78 0)
        (effects (font (size 1.27 1.27) (thickness 0.15)) (justify left bottom) hide)
      )
      (property "Manufacturer" "Murata" (id 5) (at 20.32 -20.32 0)
        (effects (font (size 1.27 1.27) (thickness 0.15)) (justify left bottom) hide)
      )
      (property "License" "Apache-2.0" (id 6) (at 20.32 -22.86 0)
        (effects (font (size 1.27 1.27) (thickness 0.15)) (justify left bottom) hide)
      )
      (property "Author" "Antmicro" (id 7) (at 20.32 -25.4 0)
        (effects (font (size 1.27 1.27) (thickness 0.15)) (justify left bottom) hide)
      )
      (property "Val" "100n" (id 8) (at 20.32 -7.62 0)
        (effects (font (size 1.27 1.27) (thickness 0.15)) (justify left bottom))
      )
      (property "Voltage" "50V" (id 9) (at 20.32 -27.94 0)
        (effects (font (size 1.27 1.27)) (justify left bottom) hide)
      )
      (property "Dielectric" "X5R" (id 10) (at 20.32 -30.48 0)
        (effects (font (size 1.27 1.27)) (justify left bottom) hide)
      )
      (property "ki_description" " " (id 11) (at 0 0 0)
        (effects (font (size 1.27 1.27)) hide)
      )
      (symbol "C_100n_0402_12_0_1"
        (polyline
          (pts
            (xy 2.032 -1.524)
            (xy 2.032 1.524)
          )
          (stroke (width 0.3048) (type default) (color 0 0 0 0))
          (fill (type none))
        )
        (polyline
          (pts
            (xy 3.048 -1.524)
            (xy 3.048 1.524)
          )
          (stroke (width 0.3302) (type default) (color 0 0 0 0))
          (fill (type none))
        )
      )
      (symbol "C_100n_0402_12_1_1"
        (pin passive line (at 0 0 0) (length 2.032)
          (name "~" (effects (font (size 1.27 1.27))))
          (number "1" (effects (font (size 1.27 1.27))))
        )
        (pin passive line (at 5.08 0 180) (length 2.032)
          (name "~" (effects (font (size 1.27 1.27))))
          (number "2" (effects (font (size 1.27 1.27))))
        )
      )
    )
	(symbol "sa800u-baseboard-hw:C_100n_0402_13" (pin_numbers hide) (pin_names hide) (in_bom yes) (on_board yes)
      (property "Reference" "C" (id 0) (at 20.32 -5.08 0)
        (effects (font (size 1.27 1.27) (thickness 0.15)) (justify left bottom))
      )
      (property "Value" "C_100n_0402_13" (id 1) (at 20.32 -10.16 0)
        (effects (font (size 1.27 1.27) (thickness 0.15)) (justify left bottom) hide)
      )
      (property "Footprint" "sa800u-baseboard-hw-footprints:C_0402_1005Metric" (id 2) (at 20.32 -12.7 0)
        (effects (font (size 1.27 1.27) (thickness 0.15)) (justify left bottom) hide)
      )
      (property "Datasheet" "https://search.murata.co.jp/Ceramy/image/img/A01X/G101/ENG/GRM155R61H104KE14-01.pdf" (id 3) (at 20.32 -15.24 0)
        (effects (font (size 1.27 1.27) (thickness 0.15)) (justify left bottom) hide)
      )
      (property "MPN" "GRM155R61H104KE14D" (id 4) (at 20.32 -17.78 0)
        (effects (font (size 1.27 1.27) (thickness 0.15)) (justify left bottom) hide)
      )
      (property "Manufacturer" "Murata" (id 5) (at 20.32 -20.32 0)
        (effects (font (size 1.27 1.27) (thickness 0.15)) (justify left bottom) hide)
      )
      (property "License" "Apache-2.0" (id 6) (at 20.32 -22.86 0)
        (effects (font (size 1.27 1.27) (thickness 0.15)) (justify left bottom) hide)
      )
      (property "Author" "Antmicro" (id 7) (at 20.32 -25.4 0)
        (effects (font (size 1.27 1.27) (thickness 0.15)) (justify left bottom) hide)
      )
      (property "Val" "100n" (id 8) (at 20.32 -7.62 0)
        (effects (font (size 1.27 1.27) (thickness 0.15)) (justify left bottom))
      )
      (property "Voltage" "50V" (id 9) (at 20.32 -27.94 0)
        (effects (font (size 1.27 1.27)) (justify left bottom) hide)
      )
      (property "Dielectric" "X5R" (id 10) (at 20.32 -30.48 0)
        (effects (font (size 1.27 1.27)) (justify left bottom) hide)
      )
      (property "ki_description" " " (id 11) (at 0 0 0)
        (effects (font (size 1.27 1.27)) hide)
      )
      (symbol "C_100n_0402_13_0_1"
        (polyline
          (pts
            (xy 2.032 -1.524)
            (xy 2.032 1.524)
          )
          (stroke (width 0.3048) (type default) (color 0 0 0 0))
          (fill (type none))
        )
        (polyline
          (pts
            (xy 3.048 -1.524)
            (xy 3.048 1.524)
          )
          (stroke (width 0.3302) (type default) (color 0 0 0 0))
          (fill (type none))
        )
      )
      (symbol "C_100n_0402_13_1_1"
        (pin passive line (at 0 0 0) (length 2.032)
          (name "~" (effects (font (size 1.27 1.27))))
          (number "1" (effects (font (size 1.27 1.27))))
        )
        (pin passive line (at 5.08 0 180) (length 2.032)
          (name "~" (effects (font (size 1.27 1.27))))
          (number "2" (effects (font (size 1.27 1.27))))
        )
      )
    )
	(symbol "sa800u-baseboard-hw:C_100n_0402_14" (pin_numbers hide) (pin_names hide) (in_bom yes) (on_board yes)
      (property "Reference" "C" (id 0) (at 20.32 -5.08 0)
        (effects (font (size 1.27 1.27) (thickness 0.15)) (justify left bottom))
      )
      (property "Value" "C_100n_0402_14" (id 1) (at 20.32 -10.16 0)
        (effects (font (size 1.27 1.27) (thickness 0.15)) (justify left bottom) hide)
      )
      (property "Footprint" "sa800u-baseboard-hw-footprints:C_0402_1005Metric" (id 2) (at 20.32 -12.7 0)
        (effects (font (size 1.27 1.27) (thickness 0.15)) (justify left bottom) hide)
      )
      (property "Datasheet" "https://search.murata.co.jp/Ceramy/image/img/A01X/G101/ENG/GRM155R61H104KE14-01.pdf" (id 3) (at 20.32 -15.24 0)
        (effects (font (size 1.27 1.27) (thickness 0.15)) (justify left bottom) hide)
      )
      (property "MPN" "GRM155R61H104KE14D" (id 4) (at 20.32 -17.78 0)
        (effects (font (size 1.27 1.27) (thickness 0.15)) (justify left bottom) hide)
      )
      (property "Manufacturer" "Murata" (id 5) (at 20.32 -20.32 0)
        (effects (font (size 1.27 1.27) (thickness 0.15)) (justify left bottom) hide)
      )
      (property "License" "Apache-2.0" (id 6) (at 20.32 -22.86 0)
        (effects (font (size 1.27 1.27) (thickness 0.15)) (justify left bottom) hide)
      )
      (property "Author" "Antmicro" (id 7) (at 20.32 -25.4 0)
        (effects (font (size 1.27 1.27) (thickness 0.15)) (justify left bottom) hide)
      )
      (property "Val" "100n" (id 8) (at 20.32 -7.62 0)
        (effects (font (size 1.27 1.27) (thickness 0.15)) (justify left bottom))
      )
      (property "Voltage" "50V" (id 9) (at 20.32 -27.94 0)
        (effects (font (size 1.27 1.27)) (justify left bottom) hide)
      )
      (property "Dielectric" "X5R" (id 10) (at 20.32 -30.48 0)
        (effects (font (size 1.27 1.27)) (justify left bottom) hide)
      )
      (property "ki_description" " " (id 11) (at 0 0 0)
        (effects (font (size 1.27 1.27)) hide)
      )
      (symbol "C_100n_0402_14_0_1"
        (polyline
          (pts
            (xy 2.032 -1.524)
            (xy 2.032 1.524)
          )
          (stroke (width 0.3048) (type default) (color 0 0 0 0))
          (fill (type none))
        )
        (polyline
          (pts
            (xy 3.048 -1.524)
            (xy 3.048 1.524)
          )
          (stroke (width 0.3302) (type default) (color 0 0 0 0))
          (fill (type none))
        )
      )
      (symbol "C_100n_0402_14_1_1"
        (pin passive line (at 0 0 0) (length 2.032)
          (name "~" (effects (font (size 1.27 1.27))))
          (number "1" (effects (font (size 1.27 1.27))))
        )
        (pin passive line (at 5.08 0 180) (length 2.032)
          (name "~" (effects (font (size 1.27 1.27))))
          (number "2" (effects (font (size 1.27 1.27))))
        )
      )
    )
	(symbol "sa800u-baseboard-hw:C_100n_0402_15" (pin_numbers hide) (pin_names hide) (in_bom yes) (on_board yes)
      (property "Reference" "C" (id 0) (at 20.32 -5.08 0)
        (effects (font (size 1.27 1.27) (thickness 0.15)) (justify left bottom))
      )
      (property "Value" "C_100n_0402_15" (id 1) (at 20.32 -10.16 0)
        (effects (font (size 1.27 1.27) (thickness 0.15)) (justify left bottom) hide)
      )
      (property "Footprint" "sa800u-baseboard-hw-footprints:C_0402_1005Metric" (id 2) (at 20.32 -12.7 0)
        (effects (font (size 1.27 1.27) (thickness 0.15)) (justify left bottom) hide)
      )
      (property "Datasheet" "https://search.murata.co.jp/Ceramy/image/img/A01X/G101/ENG/GRM155R61H104KE14-01.pdf" (id 3) (at 20.32 -15.24 0)
        (effects (font (size 1.27 1.27) (thickness 0.15)) (justify left bottom) hide)
      )
      (property "MPN" "GRM155R61H104KE14D" (id 4) (at 20.32 -17.78 0)
        (effects (font (size 1.27 1.27) (thickness 0.15)) (justify left bottom) hide)
      )
      (property "Manufacturer" "Murata" (id 5) (at 20.32 -20.32 0)
        (effects (font (size 1.27 1.27) (thickness 0.15)) (justify left bottom) hide)
      )
      (property "License" "Apache-2.0" (id 6) (at 20.32 -22.86 0)
        (effects (font (size 1.27 1.27) (thickness 0.15)) (justify left bottom) hide)
      )
      (property "Author" "Antmicro" (id 7) (at 20.32 -25.4 0)
        (effects (font (size 1.27 1.27) (thickness 0.15)) (justify left bottom) hide)
      )
      (property "Val" "100n" (id 8) (at 20.32 -7.62 0)
        (effects (font (size 1.27 1.27) (thickness 0.15)) (justify left bottom))
      )
      (property "Voltage" "50V" (id 9) (at 20.32 -27.94 0)
        (effects (font (size 1.27 1.27)) (justify left bottom) hide)
      )
      (property "Dielectric" "X5R" (id 10) (at 20.32 -30.48 0)
        (effects (font (size 1.27 1.27)) (justify left bottom) hide)
      )
      (property "ki_description" " " (id 11) (at 0 0 0)
        (effects (font (size 1.27 1.27)) hide)
      )
      (symbol "C_100n_0402_15_0_1"
        (polyline
          (pts
            (xy 2.032 -1.524)
            (xy 2.032 1.524)
          )
          (stroke (width 0.3048) (type default) (color 0 0 0 0))
          (fill (type none))
        )
        (polyline
          (pts
            (xy 3.048 -1.524)
            (xy 3.048 1.524)
          )
          (stroke (width 0.3302) (type default) (color 0 0 0 0))
          (fill (type none))
        )
      )
      (symbol "C_100n_0402_15_1_1"
        (pin passive line (at 0 0 0) (length 2.032)
          (name "~" (effects (font (size 1.27 1.27))))
          (number "1" (effects (font (size 1.27 1.27))))
        )
        (pin passive line (at 5.08 0 180) (length 2.032)
          (name "~" (effects (font (size 1.27 1.27))))
          (number "2" (effects (font (size 1.27 1.27))))
        )
      )
    )
	(symbol "sa800u-baseboard-hw:C_100n_0402_16" (pin_numbers hide) (pin_names hide) (in_bom yes) (on_board yes)
      (property "Reference" "C" (id 0) (at 20.32 -5.08 0)
        (effects (font (size 1.27 1.27) (thickness 0.15)) (justify left bottom))
      )
      (property "Value" "C_100n_0402_16" (id 1) (at 20.32 -10.16 0)
        (effects (font (size 1.27 1.27) (thickness 0.15)) (justify left bottom) hide)
      )
      (property "Footprint" "sa800u-baseboard-hw-footprints:C_0402_1005Metric" (id 2) (at 20.32 -12.7 0)
        (effects (font (size 1.27 1.27) (thickness 0.15)) (justify left bottom) hide)
      )
      (property "Datasheet" "https://search.murata.co.jp/Ceramy/image/img/A01X/G101/ENG/GRM155R61H104KE14-01.pdf" (id 3) (at 20.32 -15.24 0)
        (effects (font (size 1.27 1.27) (thickness 0.15)) (justify left bottom) hide)
      )
      (property "MPN" "GRM155R61H104KE14D" (id 4) (at 20.32 -17.78 0)
        (effects (font (size 1.27 1.27) (thickness 0.15)) (justify left bottom) hide)
      )
      (property "Manufacturer" "Murata" (id 5) (at 20.32 -20.32 0)
        (effects (font (size 1.27 1.27) (thickness 0.15)) (justify left bottom) hide)
      )
      (property "License" "Apache-2.0" (id 6) (at 20.32 -22.86 0)
        (effects (font (size 1.27 1.27) (thickness 0.15)) (justify left bottom) hide)
      )
      (property "Author" "Antmicro" (id 7) (at 20.32 -25.4 0)
        (effects (font (size 1.27 1.27) (thickness 0.15)) (justify left bottom) hide)
      )
      (property "Val" "100n" (id 8) (at 20.32 -7.62 0)
        (effects (font (size 1.27 1.27) (thickness 0.15)) (justify left bottom))
      )
      (property "Voltage" "50V" (id 9) (at 20.32 -27.94 0)
        (effects (font (size 1.27 1.27)) (justify left bottom) hide)
      )
      (property "Dielectric" "X5R" (id 10) (at 20.32 -30.48 0)
        (effects (font (size 1.27 1.27)) (justify left bottom) hide)
      )
      (property "ki_description" " " (id 11) (at 0 0 0)
        (effects (font (size 1.27 1.27)) hide)
      )
      (symbol "C_100n_0402_16_0_1"
        (polyline
          (pts
            (xy 2.032 -1.524)
            (xy 2.032 1.524)
          )
          (stroke (width 0.3048) (type default) (color 0 0 0 0))
          (fill (type none))
        )
        (polyline
          (pts
            (xy 3.048 -1.524)
            (xy 3.048 1.524)
          )
          (stroke (width 0.3302) (type default) (color 0 0 0 0))
          (fill (type none))
        )
      )
      (symbol "C_100n_0402_16_1_1"
        (pin passive line (at 0 0 0) (length 2.032)
          (name "~" (effects (font (size 1.27 1.27))))
          (number "1" (effects (font (size 1.27 1.27))))
        )
        (pin passive line (at 5.08 0 180) (length 2.032)
          (name "~" (effects (font (size 1.27 1.27))))
          (number "2" (effects (font (size 1.27 1.27))))
        )
      )
    )
	(symbol "sa800u-baseboard-hw:C_100n_0402_17" (pin_numbers hide) (pin_names hide) (in_bom yes) (on_board yes)
      (property "Reference" "C" (id 0) (at 20.32 -5.08 0)
        (effects (font (size 1.27 1.27) (thickness 0.15)) (justify left bottom))
      )
      (property "Value" "C_100n_0402_17" (id 1) (at 20.32 -10.16 0)
        (effects (font (size 1.27 1.27) (thickness 0.15)) (justify left bottom) hide)
      )
      (property "Footprint" "sa800u-baseboard-hw-footprints:C_0402_1005Metric" (id 2) (at 20.32 -12.7 0)
        (effects (font (size 1.27 1.27) (thickness 0.15)) (justify left bottom) hide)
      )
      (property "Datasheet" "https://search.murata.co.jp/Ceramy/image/img/A01X/G101/ENG/GRM155R61H104KE14-01.pdf" (id 3) (at 20.32 -15.24 0)
        (effects (font (size 1.27 1.27) (thickness 0.15)) (justify left bottom) hide)
      )
      (property "MPN" "GRM155R61H104KE14D" (id 4) (at 20.32 -17.78 0)
        (effects (font (size 1.27 1.27) (thickness 0.15)) (justify left bottom) hide)
      )
      (property "Manufacturer" "Murata" (id 5) (at 20.32 -20.32 0)
        (effects (font (size 1.27 1.27) (thickness 0.15)) (justify left bottom) hide)
      )
      (property "License" "Apache-2.0" (id 6) (at 20.32 -22.86 0)
        (effects (font (size 1.27 1.27) (thickness 0.15)) (justify left bottom) hide)
      )
      (property "Author" "Antmicro" (id 7) (at 20.32 -25.4 0)
        (effects (font (size 1.27 1.27) (thickness 0.15)) (justify left bottom) hide)
      )
      (property "Val" "100n" (id 8) (at 20.32 -7.62 0)
        (effects (font (size 1.27 1.27) (thickness 0.15)) (justify left bottom))
      )
      (property "Voltage" "50V" (id 9) (at 20.32 -27.94 0)
        (effects (font (size 1.27 1.27)) (justify left bottom) hide)
      )
      (property "Dielectric" "X5R" (id 10) (at 20.32 -30.48 0)
        (effects (font (size 1.27 1.27)) (justify left bottom) hide)
      )
      (property "ki_description" " " (id 11) (at 0 0 0)
        (effects (font (size 1.27 1.27)) hide)
      )
      (symbol "C_100n_0402_17_0_1"
        (polyline
          (pts
            (xy 2.032 -1.524)
            (xy 2.032 1.524)
          )
          (stroke (width 0.3048) (type default) (color 0 0 0 0))
          (fill (type none))
        )
        (polyline
          (pts
            (xy 3.048 -1.524)
            (xy 3.048 1.524)
          )
          (stroke (width 0.3302) (type default) (color 0 0 0 0))
          (fill (type none))
        )
      )
      (symbol "C_100n_0402_17_1_1"
        (pin passive line (at 0 0 0) (length 2.032)
          (name "~" (effects (font (size 1.27 1.27))))
          (number "1" (effects (font (size 1.27 1.27))))
        )
        (pin passive line (at 5.08 0 180) (length 2.032)
          (name "~" (effects (font (size 1.27 1.27))))
          (number "2" (effects (font (size 1.27 1.27))))
        )
      )
    )
	(symbol "sa800u-baseboard-hw:C_100n_0402_18" (pin_numbers hide) (pin_names hide) (in_bom yes) (on_board yes)
      (property "Reference" "C" (id 0) (at 20.32 -5.08 0)
        (effects (font (size 1.27 1.27) (thickness 0.15)) (justify left bottom))
      )
      (property "Value" "C_100n_0402_18" (id 1) (at 20.32 -10.16 0)
        (effects (font (size 1.27 1.27) (thickness 0.15)) (justify left bottom) hide)
      )
      (property "Footprint" "sa800u-baseboard-hw-footprints:C_0402_1005Metric" (id 2) (at 20.32 -12.7 0)
        (effects (font (size 1.27 1.27) (thickness 0.15)) (justify left bottom) hide)
      )
      (property "Datasheet" "https://search.murata.co.jp/Ceramy/image/img/A01X/G101/ENG/GRM155R61H104KE14-01.pdf" (id 3) (at 20.32 -15.24 0)
        (effects (font (size 1.27 1.27) (thickness 0.15)) (justify left bottom) hide)
      )
      (property "MPN" "GRM155R61H104KE14D" (id 4) (at 20.32 -17.78 0)
        (effects (font (size 1.27 1.27) (thickness 0.15)) (justify left bottom) hide)
      )
      (property "Manufacturer" "Murata" (id 5) (at 20.32 -20.32 0)
        (effects (font (size 1.27 1.27) (thickness 0.15)) (justify left bottom) hide)
      )
      (property "License" "Apache-2.0" (id 6) (at 20.32 -22.86 0)
        (effects (font (size 1.27 1.27) (thickness 0.15)) (justify left bottom) hide)
      )
      (property "Author" "Antmicro" (id 7) (at 20.32 -25.4 0)
        (effects (font (size 1.27 1.27) (thickness 0.15)) (justify left bottom) hide)
      )
      (property "Val" "100n" (id 8) (at 20.32 -7.62 0)
        (effects (font (size 1.27 1.27) (thickness 0.15)) (justify left bottom))
      )
      (property "Voltage" "50V" (id 9) (at 20.32 -27.94 0)
        (effects (font (size 1.27 1.27)) (justify left bottom) hide)
      )
      (property "Dielectric" "X5R" (id 10) (at 20.32 -30.48 0)
        (effects (font (size 1.27 1.27)) (justify left bottom) hide)
      )
      (property "ki_description" " " (id 11) (at 0 0 0)
        (effects (font (size 1.27 1.27)) hide)
      )
      (symbol "C_100n_0402_18_0_1"
        (polyline
          (pts
            (xy 2.032 -1.524)
            (xy 2.032 1.524)
          )
          (stroke (width 0.3048) (type default) (color 0 0 0 0))
          (fill (type none))
        )
        (polyline
          (pts
            (xy 3.048 -1.524)
            (xy 3.048 1.524)
          )
          (stroke (width 0.3302) (type default) (color 0 0 0 0))
          (fill (type none))
        )
      )
      (symbol "C_100n_0402_18_1_1"
        (pin passive line (at 0 0 0) (length 2.032)
          (name "~" (effects (font (size 1.27 1.27))))
          (number "1" (effects (font (size 1.27 1.27))))
        )
        (pin passive line (at 5.08 0 180) (length 2.032)
          (name "~" (effects (font (size 1.27 1.27))))
          (number "2" (effects (font (size 1.27 1.27))))
        )
      )
    )
	(symbol "sa800u-baseboard-hw:C_100n_0402_19" (pin_numbers hide) (pin_names hide) (in_bom yes) (on_board yes)
      (property "Reference" "C" (id 0) (at 20.32 -5.08 0)
        (effects (font (size 1.27 1.27) (thickness 0.15)) (justify left bottom))
      )
      (property "Value" "C_100n_0402_19" (id 1) (at 20.32 -10.16 0)
        (effects (font (size 1.27 1.27) (thickness 0.15)) (justify left bottom) hide)
      )
      (property "Footprint" "sa800u-baseboard-hw-footprints:C_0402_1005Metric" (id 2) (at 20.32 -12.7 0)
        (effects (font (size 1.27 1.27) (thickness 0.15)) (justify left bottom) hide)
      )
      (property "Datasheet" "https://search.murata.co.jp/Ceramy/image/img/A01X/G101/ENG/GRM155R61H104KE14-01.pdf" (id 3) (at 20.32 -15.24 0)
        (effects (font (size 1.27 1.27) (thickness 0.15)) (justify left bottom) hide)
      )
      (property "MPN" "GRM155R61H104KE14D" (id 4) (at 20.32 -17.78 0)
        (effects (font (size 1.27 1.27) (thickness 0.15)) (justify left bottom) hide)
      )
      (property "Manufacturer" "Murata" (id 5) (at 20.32 -20.32 0)
        (effects (font (size 1.27 1.27) (thickness 0.15)) (justify left bottom) hide)
      )
      (property "License" "Apache-2.0" (id 6) (at 20.32 -22.86 0)
        (effects (font (size 1.27 1.27) (thickness 0.15)) (justify left bottom) hide)
      )
      (property "Author" "Antmicro" (id 7) (at 20.32 -25.4 0)
        (effects (font (size 1.27 1.27) (thickness 0.15)) (justify left bottom) hide)
      )
      (property "Val" "100n" (id 8) (at 20.32 -7.62 0)
        (effects (font (size 1.27 1.27) (thickness 0.15)) (justify left bottom))
      )
      (property "Voltage" "50V" (id 9) (at 20.32 -27.94 0)
        (effects (font (size 1.27 1.27)) (justify left bottom) hide)
      )
      (property "Dielectric" "X5R" (id 10) (at 20.32 -30.48 0)
        (effects (font (size 1.27 1.27)) (justify left bottom) hide)
      )
      (property "ki_description" " " (id 11) (at 0 0 0)
        (effects (font (size 1.27 1.27)) hide)
      )
      (symbol "C_100n_0402_19_0_1"
        (polyline
          (pts
            (xy 2.032 -1.524)
            (xy 2.032 1.524)
          )
          (stroke (width 0.3048) (type default) (color 0 0 0 0))
          (fill (type none))
        )
        (polyline
          (pts
            (xy 3.048 -1.524)
            (xy 3.048 1.524)
          )
          (stroke (width 0.3302) (type default) (color 0 0 0 0))
          (fill (type none))
        )
      )
      (symbol "C_100n_0402_19_1_1"
        (pin passive line (at 0 0 0) (length 2.032)
          (name "~" (effects (font (size 1.27 1.27))))
          (number "1" (effects (font (size 1.27 1.27))))
        )
        (pin passive line (at 5.08 0 180) (length 2.032)
          (name "~" (effects (font (size 1.27 1.27))))
          (number "2" (effects (font (size 1.27 1.27))))
        )
      )
    )
	(symbol "sa800u-baseboard-hw:C_100n_0402_20" (pin_numbers hide) (pin_names hide) (in_bom yes) (on_board yes)
      (property "Reference" "C" (id 0) (at 20.32 -5.08 0)
        (effects (font (size 1.27 1.27) (thickness 0.15)) (justify left bottom))
      )
      (property "Value" "C_100n_0402_20" (id 1) (at 20.32 -10.16 0)
        (effects (font (size 1.27 1.27) (thickness 0.15)) (justify left bottom) hide)
      )
      (property "Footprint" "sa800u-baseboard-hw-footprints:C_0402_1005Metric" (id 2) (at 20.32 -12.7 0)
        (effects (font (size 1.27 1.27) (thickness 0.15)) (justify left bottom) hide)
      )
      (property "Datasheet" "https://search.murata.co.jp/Ceramy/image/img/A01X/G101/ENG/GRM155R61H104KE14-01.pdf" (id 3) (at 20.32 -15.24 0)
        (effects (font (size 1.27 1.27) (thickness 0.15)) (justify left bottom) hide)
      )
      (property "MPN" "GRM155R61H104KE14D" (id 4) (at 20.32 -17.78 0)
        (effects (font (size 1.27 1.27) (thickness 0.15)) (justify left bottom) hide)
      )
      (property "Manufacturer" "Murata" (id 5) (at 20.32 -20.32 0)
        (effects (font (size 1.27 1.27) (thickness 0.15)) (justify left bottom) hide)
      )
      (property "License" "Apache-2.0" (id 6) (at 20.32 -22.86 0)
        (effects (font (size 1.27 1.27) (thickness 0.15)) (justify left bottom) hide)
      )
      (property "Author" "Antmicro" (id 7) (at 20.32 -25.4 0)
        (effects (font (size 1.27 1.27) (thickness 0.15)) (justify left bottom) hide)
      )
      (property "Val" "100n" (id 8) (at 20.32 -7.62 0)
        (effects (font (size 1.27 1.27) (thickness 0.15)) (justify left bottom))
      )
      (property "Voltage" "50V" (id 9) (at 20.32 -27.94 0)
        (effects (font (size 1.27 1.27)) (justify left bottom) hide)
      )
      (property "Dielectric" "X5R" (id 10) (at 20.32 -30.48 0)
        (effects (font (size 1.27 1.27)) (justify left bottom) hide)
      )
      (property "ki_description" " " (id 11) (at 0 0 0)
        (effects (font (size 1.27 1.27)) hide)
      )
      (symbol "C_100n_0402_20_0_1"
        (polyline
          (pts
            (xy 2.032 -1.524)
            (xy 2.032 1.524)
          )
          (stroke (width 0.3048) (type default) (color 0 0 0 0))
          (fill (type none))
        )
        (polyline
          (pts
            (xy 3.048 -1.524)
            (xy 3.048 1.524)
          )
          (stroke (width 0.3302) (type default) (color 0 0 0 0))
          (fill (type none))
        )
      )
      (symbol "C_100n_0402_20_1_1"
        (pin passive line (at 0 0 0) (length 2.032)
          (name "~" (effects (font (size 1.27 1.27))))
          (number "1" (effects (font (size 1.27 1.27))))
        )
        (pin passive line (at 5.08 0 180) (length 2.032)
          (name "~" (effects (font (size 1.27 1.27))))
          (number "2" (effects (font (size 1.27 1.27))))
        )
      )
    )
	(symbol "sa800u-baseboard-hw:C_100n_0402_21" (pin_numbers hide) (pin_names hide) (in_bom yes) (on_board yes)
      (property "Reference" "C" (id 0) (at 20.32 -5.08 0)
        (effects (font (size 1.27 1.27) (thickness 0.15)) (justify left bottom))
      )
      (property "Value" "C_100n_0402_21" (id 1) (at 20.32 -10.16 0)
        (effects (font (size 1.27 1.27) (thickness 0.15)) (justify left bottom) hide)
      )
      (property "Footprint" "sa800u-baseboard-hw-footprints:C_0402_1005Metric" (id 2) (at 20.32 -12.7 0)
        (effects (font (size 1.27 1.27) (thickness 0.15)) (justify left bottom) hide)
      )
      (property "Datasheet" "https://search.murata.co.jp/Ceramy/image/img/A01X/G101/ENG/GRM155R61H104KE14-01.pdf" (id 3) (at 20.32 -15.24 0)
        (effects (font (size 1.27 1.27) (thickness 0.15)) (justify left bottom) hide)
      )
      (property "MPN" "GRM155R61H104KE14D" (id 4) (at 20.32 -17.78 0)
        (effects (font (size 1.27 1.27) (thickness 0.15)) (justify left bottom) hide)
      )
      (property "Manufacturer" "Murata" (id 5) (at 20.32 -20.32 0)
        (effects (font (size 1.27 1.27) (thickness 0.15)) (justify left bottom) hide)
      )
      (property "License" "Apache-2.0" (id 6) (at 20.32 -22.86 0)
        (effects (font (size 1.27 1.27) (thickness 0.15)) (justify left bottom) hide)
      )
      (property "Author" "Antmicro" (id 7) (at 20.32 -25.4 0)
        (effects (font (size 1.27 1.27) (thickness 0.15)) (justify left bottom) hide)
      )
      (property "Val" "100n" (id 8) (at 20.32 -7.62 0)
        (effects (font (size 1.27 1.27) (thickness 0.15)) (justify left bottom))
      )
      (property "Voltage" "50V" (id 9) (at 20.32 -27.94 0)
        (effects (font (size 1.27 1.27)) (justify left bottom) hide)
      )
      (property "Dielectric" "X5R" (id 10) (at 20.32 -30.48 0)
        (effects (font (size 1.27 1.27)) (justify left bottom) hide)
      )
      (property "ki_description" " " (id 11) (at 0 0 0)
        (effects (font (size 1.27 1.27)) hide)
      )
      (symbol "C_100n_0402_21_0_1"
        (polyline
          (pts
            (xy 2.032 -1.524)
            (xy 2.032 1.524)
          )
          (stroke (width 0.3048) (type default) (color 0 0 0 0))
          (fill (type none))
        )
        (polyline
          (pts
            (xy 3.048 -1.524)
            (xy 3.048 1.524)
          )
          (stroke (width 0.3302) (type default) (color 0 0 0 0))
          (fill (type none))
        )
      )
      (symbol "C_100n_0402_21_1_1"
        (pin passive line (at 0 0 0) (length 2.032)
          (name "~" (effects (font (size 1.27 1.27))))
          (number "1" (effects (font (size 1.27 1.27))))
        )
        (pin passive line (at 5.08 0 180) (length 2.032)
          (name "~" (effects (font (size 1.27 1.27))))
          (number "2" (effects (font (size 1.27 1.27))))
        )
      )
    )
	(symbol "sa800u-baseboard-hw:C_100n_0402_22" (pin_numbers hide) (pin_names hide) (in_bom yes) (on_board yes)
      (property "Reference" "C" (id 0) (at 20.32 -5.08 0)
        (effects (font (size 1.27 1.27) (thickness 0.15)) (justify left bottom))
      )
      (property "Value" "C_100n_0402_22" (id 1) (at 20.32 -10.16 0)
        (effects (font (size 1.27 1.27) (thickness 0.15)) (justify left bottom) hide)
      )
      (property "Footprint" "sa800u-baseboard-hw-footprints:C_0402_1005Metric" (id 2) (at 20.32 -12.7 0)
        (effects (font (size 1.27 1.27) (thickness 0.15)) (justify left bottom) hide)
      )
      (property "Datasheet" "https://search.murata.co.jp/Ceramy/image/img/A01X/G101/ENG/GRM155R61H104KE14-01.pdf" (id 3) (at 20.32 -15.24 0)
        (effects (font (size 1.27 1.27) (thickness 0.15)) (justify left bottom) hide)
      )
      (property "MPN" "GRM155R61H104KE14D" (id 4) (at 20.32 -17.78 0)
        (effects (font (size 1.27 1.27) (thickness 0.15)) (justify left bottom) hide)
      )
      (property "Manufacturer" "Murata" (id 5) (at 20.32 -20.32 0)
        (effects (font (size 1.27 1.27) (thickness 0.15)) (justify left bottom) hide)
      )
      (property "License" "Apache-2.0" (id 6) (at 20.32 -22.86 0)
        (effects (font (size 1.27 1.27) (thickness 0.15)) (justify left bottom) hide)
      )
      (property "Author" "Antmicro" (id 7) (at 20.32 -25.4 0)
        (effects (font (size 1.27 1.27) (thickness 0.15)) (justify left bottom) hide)
      )
      (property "Val" "100n" (id 8) (at 20.32 -7.62 0)
        (effects (font (size 1.27 1.27) (thickness 0.15)) (justify left bottom))
      )
      (property "Voltage" "50V" (id 9) (at 20.32 -27.94 0)
        (effects (font (size 1.27 1.27)) (justify left bottom) hide)
      )
      (property "Dielectric" "X5R" (id 10) (at 20.32 -30.48 0)
        (effects (font (size 1.27 1.27)) (justify left bottom) hide)
      )
      (property "ki_description" " " (id 11) (at 0 0 0)
        (effects (font (size 1.27 1.27)) hide)
      )
      (symbol "C_100n_0402_22_0_1"
        (polyline
          (pts
            (xy 2.032 -1.524)
            (xy 2.032 1.524)
          )
          (stroke (width 0.3048) (type default) (color 0 0 0 0))
          (fill (type none))
        )
        (polyline
          (pts
            (xy 3.048 -1.524)
            (xy 3.048 1.524)
          )
          (stroke (width 0.3302) (type default) (color 0 0 0 0))
          (fill (type none))
        )
      )
      (symbol "C_100n_0402_22_1_1"
        (pin passive line (at 0 0 0) (length 2.032)
          (name "~" (effects (font (size 1.27 1.27))))
          (number "1" (effects (font (size 1.27 1.27))))
        )
        (pin passive line (at 5.08 0 180) (length 2.032)
          (name "~" (effects (font (size 1.27 1.27))))
          (number "2" (effects (font (size 1.27 1.27))))
        )
      )
    )
	(symbol "sa800u-baseboard-hw:C_100n_0402_23" (pin_numbers hide) (pin_names hide) (in_bom yes) (on_board yes)
      (property "Reference" "C" (id 0) (at 20.32 -5.08 0)
        (effects (font (size 1.27 1.27) (thickness 0.15)) (justify left bottom))
      )
      (property "Value" "C_100n_0402_23" (id 1) (at 20.32 -10.16 0)
        (effects (font (size 1.27 1.27) (thickness 0.15)) (justify left bottom) hide)
      )
      (property "Footprint" "sa800u-baseboard-hw-footprints:C_0402_1005Metric" (id 2) (at 20.32 -12.7 0)
        (effects (font (size 1.27 1.27) (thickness 0.15)) (justify left bottom) hide)
      )
      (property "Datasheet" "https://search.murata.co.jp/Ceramy/image/img/A01X/G101/ENG/GRM155R61H104KE14-01.pdf" (id 3) (at 20.32 -15.24 0)
        (effects (font (size 1.27 1.27) (thickness 0.15)) (justify left bottom) hide)
      )
      (property "MPN" "GRM155R61H104KE14D" (id 4) (at 20.32 -17.78 0)
        (effects (font (size 1.27 1.27) (thickness 0.15)) (justify left bottom) hide)
      )
      (property "Manufacturer" "Murata" (id 5) (at 20.32 -20.32 0)
        (effects (font (size 1.27 1.27) (thickness 0.15)) (justify left bottom) hide)
      )
      (property "License" "Apache-2.0" (id 6) (at 20.32 -22.86 0)
        (effects (font (size 1.27 1.27) (thickness 0.15)) (justify left bottom) hide)
      )
      (property "Author" "Antmicro" (id 7) (at 20.32 -25.4 0)
        (effects (font (size 1.27 1.27) (thickness 0.15)) (justify left bottom) hide)
      )
      (property "Val" "100n" (id 8) (at 20.32 -7.62 0)
        (effects (font (size 1.27 1.27) (thickness 0.15)) (justify left bottom))
      )
      (property "Voltage" "50V" (id 9) (at 20.32 -27.94 0)
        (effects (font (size 1.27 1.27)) (justify left bottom) hide)
      )
      (property "Dielectric" "X5R" (id 10) (at 20.32 -30.48 0)
        (effects (font (size 1.27 1.27)) (justify left bottom) hide)
      )
      (property "ki_description" " " (id 11) (at 0 0 0)
        (effects (font (size 1.27 1.27)) hide)
      )
      (symbol "C_100n_0402_23_0_1"
        (polyline
          (pts
            (xy 2.032 -1.524)
            (xy 2.032 1.524)
          )
          (stroke (width 0.3048) (type default) (color 0 0 0 0))
          (fill (type none))
        )
        (polyline
          (pts
            (xy 3.048 -1.524)
            (xy 3.048 1.524)
          )
          (stroke (width 0.3302) (type default) (color 0 0 0 0))
          (fill (type none))
        )
      )
      (symbol "C_100n_0402_23_1_1"
        (pin passive line (at 0 0 0) (length 2.032)
          (name "~" (effects (font (size 1.27 1.27))))
          (number "1" (effects (font (size 1.27 1.27))))
        )
        (pin passive line (at 5.08 0 180) (length 2.032)
          (name "~" (effects (font (size 1.27 1.27))))
          (number "2" (effects (font (size 1.27 1.27))))
        )
      )
    )
	(symbol "sa800u-baseboard-hw:C_100n_0402_24" (pin_numbers hide) (pin_names hide) (in_bom yes) (on_board yes)
      (property "Reference" "C" (id 0) (at 20.32 -5.08 0)
        (effects (font (size 1.27 1.27) (thickness 0.15)) (justify left bottom))
      )
      (property "Value" "C_100n_0402_24" (id 1) (at 20.32 -10.16 0)
        (effects (font (size 1.27 1.27) (thickness 0.15)) (justify left bottom) hide)
      )
      (property "Footprint" "sa800u-baseboard-hw-footprints:C_0402_1005Metric" (id 2) (at 20.32 -12.7 0)
        (effects (font (size 1.27 1.27) (thickness 0.15)) (justify left bottom) hide)
      )
      (property "Datasheet" "https://search.murata.co.jp/Ceramy/image/img/A01X/G101/ENG/GRM155R61H104KE14-01.pdf" (id 3) (at 20.32 -15.24 0)
        (effects (font (size 1.27 1.27) (thickness 0.15)) (justify left bottom) hide)
      )
      (property "MPN" "GRM155R61H104KE14D" (id 4) (at 20.32 -17.78 0)
        (effects (font (size 1.27 1.27) (thickness 0.15)) (justify left bottom) hide)
      )
      (property "Manufacturer" "Murata" (id 5) (at 20.32 -20.32 0)
        (effects (font (size 1.27 1.27) (thickness 0.15)) (justify left bottom) hide)
      )
      (property "License" "Apache-2.0" (id 6) (at 20.32 -22.86 0)
        (effects (font (size 1.27 1.27) (thickness 0.15)) (justify left bottom) hide)
      )
      (property "Author" "Antmicro" (id 7) (at 20.32 -25.4 0)
        (effects (font (size 1.27 1.27) (thickness 0.15)) (justify left bottom) hide)
      )
      (property "Val" "100n" (id 8) (at 20.32 -7.62 0)
        (effects (font (size 1.27 1.27) (thickness 0.15)) (justify left bottom))
      )
      (property "Voltage" "50V" (id 9) (at 20.32 -27.94 0)
        (effects (font (size 1.27 1.27)) (justify left bottom) hide)
      )
      (property "Dielectric" "X5R" (id 10) (at 20.32 -30.48 0)
        (effects (font (size 1.27 1.27)) (justify left bottom) hide)
      )
      (property "ki_description" " " (id 11) (at 0 0 0)
        (effects (font (size 1.27 1.27)) hide)
      )
      (symbol "C_100n_0402_24_0_1"
        (polyline
          (pts
            (xy 2.032 -1.524)
            (xy 2.032 1.524)
          )
          (stroke (width 0.3048) (type default) (color 0 0 0 0))
          (fill (type none))
        )
        (polyline
          (pts
            (xy 3.048 -1.524)
            (xy 3.048 1.524)
          )
          (stroke (width 0.3302) (type default) (color 0 0 0 0))
          (fill (type none))
        )
      )
      (symbol "C_100n_0402_24_1_1"
        (pin passive line (at 0 0 0) (length 2.032)
          (name "~" (effects (font (size 1.27 1.27))))
          (number "1" (effects (font (size 1.27 1.27))))
        )
        (pin passive line (at 5.08 0 180) (length 2.032)
          (name "~" (effects (font (size 1.27 1.27))))
          (number "2" (effects (font (size 1.27 1.27))))
        )
      )
    )
	(symbol "sa800u-baseboard-hw:C_100n_0402_25" (pin_numbers hide) (pin_names hide) (in_bom yes) (on_board yes)
      (property "Reference" "C" (id 0) (at 20.32 -5.08 0)
        (effects (font (size 1.27 1.27) (thickness 0.15)) (justify left bottom))
      )
      (property "Value" "C_100n_0402_25" (id 1) (at 20.32 -10.16 0)
        (effects (font (size 1.27 1.27) (thickness 0.15)) (justify left bottom) hide)
      )
      (property "Footprint" "sa800u-baseboard-hw-footprints:C_0402_1005Metric" (id 2) (at 20.32 -12.7 0)
        (effects (font (size 1.27 1.27) (thickness 0.15)) (justify left bottom) hide)
      )
      (property "Datasheet" "https://search.murata.co.jp/Ceramy/image/img/A01X/G101/ENG/GRM155R61H104KE14-01.pdf" (id 3) (at 20.32 -15.24 0)
        (effects (font (size 1.27 1.27) (thickness 0.15)) (justify left bottom) hide)
      )
      (property "MPN" "GRM155R61H104KE14D" (id 4) (at 20.32 -17.78 0)
        (effects (font (size 1.27 1.27) (thickness 0.15)) (justify left bottom) hide)
      )
      (property "Manufacturer" "Murata" (id 5) (at 20.32 -20.32 0)
        (effects (font (size 1.27 1.27) (thickness 0.15)) (justify left bottom) hide)
      )
      (property "License" "Apache-2.0" (id 6) (at 20.32 -22.86 0)
        (effects (font (size 1.27 1.27) (thickness 0.15)) (justify left bottom) hide)
      )
      (property "Author" "Antmicro" (id 7) (at 20.32 -25.4 0)
        (effects (font (size 1.27 1.27) (thickness 0.15)) (justify left bottom) hide)
      )
      (property "Val" "100n" (id 8) (at 20.32 -7.62 0)
        (effects (font (size 1.27 1.27) (thickness 0.15)) (justify left bottom))
      )
      (property "Voltage" "50V" (id 9) (at 20.32 -27.94 0)
        (effects (font (size 1.27 1.27)) (justify left bottom) hide)
      )
      (property "Dielectric" "X5R" (id 10) (at 20.32 -30.48 0)
        (effects (font (size 1.27 1.27)) (justify left bottom) hide)
      )
      (property "ki_description" " " (id 11) (at 0 0 0)
        (effects (font (size 1.27 1.27)) hide)
      )
      (symbol "C_100n_0402_25_0_1"
        (polyline
          (pts
            (xy 2.032 -1.524)
            (xy 2.032 1.524)
          )
          (stroke (width 0.3048) (type default) (color 0 0 0 0))
          (fill (type none))
        )
        (polyline
          (pts
            (xy 3.048 -1.524)
            (xy 3.048 1.524)
          )
          (stroke (width 0.3302) (type default) (color 0 0 0 0))
          (fill (type none))
        )
      )
      (symbol "C_100n_0402_25_1_1"
        (pin passive line (at 0 0 0) (length 2.032)
          (name "~" (effects (font (size 1.27 1.27))))
          (number "1" (effects (font (size 1.27 1.27))))
        )
        (pin passive line (at 5.08 0 180) (length 2.032)
          (name "~" (effects (font (size 1.27 1.27))))
          (number "2" (effects (font (size 1.27 1.27))))
        )
      )
    )
	(symbol "sa800u-baseboard-hw:C_100n_0402_26" (pin_numbers hide) (pin_names hide) (in_bom yes) (on_board yes)
      (property "Reference" "C" (id 0) (at 20.32 -5.08 0)
        (effects (font (size 1.27 1.27) (thickness 0.15)) (justify left bottom))
      )
      (property "Value" "C_100n_0402_26" (id 1) (at 20.32 -10.16 0)
        (effects (font (size 1.27 1.27) (thickness 0.15)) (justify left bottom) hide)
      )
      (property "Footprint" "sa800u-baseboard-hw-footprints:C_0402_1005Metric" (id 2) (at 20.32 -12.7 0)
        (effects (font (size 1.27 1.27) (thickness 0.15)) (justify left bottom) hide)
      )
      (property "Datasheet" "https://search.murata.co.jp/Ceramy/image/img/A01X/G101/ENG/GRM155R61H104KE14-01.pdf" (id 3) (at 20.32 -15.24 0)
        (effects (font (size 1.27 1.27) (thickness 0.15)) (justify left bottom) hide)
      )
      (property "MPN" "GRM155R61H104KE14D" (id 4) (at 20.32 -17.78 0)
        (effects (font (size 1.27 1.27) (thickness 0.15)) (justify left bottom) hide)
      )
      (property "Manufacturer" "Murata" (id 5) (at 20.32 -20.32 0)
        (effects (font (size 1.27 1.27) (thickness 0.15)) (justify left bottom) hide)
      )
      (property "License" "Apache-2.0" (id 6) (at 20.32 -22.86 0)
        (effects (font (size 1.27 1.27) (thickness 0.15)) (justify left bottom) hide)
      )
      (property "Author" "Antmicro" (id 7) (at 20.32 -25.4 0)
        (effects (font (size 1.27 1.27) (thickness 0.15)) (justify left bottom) hide)
      )
      (property "Val" "100n" (id 8) (at 20.32 -7.62 0)
        (effects (font (size 1.27 1.27) (thickness 0.15)) (justify left bottom))
      )
      (property "Voltage" "50V" (id 9) (at 20.32 -27.94 0)
        (effects (font (size 1.27 1.27)) (justify left bottom) hide)
      )
      (property "Dielectric" "X5R" (id 10) (at 20.32 -30.48 0)
        (effects (font (size 1.27 1.27)) (justify left bottom) hide)
      )
      (property "ki_description" " " (id 11) (at 0 0 0)
        (effects (font (size 1.27 1.27)) hide)
      )
      (symbol "C_100n_0402_26_0_1"
        (polyline
          (pts
            (xy 2.032 -1.524)
            (xy 2.032 1.524)
          )
          (stroke (width 0.3048) (type default) (color 0 0 0 0))
          (fill (type none))
        )
        (polyline
          (pts
            (xy 3.048 -1.524)
            (xy 3.048 1.524)
          )
          (stroke (width 0.3302) (type default) (color 0 0 0 0))
          (fill (type none))
        )
      )
      (symbol "C_100n_0402_26_1_1"
        (pin passive line (at 0 0 0) (length 2.032)
          (name "~" (effects (font (size 1.27 1.27))))
          (number "1" (effects (font (size 1.27 1.27))))
        )
        (pin passive line (at 5.08 0 180) (length 2.032)
          (name "~" (effects (font (size 1.27 1.27))))
          (number "2" (effects (font (size 1.27 1.27))))
        )
      )
    )
	(symbol "sa800u-baseboard-hw:C_100n_0805_100V" (pin_numbers hide) (pin_names hide) (in_bom yes) (on_board yes)
      (property "Reference" "C" (id 0) (at 20.32 -5.08 0)
        (effects (font (size 1.27 1.27) (thickness 0.15)) (justify left bottom))
      )
      (property "Value" "C_100n_0805_100V" (id 1) (at 20.32 -10.16 0)
        (effects (font (size 1.27 1.27) (thickness 0.15)) (justify left bottom) hide)
      )
      (property "Footprint" "sa800u-baseboard-hw-footprints:C_0805_2012Metric" (id 2) (at 20.32 -12.7 0)
        (effects (font (size 1.27 1.27) (thickness 0.15)) (justify left bottom) hide)
      )
      (property "Datasheet" "https://www.mouser.pl/datasheet/2/585/MLCC-1837944.pdf" (id 3) (at 20.32 -15.24 0)
        (effects (font (size 1.27 1.27) (thickness 0.15)) (justify left bottom) hide)
      )
      (property "MPN" "CL21B104KCFNNNE" (id 4) (at 20.32 -17.78 0)
        (effects (font (size 1.27 1.27) (thickness 0.15)) (justify left bottom) hide)
      )
      (property "Manufacturer" "SAMSUNG" (id 5) (at 20.32 -20.32 0)
        (effects (font (size 1.27 1.27) (thickness 0.15)) (justify left bottom) hide)
      )
      (property "License" "Apache-2.0" (id 6) (at 20.32 -22.86 0)
        (effects (font (size 1.27 1.27) (thickness 0.15)) (justify left bottom) hide)
      )
      (property "Author" "Antmicro" (id 7) (at 20.32 -25.4 0)
        (effects (font (size 1.27 1.27) (thickness 0.15)) (justify left bottom) hide)
      )
      (property "Val" "100n/100V" (id 8) (at 20.32 -7.62 0)
        (effects (font (size 1.27 1.27) (thickness 0.15)) (justify left bottom))
      )
      (property "Voltage" "100V" (id 9) (at 20.32 -27.94 0)
        (effects (font (size 1.27 1.27)) (justify left bottom) hide)
      )
      (property "Dielectric" "X7R" (id 10) (at 20.32 -30.48 0)
        (effects (font (size 1.27 1.27)) (justify left bottom) hide)
      )
      (property "ki_description" " " (id 11) (at 0 0 0)
        (effects (font (size 1.27 1.27)) hide)
      )
      (symbol "C_100n_0805_100V_0_1"
        (polyline
          (pts
            (xy 2.032 -1.524)
            (xy 2.032 1.524)
          )
          (stroke (width 0.3048) (type default) (color 0 0 0 0))
          (fill (type none))
        )
        (polyline
          (pts
            (xy 3.048 -1.524)
            (xy 3.048 1.524)
          )
          (stroke (width 0.3302) (type default) (color 0 0 0 0))
          (fill (type none))
        )
      )
      (symbol "C_100n_0805_100V_1_1"
        (pin passive line (at 0 0 0) (length 2.032)
          (name "~" (effects (font (size 1.27 1.27))))
          (number "1" (effects (font (size 1.27 1.27))))
        )
        (pin passive line (at 5.08 0 180) (length 2.032)
          (name "~" (effects (font (size 1.27 1.27))))
          (number "2" (effects (font (size 1.27 1.27))))
        )
      )
    )
	(symbol "sa800u-baseboard-hw:C_100u_0805" (pin_numbers hide) (pin_names hide) (in_bom yes) (on_board yes)
      (property "Reference" "C" (id 0) (at 20.32 -5.08 0)
        (effects (font (size 1.27 1.27) (thickness 0.15)) (justify left bottom))
      )
      (property "Value" "C_100u_0805" (id 1) (at 20.32 -10.16 0)
        (effects (font (size 1.27 1.27) (thickness 0.15)) (justify left bottom) hide)
      )
      (property "Footprint" "sa800u-baseboard-hw-footprints:C_0805_2012Metric" (id 2) (at 20.32 -12.7 0)
        (effects (font (size 1.27 1.27) (thickness 0.15)) (justify left bottom) hide)
      )
      (property "Datasheet" " " (id 3) (at 20.32 -15.24 0)
        (effects (font (size 1.27 1.27) (thickness 0.15)) (justify left bottom) hide)
      )
      (property "MPN" "GRM21BR60J107ME15L" (id 4) (at 20.32 -17.78 0)
        (effects (font (size 1.27 1.27) (thickness 0.15)) (justify left bottom) hide)
      )
      (property "Manufacturer" "Murata" (id 5) (at 20.32 -20.32 0)
        (effects (font (size 1.27 1.27) (thickness 0.15)) (justify left bottom) hide)
      )
      (property "License" "Apache-2.0" (id 6) (at 20.32 -22.86 0)
        (effects (font (size 1.27 1.27) (thickness 0.15)) (justify left bottom) hide)
      )
      (property "Author" "Antmicro" (id 7) (at 20.32 -25.4 0)
        (effects (font (size 1.27 1.27) (thickness 0.15)) (justify left bottom) hide)
      )
      (property "Val" "100u" (id 8) (at 20.32 -7.62 0)
        (effects (font (size 1.27 1.27) (thickness 0.15)) (justify left bottom))
      )
      (property "Voltage" "" (id 9) (at 20.32 -27.94 0)
        (effects (font (size 1.27 1.27)) (justify left bottom) hide)
      )
      (property "Dielectric" "" (id 10) (at 20.32 -30.48 0)
        (effects (font (size 1.27 1.27)) (justify left bottom) hide)
      )
      (property "ki_description" " " (id 11) (at 0 0 0)
        (effects (font (size 1.27 1.27)) hide)
      )
      (symbol "C_100u_0805_0_1"
        (polyline
          (pts
            (xy 2.032 -1.524)
            (xy 2.032 1.524)
          )
          (stroke (width 0.3048) (type default) (color 0 0 0 0))
          (fill (type none))
        )
        (polyline
          (pts
            (xy 3.048 -1.524)
            (xy 3.048 1.524)
          )
          (stroke (width 0.3302) (type default) (color 0 0 0 0))
          (fill (type none))
        )
      )
      (symbol "C_100u_0805_1_1"
        (pin passive line (at 0 0 0) (length 2.032)
          (name "~" (effects (font (size 1.27 1.27))))
          (number "1" (effects (font (size 1.27 1.27))))
        )
        (pin passive line (at 5.08 0 180) (length 2.032)
          (name "~" (effects (font (size 1.27 1.27))))
          (number "2" (effects (font (size 1.27 1.27))))
        )
      )
    )
	(symbol "sa800u-baseboard-hw:C_10n_0402" (pin_numbers hide) (pin_names hide) (in_bom yes) (on_board yes)
      (property "Reference" "C" (id 0) (at 20.32 -5.08 0)
        (effects (font (size 1.27 1.27) (thickness 0.15)) (justify left bottom))
      )
      (property "Value" "C_10n_0402" (id 1) (at 20.32 -10.16 0)
        (effects (font (size 1.27 1.27) (thickness 0.15)) (justify left bottom) hide)
      )
      (property "Footprint" "sa800u-baseboard-hw-footprints:C_0402_1005Metric" (id 2) (at 20.32 -12.7 0)
        (effects (font (size 1.27 1.27) (thickness 0.15)) (justify left bottom) hide)
      )
      (property "Datasheet" "https://search.murata.co.jp/Ceramy/image/img/A01X/G101/ENG/GRM155R71H103KA88-01.pdf" (id 3) (at 20.32 -15.24 0)
        (effects (font (size 1.27 1.27) (thickness 0.15)) (justify left bottom) hide)
      )
      (property "MPN" "GRM155R71H103KA88D" (id 4) (at 20.32 -17.78 0)
        (effects (font (size 1.27 1.27) (thickness 0.15)) (justify left bottom) hide)
      )
      (property "Manufacturer" "Murata" (id 5) (at 20.32 -20.32 0)
        (effects (font (size 1.27 1.27) (thickness 0.15)) (justify left bottom) hide)
      )
      (property "License" "Apache-2.0" (id 6) (at 20.32 -22.86 0)
        (effects (font (size 1.27 1.27) (thickness 0.15)) (justify left bottom) hide)
      )
      (property "Author" "Antmicro" (id 7) (at 20.32 -25.4 0)
        (effects (font (size 1.27 1.27) (thickness 0.15)) (justify left bottom) hide)
      )
      (property "Val" "10n" (id 8) (at 20.32 -7.62 0)
        (effects (font (size 1.27 1.27) (thickness 0.15)) (justify left bottom))
      )
      (property "Voltage" "50V" (id 9) (at 20.32 -27.94 0)
        (effects (font (size 1.27 1.27)) (justify left bottom) hide)
      )
      (property "Dielectric" "X7R" (id 10) (at 20.32 -30.48 0)
        (effects (font (size 1.27 1.27)) (justify left bottom) hide)
      )
      (property "ki_description" " " (id 11) (at 0 0 0)
        (effects (font (size 1.27 1.27)) hide)
      )
      (symbol "C_10n_0402_0_1"
        (polyline
          (pts
            (xy 2.032 -1.524)
            (xy 2.032 1.524)
          )
          (stroke (width 0.3048) (type default) (color 0 0 0 0))
          (fill (type none))
        )
        (polyline
          (pts
            (xy 3.048 -1.524)
            (xy 3.048 1.524)
          )
          (stroke (width 0.3302) (type default) (color 0 0 0 0))
          (fill (type none))
        )
      )
      (symbol "C_10n_0402_1_1"
        (pin passive line (at 0 0 0) (length 2.032)
          (name "~" (effects (font (size 1.27 1.27))))
          (number "1" (effects (font (size 1.27 1.27))))
        )
        (pin passive line (at 5.08 0 180) (length 2.032)
          (name "~" (effects (font (size 1.27 1.27))))
          (number "2" (effects (font (size 1.27 1.27))))
        )
      )
    )
	(symbol "sa800u-baseboard-hw:C_10p_0402" (pin_numbers hide) (pin_names hide) (in_bom yes) (on_board yes)
      (property "Reference" "C" (id 0) (at 20.32 -5.08 0)
        (effects (font (size 1.27 1.27) (thickness 0.15)) (justify left bottom))
      )
      (property "Value" "C_10p_0402" (id 1) (at 20.32 -10.16 0)
        (effects (font (size 1.27 1.27) (thickness 0.15)) (justify left bottom) hide)
      )
      (property "Footprint" "sa800u-baseboard-hw-footprints:C_0402_1005Metric" (id 2) (at 20.32 -12.7 0)
        (effects (font (size 1.27 1.27) (thickness 0.15)) (justify left bottom) hide)
      )
      (property "Datasheet" "https://search.murata.co.jp/Ceramy/image/img/A01X/G101/ENG/GCM1555C1H100GA16-01.pdf" (id 3) (at 20.32 -15.24 0)
        (effects (font (size 1.27 1.27) (thickness 0.15)) (justify left bottom) hide)
      )
      (property "MPN" "GCM1555C1H100GA16D" (id 4) (at 20.32 -17.78 0)
        (effects (font (size 1.27 1.27) (thickness 0.15)) (justify left bottom) hide)
      )
      (property "Manufacturer" "Murata" (id 5) (at 20.32 -20.32 0)
        (effects (font (size 1.27 1.27) (thickness 0.15)) (justify left bottom) hide)
      )
      (property "License" "Apache-2.0" (id 6) (at 20.32 -22.86 0)
        (effects (font (size 1.27 1.27) (thickness 0.15)) (justify left bottom) hide)
      )
      (property "Author" "Antmicro" (id 7) (at 20.32 -25.4 0)
        (effects (font (size 1.27 1.27) (thickness 0.15)) (justify left bottom) hide)
      )
      (property "Val" "10p" (id 8) (at 20.32 -7.62 0)
        (effects (font (size 1.27 1.27) (thickness 0.15)) (justify left bottom))
      )
      (property "Voltage" "50V" (id 9) (at 20.32 -27.94 0)
        (effects (font (size 1.27 1.27)) (justify left bottom) hide)
      )
      (property "Dielectric" "C0G" (id 10) (at 20.32 -30.48 0)
        (effects (font (size 1.27 1.27)) (justify left bottom) hide)
      )
      (property "ki_description" " " (id 11) (at 0 0 0)
        (effects (font (size 1.27 1.27)) hide)
      )
      (symbol "C_10p_0402_0_1"
        (polyline
          (pts
            (xy 2.032 -1.524)
            (xy 2.032 1.524)
          )
          (stroke (width 0.3048) (type default) (color 0 0 0 0))
          (fill (type none))
        )
        (polyline
          (pts
            (xy 3.048 -1.524)
            (xy 3.048 1.524)
          )
          (stroke (width 0.3302) (type default) (color 0 0 0 0))
          (fill (type none))
        )
      )
      (symbol "C_10p_0402_1_1"
        (pin passive line (at 0 0 0) (length 2.032)
          (name "~" (effects (font (size 1.27 1.27))))
          (number "1" (effects (font (size 1.27 1.27))))
        )
        (pin passive line (at 5.08 0 180) (length 2.032)
          (name "~" (effects (font (size 1.27 1.27))))
          (number "2" (effects (font (size 1.27 1.27))))
        )
      )
    )
	(symbol "sa800u-baseboard-hw:C_10u_0402" (pin_numbers hide) (pin_names hide) (in_bom yes) (on_board yes)
      (property "Reference" "C" (id 0) (at 20.32 -5.08 0)
        (effects (font (size 1.27 1.27) (thickness 0.15)) (justify left bottom))
      )
      (property "Value" "C_10u_0402" (id 1) (at 20.32 -10.16 0)
        (effects (font (size 1.27 1.27) (thickness 0.15)) (justify left bottom) hide)
      )
      (property "Footprint" "sa800u-baseboard-hw-footprints:C_0402_1005Metric" (id 2) (at 20.32 -12.7 0)
        (effects (font (size 1.27 1.27) (thickness 0.15)) (justify left bottom) hide)
      )
      (property "Datasheet" " " (id 3) (at 20.32 -15.24 0)
        (effects (font (size 1.27 1.27) (thickness 0.15)) (justify left bottom) hide)
      )
      (property "MPN" "CC0402MRX5R5BB106" (id 4) (at 20.32 -17.78 0)
        (effects (font (size 1.27 1.27) (thickness 0.15)) (justify left bottom) hide)
      )
      (property "Manufacturer" "Yaego" (id 5) (at 20.32 -20.32 0)
        (effects (font (size 1.27 1.27) (thickness 0.15)) (justify left bottom) hide)
      )
      (property "License" "Apache-2.0" (id 6) (at 20.32 -22.86 0)
        (effects (font (size 1.27 1.27) (thickness 0.15)) (justify left bottom) hide)
      )
      (property "Author" "Antmicro" (id 7) (at 20.32 -25.4 0)
        (effects (font (size 1.27 1.27) (thickness 0.15)) (justify left bottom) hide)
      )
      (property "Val" "10u" (id 8) (at 20.32 -7.62 0)
        (effects (font (size 1.27 1.27) (thickness 0.15)) (justify left bottom))
      )
      (property "Voltage" "" (id 9) (at 20.32 -27.94 0)
        (effects (font (size 1.27 1.27)) (justify left bottom) hide)
      )
      (property "Dielectric" "" (id 10) (at 20.32 -30.48 0)
        (effects (font (size 1.27 1.27)) (justify left bottom) hide)
      )
      (property "ki_description" " " (id 11) (at 0 0 0)
        (effects (font (size 1.27 1.27)) hide)
      )
      (symbol "C_10u_0402_0_1"
        (polyline
          (pts
            (xy 2.032 -1.524)
            (xy 2.032 1.524)
          )
          (stroke (width 0.3048) (type default) (color 0 0 0 0))
          (fill (type none))
        )
        (polyline
          (pts
            (xy 3.048 -1.524)
            (xy 3.048 1.524)
          )
          (stroke (width 0.3302) (type default) (color 0 0 0 0))
          (fill (type none))
        )
      )
      (symbol "C_10u_0402_1_1"
        (pin passive line (at 0 0 0) (length 2.032)
          (name "~" (effects (font (size 1.27 1.27))))
          (number "1" (effects (font (size 1.27 1.27))))
        )
        (pin passive line (at 5.08 0 180) (length 2.032)
          (name "~" (effects (font (size 1.27 1.27))))
          (number "2" (effects (font (size 1.27 1.27))))
        )
      )
    )
	(symbol "sa800u-baseboard-hw:C_10u_25V_0603" (pin_numbers hide) (pin_names hide) (in_bom yes) (on_board yes)
      (property "Reference" "C" (id 0) (at 20.32 -5.08 0)
        (effects (font (size 1.27 1.27) (thickness 0.15)) (justify left bottom))
      )
      (property "Value" "C_10u_25V_0603" (id 1) (at 20.32 -10.16 0)
        (effects (font (size 1.27 1.27) (thickness 0.15)) (justify left bottom) hide)
      )
      (property "Footprint" "sa800u-baseboard-hw-footprints:C_0603_1608Metric" (id 2) (at 20.32 -12.7 0)
        (effects (font (size 1.27 1.27) (thickness 0.15)) (justify left bottom) hide)
      )
      (property "Datasheet" " " (id 3) (at 20.32 -15.24 0)
        (effects (font (size 1.27 1.27) (thickness 0.15)) (justify left bottom) hide)
      )
      (property "MPN" "C1608X5R1E106M080AC" (id 4) (at 20.32 -17.78 0)
        (effects (font (size 1.27 1.27) (thickness 0.15)) (justify left bottom) hide)
      )
      (property "Manufacturer" "TDK" (id 5) (at 20.32 -20.32 0)
        (effects (font (size 1.27 1.27) (thickness 0.15)) (justify left bottom) hide)
      )
      (property "License" "Apache-2.0" (id 6) (at 20.32 -22.86 0)
        (effects (font (size 1.27 1.27) (thickness 0.15)) (justify left bottom) hide)
      )
      (property "Author" "Antmicro" (id 7) (at 20.32 -25.4 0)
        (effects (font (size 1.27 1.27) (thickness 0.15)) (justify left bottom) hide)
      )
      (property "Val" "10u/25V" (id 8) (at 20.32 -7.62 0)
        (effects (font (size 1.27 1.27) (thickness 0.15)) (justify left bottom))
      )
      (property "Voltage" "" (id 9) (at 20.32 -27.94 0)
        (effects (font (size 1.27 1.27)) (justify left bottom) hide)
      )
      (property "Dielectric" "" (id 10) (at 20.32 -30.48 0)
        (effects (font (size 1.27 1.27)) (justify left bottom) hide)
      )
      (property "ki_description" " " (id 11) (at 0 0 0)
        (effects (font (size 1.27 1.27)) hide)
      )
      (symbol "C_10u_25V_0603_0_1"
        (polyline
          (pts
            (xy 2.032 -1.524)
            (xy 2.032 1.524)
          )
          (stroke (width 0.3048) (type default) (color 0 0 0 0))
          (fill (type none))
        )
        (polyline
          (pts
            (xy 3.048 -1.524)
            (xy 3.048 1.524)
          )
          (stroke (width 0.3302) (type default) (color 0 0 0 0))
          (fill (type none))
        )
      )
      (symbol "C_10u_25V_0603_1_1"
        (pin passive line (at 0 0 0) (length 2.032)
          (name "~" (effects (font (size 1.27 1.27))))
          (number "1" (effects (font (size 1.27 1.27))))
        )
        (pin passive line (at 5.08 0 180) (length 2.032)
          (name "~" (effects (font (size 1.27 1.27))))
          (number "2" (effects (font (size 1.27 1.27))))
        )
      )
    )
	(symbol "sa800u-baseboard-hw:C_15p_0402" (pin_numbers hide) (pin_names hide) (in_bom yes) (on_board yes)
      (property "Reference" "C" (id 0) (at 20.32 -5.08 0)
        (effects (font (size 1.27 1.27) (thickness 0.15)) (justify left bottom))
      )
      (property "Value" "C_15p_0402" (id 1) (at 20.32 -10.16 0)
        (effects (font (size 1.27 1.27) (thickness 0.15)) (justify left bottom) hide)
      )
      (property "Footprint" "sa800u-baseboard-hw-footprints:C_0402_1005Metric" (id 2) (at 20.32 -12.7 0)
        (effects (font (size 1.27 1.27) (thickness 0.15)) (justify left bottom) hide)
      )
      (property "Datasheet" " " (id 3) (at 20.32 -15.24 0)
        (effects (font (size 1.27 1.27) (thickness 0.15)) (justify left bottom) hide)
      )
      (property "MPN" "MC0402N150J500CT" (id 4) (at 20.32 -17.78 0)
        (effects (font (size 1.27 1.27) (thickness 0.15)) (justify left bottom) hide)
      )
      (property "Manufacturer" "Multicomp" (id 5) (at 20.32 -20.32 0)
        (effects (font (size 1.27 1.27) (thickness 0.15)) (justify left bottom) hide)
      )
      (property "License" "Apache-2.0" (id 6) (at 20.32 -22.86 0)
        (effects (font (size 1.27 1.27) (thickness 0.15)) (justify left bottom) hide)
      )
      (property "Author" "Antmicro" (id 7) (at 20.32 -25.4 0)
        (effects (font (size 1.27 1.27) (thickness 0.15)) (justify left bottom) hide)
      )
      (property "Val" "15p" (id 8) (at 20.32 -7.62 0)
        (effects (font (size 1.27 1.27) (thickness 0.15)) (justify left bottom))
      )
      (property "Voltage" "" (id 9) (at 20.32 -27.94 0)
        (effects (font (size 1.27 1.27)) (justify left bottom) hide)
      )
      (property "Dielectric" "" (id 10) (at 20.32 -30.48 0)
        (effects (font (size 1.27 1.27)) (justify left bottom) hide)
      )
      (property "ki_description" " " (id 11) (at 0 0 0)
        (effects (font (size 1.27 1.27)) hide)
      )
      (symbol "C_15p_0402_0_1"
        (polyline
          (pts
            (xy 2.032 -1.524)
            (xy 2.032 1.524)
          )
          (stroke (width 0.3048) (type default) (color 0 0 0 0))
          (fill (type none))
        )
        (polyline
          (pts
            (xy 3.048 -1.524)
            (xy 3.048 1.524)
          )
          (stroke (width 0.3302) (type default) (color 0 0 0 0))
          (fill (type none))
        )
      )
      (symbol "C_15p_0402_1_1"
        (pin passive line (at 0 0 0) (length 2.032)
          (name "~" (effects (font (size 1.27 1.27))))
          (number "1" (effects (font (size 1.27 1.27))))
        )
        (pin passive line (at 5.08 0 180) (length 2.032)
          (name "~" (effects (font (size 1.27 1.27))))
          (number "2" (effects (font (size 1.27 1.27))))
        )
      )
    )
	(symbol "sa800u-baseboard-hw:C_1u_0402" (pin_numbers hide) (pin_names hide) (in_bom yes) (on_board yes)
      (property "Reference" "C" (id 0) (at 20.32 -5.08 0)
        (effects (font (size 1.27 1.27) (thickness 0.15)) (justify left bottom))
      )
      (property "Value" "C_1u_0402" (id 1) (at 20.32 -10.16 0)
        (effects (font (size 1.27 1.27) (thickness 0.15)) (justify left bottom) hide)
      )
      (property "Footprint" "sa800u-baseboard-hw-footprints:C_0402_1005Metric" (id 2) (at 20.32 -12.7 0)
        (effects (font (size 1.27 1.27) (thickness 0.15)) (justify left bottom) hide)
      )
      (property "Datasheet" " " (id 3) (at 20.32 -15.24 0)
        (effects (font (size 1.27 1.27) (thickness 0.15)) (justify left bottom) hide)
      )
      (property "MPN" "C1005X6S1A105K050BC" (id 4) (at 20.32 -17.78 0)
        (effects (font (size 1.27 1.27) (thickness 0.15)) (justify left bottom) hide)
      )
      (property "Manufacturer" "TDK" (id 5) (at 20.32 -20.32 0)
        (effects (font (size 1.27 1.27) (thickness 0.15)) (justify left bottom) hide)
      )
      (property "License" "Apache-2.0" (id 6) (at 20.32 -22.86 0)
        (effects (font (size 1.27 1.27) (thickness 0.15)) (justify left bottom) hide)
      )
      (property "Author" "Antmicro" (id 7) (at 20.32 -25.4 0)
        (effects (font (size 1.27 1.27) (thickness 0.15)) (justify left bottom) hide)
      )
      (property "Val" "1u" (id 8) (at 20.32 -7.62 0)
        (effects (font (size 1.27 1.27) (thickness 0.15)) (justify left bottom))
      )
      (property "Voltage" "" (id 9) (at 20.32 -27.94 0)
        (effects (font (size 1.27 1.27)) (justify left bottom) hide)
      )
      (property "Dielectric" "" (id 10) (at 20.32 -30.48 0)
        (effects (font (size 1.27 1.27)) (justify left bottom) hide)
      )
      (property "ki_description" " " (id 11) (at 0 0 0)
        (effects (font (size 1.27 1.27)) hide)
      )
      (symbol "C_1u_0402_0_1"
        (polyline
          (pts
            (xy 2.032 -1.524)
            (xy 2.032 1.524)
          )
          (stroke (width 0.3048) (type default) (color 0 0 0 0))
          (fill (type none))
        )
        (polyline
          (pts
            (xy 3.048 -1.524)
            (xy 3.048 1.524)
          )
          (stroke (width 0.3302) (type default) (color 0 0 0 0))
          (fill (type none))
        )
      )
      (symbol "C_1u_0402_1_1"
        (pin passive line (at 0 0 0) (length 2.032)
          (name "~" (effects (font (size 1.27 1.27))))
          (number "1" (effects (font (size 1.27 1.27))))
        )
        (pin passive line (at 5.08 0 180) (length 2.032)
          (name "~" (effects (font (size 1.27 1.27))))
          (number "2" (effects (font (size 1.27 1.27))))
        )
      )
    )
	(symbol "sa800u-baseboard-hw:C_1u_0603" (pin_numbers hide) (pin_names hide) (in_bom yes) (on_board yes)
      (property "Reference" "C" (id 0) (at 20.32 -5.08 0)
        (effects (font (size 1.27 1.27) (thickness 0.15)) (justify left bottom))
      )
      (property "Value" "C_1u_0603" (id 1) (at 20.32 -10.16 0)
        (effects (font (size 1.27 1.27) (thickness 0.15)) (justify left bottom) hide)
      )
      (property "Footprint" "sa800u-baseboard-hw-footprints:C_0603_1608Metric" (id 2) (at 20.32 -12.7 0)
        (effects (font (size 1.27 1.27) (thickness 0.15)) (justify left bottom) hide)
      )
      (property "Datasheet" " " (id 3) (at 20.32 -15.24 0)
        (effects (font (size 1.27 1.27) (thickness 0.15)) (justify left bottom) hide)
      )
      (property "MPN" "0603YD105KAT2A" (id 4) (at 20.32 -17.78 0)
        (effects (font (size 1.27 1.27) (thickness 0.15)) (justify left bottom) hide)
      )
      (property "Manufacturer" "Walsin" (id 5) (at 20.32 -20.32 0)
        (effects (font (size 1.27 1.27) (thickness 0.15)) (justify left bottom) hide)
      )
      (property "License" "Apache-2.0" (id 6) (at 20.32 -22.86 0)
        (effects (font (size 1.27 1.27) (thickness 0.15)) (justify left bottom) hide)
      )
      (property "Author" "Antmicro" (id 7) (at 20.32 -25.4 0)
        (effects (font (size 1.27 1.27) (thickness 0.15)) (justify left bottom) hide)
      )
      (property "Val" "1u" (id 8) (at 20.32 -7.62 0)
        (effects (font (size 1.27 1.27) (thickness 0.15)) (justify left bottom))
      )
      (property "Voltage" "" (id 9) (at 20.32 -27.94 0)
        (effects (font (size 1.27 1.27)) (justify left bottom) hide)
      )
      (property "Dielectric" "" (id 10) (at 20.32 -30.48 0)
        (effects (font (size 1.27 1.27)) (justify left bottom) hide)
      )
      (property "ki_description" " " (id 11) (at 0 0 0)
        (effects (font (size 1.27 1.27)) hide)
      )
      (symbol "C_1u_0603_0_1"
        (polyline
          (pts
            (xy 2.032 -1.524)
            (xy 2.032 1.524)
          )
          (stroke (width 0.3048) (type default) (color 0 0 0 0))
          (fill (type none))
        )
        (polyline
          (pts
            (xy 3.048 -1.524)
            (xy 3.048 1.524)
          )
          (stroke (width 0.3302) (type default) (color 0 0 0 0))
          (fill (type none))
        )
      )
      (symbol "C_1u_0603_1_1"
        (pin passive line (at 0 0 0) (length 2.032)
          (name "~" (effects (font (size 1.27 1.27))))
          (number "1" (effects (font (size 1.27 1.27))))
        )
        (pin passive line (at 5.08 0 180) (length 2.032)
          (name "~" (effects (font (size 1.27 1.27))))
          (number "2" (effects (font (size 1.27 1.27))))
        )
      )
    )
	(symbol "sa800u-baseboard-hw:C_22u_0603" (pin_numbers hide) (pin_names hide) (in_bom yes) (on_board yes)
      (property "Reference" "C" (id 0) (at 20.32 -5.08 0)
        (effects (font (size 1.27 1.27) (thickness 0.15)) (justify left bottom))
      )
      (property "Value" "C_22u_0603" (id 1) (at 20.32 -10.16 0)
        (effects (font (size 1.27 1.27) (thickness 0.15)) (justify left bottom) hide)
      )
      (property "Footprint" "sa800u-baseboard-hw-footprints:C_0603_1608Metric" (id 2) (at 20.32 -12.7 0)
        (effects (font (size 1.27 1.27) (thickness 0.15)) (justify left bottom) hide)
      )
      (property "Datasheet" " " (id 3) (at 20.32 -15.24 0)
        (effects (font (size 1.27 1.27) (thickness 0.15)) (justify left bottom) hide)
      )
      (property "MPN" "GRM188R60J226MEA0D" (id 4) (at 20.32 -17.78 0)
        (effects (font (size 1.27 1.27) (thickness 0.15)) (justify left bottom) hide)
      )
      (property "Manufacturer" "Murata" (id 5) (at 20.32 -20.32 0)
        (effects (font (size 1.27 1.27) (thickness 0.15)) (justify left bottom) hide)
      )
      (property "License" "Apache-2.0" (id 6) (at 20.32 -22.86 0)
        (effects (font (size 1.27 1.27) (thickness 0.15)) (justify left bottom) hide)
      )
      (property "Author" "Antmicro" (id 7) (at 20.32 -25.4 0)
        (effects (font (size 1.27 1.27) (thickness 0.15)) (justify left bottom) hide)
      )
      (property "Val" "22u" (id 8) (at 20.32 -7.62 0)
        (effects (font (size 1.27 1.27) (thickness 0.15)) (justify left bottom))
      )
      (property "Voltage" "" (id 9) (at 20.32 -27.94 0)
        (effects (font (size 1.27 1.27)) (justify left bottom) hide)
      )
      (property "Dielectric" "" (id 10) (at 20.32 -30.48 0)
        (effects (font (size 1.27 1.27)) (justify left bottom) hide)
      )
      (property "ki_description" " " (id 11) (at 0 0 0)
        (effects (font (size 1.27 1.27)) hide)
      )
      (symbol "C_22u_0603_0_1"
        (polyline
          (pts
            (xy 2.032 -1.524)
            (xy 2.032 1.524)
          )
          (stroke (width 0.3048) (type default) (color 0 0 0 0))
          (fill (type none))
        )
        (polyline
          (pts
            (xy 3.048 -1.524)
            (xy 3.048 1.524)
          )
          (stroke (width 0.3302) (type default) (color 0 0 0 0))
          (fill (type none))
        )
      )
      (symbol "C_22u_0603_1_1"
        (pin passive line (at 0 0 0) (length 2.032)
          (name "~" (effects (font (size 1.27 1.27))))
          (number "1" (effects (font (size 1.27 1.27))))
        )
        (pin passive line (at 5.08 0 180) (length 2.032)
          (name "~" (effects (font (size 1.27 1.27))))
          (number "2" (effects (font (size 1.27 1.27))))
        )
      )
    )
	(symbol "sa800u-baseboard-hw:C_22u_0603_10" (pin_numbers hide) (pin_names hide) (in_bom yes) (on_board yes)
      (property "Reference" "C" (id 0) (at 20.32 -5.08 0)
        (effects (font (size 1.27 1.27) (thickness 0.15)) (justify left bottom))
      )
      (property "Value" "C_22u_0603_10" (id 1) (at 20.32 -10.16 0)
        (effects (font (size 1.27 1.27) (thickness 0.15)) (justify left bottom) hide)
      )
      (property "Footprint" "sa800u-baseboard-hw-footprints:C_0603_1608Metric" (id 2) (at 20.32 -12.7 0)
        (effects (font (size 1.27 1.27) (thickness 0.15)) (justify left bottom) hide)
      )
      (property "Datasheet" " " (id 3) (at 20.32 -15.24 0)
        (effects (font (size 1.27 1.27) (thickness 0.15)) (justify left bottom) hide)
      )
      (property "MPN" "GRM188R60J226MEA0D" (id 4) (at 20.32 -17.78 0)
        (effects (font (size 1.27 1.27) (thickness 0.15)) (justify left bottom) hide)
      )
      (property "Manufacturer" "Murata" (id 5) (at 20.32 -20.32 0)
        (effects (font (size 1.27 1.27) (thickness 0.15)) (justify left bottom) hide)
      )
      (property "License" "Apache-2.0" (id 6) (at 20.32 -22.86 0)
        (effects (font (size 1.27 1.27) (thickness 0.15)) (justify left bottom) hide)
      )
      (property "Author" "Antmicro" (id 7) (at 20.32 -25.4 0)
        (effects (font (size 1.27 1.27) (thickness 0.15)) (justify left bottom) hide)
      )
      (property "Val" "22u" (id 8) (at 20.32 -7.62 0)
        (effects (font (size 1.27 1.27) (thickness 0.15)) (justify left bottom))
      )
      (property "Voltage" "" (id 9) (at 20.32 -27.94 0)
        (effects (font (size 1.27 1.27)) (justify left bottom) hide)
      )
      (property "Dielectric" "" (id 10) (at 20.32 -30.48 0)
        (effects (font (size 1.27 1.27)) (justify left bottom) hide)
      )
      (property "ki_description" " " (id 11) (at 0 0 0)
        (effects (font (size 1.27 1.27)) hide)
      )
      (symbol "C_22u_0603_10_0_1"
        (polyline
          (pts
            (xy 2.032 -1.524)
            (xy 2.032 1.524)
          )
          (stroke (width 0.3048) (type default) (color 0 0 0 0))
          (fill (type none))
        )
        (polyline
          (pts
            (xy 3.048 -1.524)
            (xy 3.048 1.524)
          )
          (stroke (width 0.3302) (type default) (color 0 0 0 0))
          (fill (type none))
        )
      )
      (symbol "C_22u_0603_10_1_1"
        (pin passive line (at 0 0 0) (length 2.032)
          (name "~" (effects (font (size 1.27 1.27))))
          (number "1" (effects (font (size 1.27 1.27))))
        )
        (pin passive line (at 5.08 0 180) (length 2.032)
          (name "~" (effects (font (size 1.27 1.27))))
          (number "2" (effects (font (size 1.27 1.27))))
        )
      )
    )
	(symbol "sa800u-baseboard-hw:C_2u2_0603" (pin_numbers hide) (pin_names hide) (in_bom yes) (on_board yes)
      (property "Reference" "C" (id 0) (at 20.32 -5.08 0)
        (effects (font (size 1.27 1.27) (thickness 0.15)) (justify left bottom))
      )
      (property "Value" "C_2u2_0603" (id 1) (at 20.32 -10.16 0)
        (effects (font (size 1.27 1.27) (thickness 0.15)) (justify left bottom) hide)
      )
      (property "Footprint" "sa800u-baseboard-hw-footprints:C_0603_1608Metric" (id 2) (at 20.32 -12.7 0)
        (effects (font (size 1.27 1.27) (thickness 0.15)) (justify left bottom) hide)
      )
      (property "Datasheet" " " (id 3) (at 20.32 -15.24 0)
        (effects (font (size 1.27 1.27) (thickness 0.15)) (justify left bottom) hide)
      )
      (property "MPN" "C1608X5R1V225K080AC" (id 4) (at 20.32 -17.78 0)
        (effects (font (size 1.27 1.27) (thickness 0.15)) (justify left bottom) hide)
      )
      (property "Manufacturer" "TDK" (id 5) (at 20.32 -20.32 0)
        (effects (font (size 1.27 1.27) (thickness 0.15)) (justify left bottom) hide)
      )
      (property "License" "Apache-2.0" (id 6) (at 20.32 -22.86 0)
        (effects (font (size 1.27 1.27) (thickness 0.15)) (justify left bottom) hide)
      )
      (property "Author" "Antmicro" (id 7) (at 20.32 -25.4 0)
        (effects (font (size 1.27 1.27) (thickness 0.15)) (justify left bottom) hide)
      )
      (property "Val" "2u2" (id 8) (at 20.32 -7.62 0)
        (effects (font (size 1.27 1.27) (thickness 0.15)) (justify left bottom))
      )
      (property "Voltage" "" (id 9) (at 20.32 -27.94 0)
        (effects (font (size 1.27 1.27)) (justify left bottom) hide)
      )
      (property "Dielectric" "" (id 10) (at 20.32 -30.48 0)
        (effects (font (size 1.27 1.27)) (justify left bottom) hide)
      )
      (property "ki_description" " " (id 11) (at 0 0 0)
        (effects (font (size 1.27 1.27)) hide)
      )
      (symbol "C_2u2_0603_0_1"
        (polyline
          (pts
            (xy 2.032 -1.524)
            (xy 2.032 1.524)
          )
          (stroke (width 0.3048) (type default) (color 0 0 0 0))
          (fill (type none))
        )
        (polyline
          (pts
            (xy 3.048 -1.524)
            (xy 3.048 1.524)
          )
          (stroke (width 0.3302) (type default) (color 0 0 0 0))
          (fill (type none))
        )
      )
      (symbol "C_2u2_0603_1_1"
        (pin passive line (at 0 0 0) (length 2.032)
          (name "~" (effects (font (size 1.27 1.27))))
          (number "1" (effects (font (size 1.27 1.27))))
        )
        (pin passive line (at 5.08 0 180) (length 2.032)
          (name "~" (effects (font (size 1.27 1.27))))
          (number "2" (effects (font (size 1.27 1.27))))
        )
      )
    )
	(symbol "sa800u-baseboard-hw:C_33p_0402" (pin_numbers hide) (pin_names hide) (in_bom yes) (on_board yes)
      (property "Reference" "C" (id 0) (at 20.32 -5.08 0)
        (effects (font (size 1.27 1.27) (thickness 0.15)) (justify left bottom))
      )
      (property "Value" "C_33p_0402" (id 1) (at 20.32 -10.16 0)
        (effects (font (size 1.27 1.27) (thickness 0.15)) (justify left bottom) hide)
      )
      (property "Footprint" "sa800u-baseboard-hw-footprints:C_0402_1005Metric" (id 2) (at 20.32 -12.7 0)
        (effects (font (size 1.27 1.27) (thickness 0.15)) (justify left bottom) hide)
      )
      (property "Datasheet" " " (id 3) (at 20.32 -15.24 0)
        (effects (font (size 1.27 1.27) (thickness 0.15)) (justify left bottom) hide)
      )
      (property "MPN" "MC0402N330J500CT" (id 4) (at 20.32 -17.78 0)
        (effects (font (size 1.27 1.27) (thickness 0.15)) (justify left bottom) hide)
      )
      (property "Manufacturer" "Multicomp" (id 5) (at 20.32 -20.32 0)
        (effects (font (size 1.27 1.27) (thickness 0.15)) (justify left bottom) hide)
      )
      (property "License" "Apache-2.0" (id 6) (at 20.32 -22.86 0)
        (effects (font (size 1.27 1.27) (thickness 0.15)) (justify left bottom) hide)
      )
      (property "Author" "Antmicro" (id 7) (at 20.32 -25.4 0)
        (effects (font (size 1.27 1.27) (thickness 0.15)) (justify left bottom) hide)
      )
      (property "Val" "33p" (id 8) (at 20.32 -7.62 0)
        (effects (font (size 1.27 1.27) (thickness 0.15)) (justify left bottom))
      )
      (property "Voltage" "" (id 9) (at 20.32 -27.94 0)
        (effects (font (size 1.27 1.27)) (justify left bottom) hide)
      )
      (property "Dielectric" "" (id 10) (at 20.32 -30.48 0)
        (effects (font (size 1.27 1.27)) (justify left bottom) hide)
      )
      (property "ki_description" " " (id 11) (at 0 0 0)
        (effects (font (size 1.27 1.27)) hide)
      )
      (symbol "C_33p_0402_0_1"
        (polyline
          (pts
            (xy 2.032 -1.524)
            (xy 2.032 1.524)
          )
          (stroke (width 0.3048) (type default) (color 0 0 0 0))
          (fill (type none))
        )
        (polyline
          (pts
            (xy 3.048 -1.524)
            (xy 3.048 1.524)
          )
          (stroke (width 0.3302) (type default) (color 0 0 0 0))
          (fill (type none))
        )
      )
      (symbol "C_33p_0402_1_1"
        (pin passive line (at 0 0 0) (length 2.032)
          (name "~" (effects (font (size 1.27 1.27))))
          (number "1" (effects (font (size 1.27 1.27))))
        )
        (pin passive line (at 5.08 0 180) (length 2.032)
          (name "~" (effects (font (size 1.27 1.27))))
          (number "2" (effects (font (size 1.27 1.27))))
        )
      )
    )
	(symbol "sa800u-baseboard-hw:C_47p_0402" (pin_numbers hide) (pin_names hide) (in_bom yes) (on_board yes)
      (property "Reference" "C" (id 0) (at 20.32 -5.08 0)
        (effects (font (size 1.27 1.27) (thickness 0.15)) (justify left bottom))
      )
      (property "Value" "C_47p_0402" (id 1) (at 20.32 -10.16 0)
        (effects (font (size 1.27 1.27) (thickness 0.15)) (justify left bottom) hide)
      )
      (property "Footprint" "sa800u-baseboard-hw-footprints:C_0402_1005Metric" (id 2) (at 20.32 -12.7 0)
        (effects (font (size 1.27 1.27) (thickness 0.15)) (justify left bottom) hide)
      )
      (property "Datasheet" " " (id 3) (at 20.32 -15.24 0)
        (effects (font (size 1.27 1.27) (thickness 0.15)) (justify left bottom) hide)
      )
      (property "MPN" "GRM1555C1E470JA01D" (id 4) (at 20.32 -17.78 0)
        (effects (font (size 1.27 1.27) (thickness 0.15)) (justify left bottom) hide)
      )
      (property "Manufacturer" "Murata" (id 5) (at 20.32 -20.32 0)
        (effects (font (size 1.27 1.27) (thickness 0.15)) (justify left bottom) hide)
      )
      (property "License" "Apache-2.0" (id 6) (at 20.32 -22.86 0)
        (effects (font (size 1.27 1.27) (thickness 0.15)) (justify left bottom) hide)
      )
      (property "Author" "Antmicro" (id 7) (at 20.32 -25.4 0)
        (effects (font (size 1.27 1.27) (thickness 0.15)) (justify left bottom) hide)
      )
      (property "Val" "47p" (id 8) (at 20.32 -7.62 0)
        (effects (font (size 1.27 1.27) (thickness 0.15)) (justify left bottom))
      )
      (property "Voltage" "" (id 9) (at 20.32 -27.94 0)
        (effects (font (size 1.27 1.27)) (justify left bottom) hide)
      )
      (property "Dielectric" "C0G" (id 10) (at 20.32 -30.48 0)
        (effects (font (size 1.27 1.27)) (justify left bottom) hide)
      )
      (property "ki_description" " " (id 11) (at 0 0 0)
        (effects (font (size 1.27 1.27)) hide)
      )
      (symbol "C_47p_0402_0_1"
        (polyline
          (pts
            (xy 2.032 -1.524)
            (xy 2.032 1.524)
          )
          (stroke (width 0.3048) (type default) (color 0 0 0 0))
          (fill (type none))
        )
        (polyline
          (pts
            (xy 3.048 -1.524)
            (xy 3.048 1.524)
          )
          (stroke (width 0.3302) (type default) (color 0 0 0 0))
          (fill (type none))
        )
      )
      (symbol "C_47p_0402_1_1"
        (pin passive line (at 0 0 0) (length 2.032)
          (name "~" (effects (font (size 1.27 1.27))))
          (number "1" (effects (font (size 1.27 1.27))))
        )
        (pin passive line (at 5.08 0 180) (length 2.032)
          (name "~" (effects (font (size 1.27 1.27))))
          (number "2" (effects (font (size 1.27 1.27))))
        )
      )
    )
	(symbol "sa800u-baseboard-hw:C_47u_0603" (pin_numbers hide) (pin_names hide) (in_bom yes) (on_board yes)
      (property "Reference" "C" (id 0) (at 20.32 -5.08 0)
        (effects (font (size 1.27 1.27) (thickness 0.15)) (justify left bottom))
      )
      (property "Value" "C_47u_0603" (id 1) (at 20.32 -10.16 0)
        (effects (font (size 1.27 1.27) (thickness 0.15)) (justify left bottom) hide)
      )
      (property "Footprint" "sa800u-baseboard-hw-footprints:C_0603_1608Metric" (id 2) (at 20.32 -12.7 0)
        (effects (font (size 1.27 1.27) (thickness 0.15)) (justify left bottom) hide)
      )
      (property "Datasheet" " " (id 3) (at 20.32 -15.24 0)
        (effects (font (size 1.27 1.27) (thickness 0.15)) (justify left bottom) hide)
      )
      (property "MPN" "GRM188R60J476ME15D" (id 4) (at 20.32 -17.78 0)
        (effects (font (size 1.27 1.27) (thickness 0.15)) (justify left bottom) hide)
      )
      (property "Manufacturer" "Murata" (id 5) (at 20.32 -20.32 0)
        (effects (font (size 1.27 1.27) (thickness 0.15)) (justify left bottom) hide)
      )
      (property "License" "Apache-2.0" (id 6) (at 20.32 -22.86 0)
        (effects (font (size 1.27 1.27) (thickness 0.15)) (justify left bottom) hide)
      )
      (property "Author" "Antmicro" (id 7) (at 20.32 -25.4 0)
        (effects (font (size 1.27 1.27) (thickness 0.15)) (justify left bottom) hide)
      )
      (property "Val" "47u" (id 8) (at 20.32 -7.62 0)
        (effects (font (size 1.27 1.27) (thickness 0.15)) (justify left bottom))
      )
      (property "Voltage" "" (id 9) (at 20.32 -27.94 0)
        (effects (font (size 1.27 1.27)) (justify left bottom) hide)
      )
      (property "Dielectric" "" (id 10) (at 20.32 -30.48 0)
        (effects (font (size 1.27 1.27)) (justify left bottom) hide)
      )
      (property "ki_description" " " (id 11) (at 0 0 0)
        (effects (font (size 1.27 1.27)) hide)
      )
      (symbol "C_47u_0603_0_1"
        (polyline
          (pts
            (xy 2.032 -1.524)
            (xy 2.032 1.524)
          )
          (stroke (width 0.3048) (type default) (color 0 0 0 0))
          (fill (type none))
        )
        (polyline
          (pts
            (xy 3.048 -1.524)
            (xy 3.048 1.524)
          )
          (stroke (width 0.3302) (type default) (color 0 0 0 0))
          (fill (type none))
        )
      )
      (symbol "C_47u_0603_1_1"
        (pin passive line (at 0 0 0) (length 2.032)
          (name "~" (effects (font (size 1.27 1.27))))
          (number "1" (effects (font (size 1.27 1.27))))
        )
        (pin passive line (at 5.08 0 180) (length 2.032)
          (name "~" (effects (font (size 1.27 1.27))))
          (number "2" (effects (font (size 1.27 1.27))))
        )
      )
    )
	(symbol "sa800u-baseboard-hw:C_47u_0805" (pin_numbers hide) (pin_names hide) (in_bom yes) (on_board yes)
      (property "Reference" "C" (id 0) (at 20.32 -5.08 0)
        (effects (font (size 1.27 1.27) (thickness 0.15)) (justify left bottom))
      )
      (property "Value" "C_47u_0805" (id 1) (at 20.32 -10.16 0)
        (effects (font (size 1.27 1.27) (thickness 0.15)) (justify left bottom) hide)
      )
      (property "Footprint" "sa800u-baseboard-hw-footprints:C_0805_2012Metric" (id 2) (at 20.32 -12.7 0)
        (effects (font (size 1.27 1.27) (thickness 0.15)) (justify left bottom) hide)
      )
      (property "Datasheet" " " (id 3) (at 20.32 -15.24 0)
        (effects (font (size 1.27 1.27) (thickness 0.15)) (justify left bottom) hide)
      )
      (property "MPN" "C0805C476M9PACTU" (id 4) (at 20.32 -17.78 0)
        (effects (font (size 1.27 1.27) (thickness 0.15)) (justify left bottom) hide)
      )
      (property "Manufacturer" "KEMET" (id 5) (at 20.32 -20.32 0)
        (effects (font (size 1.27 1.27) (thickness 0.15)) (justify left bottom) hide)
      )
      (property "License" "Apache-2.0" (id 6) (at 20.32 -22.86 0)
        (effects (font (size 1.27 1.27) (thickness 0.15)) (justify left bottom) hide)
      )
      (property "Author" "Antmicro" (id 7) (at 20.32 -25.4 0)
        (effects (font (size 1.27 1.27) (thickness 0.15)) (justify left bottom) hide)
      )
      (property "Val" "47u" (id 8) (at 20.32 -7.62 0)
        (effects (font (size 1.27 1.27) (thickness 0.15)) (justify left bottom))
      )
      (property "Voltage" "" (id 9) (at 20.32 -27.94 0)
        (effects (font (size 1.27 1.27)) (justify left bottom) hide)
      )
      (property "Dielectric" "" (id 10) (at 20.32 -30.48 0)
        (effects (font (size 1.27 1.27)) (justify left bottom) hide)
      )
      (property "ki_description" " " (id 11) (at 0 0 0)
        (effects (font (size 1.27 1.27)) hide)
      )
      (symbol "C_47u_0805_0_1"
        (polyline
          (pts
            (xy 2.032 -1.524)
            (xy 2.032 1.524)
          )
          (stroke (width 0.3048) (type default) (color 0 0 0 0))
          (fill (type none))
        )
        (polyline
          (pts
            (xy 3.048 -1.524)
            (xy 3.048 1.524)
          )
          (stroke (width 0.3302) (type default) (color 0 0 0 0))
          (fill (type none))
        )
      )
      (symbol "C_47u_0805_1_1"
        (pin passive line (at 0 0 0) (length 2.032)
          (name "~" (effects (font (size 1.27 1.27))))
          (number "1" (effects (font (size 1.27 1.27))))
        )
        (pin passive line (at 5.08 0 180) (length 2.032)
          (name "~" (effects (font (size 1.27 1.27))))
          (number "2" (effects (font (size 1.27 1.27))))
        )
      )
    )
	(symbol "sa800u-baseboard-hw:C_47u_ELEC_100V" (pin_numbers hide) (pin_names hide) (in_bom yes) (on_board yes)
      (property "Reference" "C" (id 0) (at 13.97 0 0)
        (effects (font (size 1.27 1.27) (thickness 0.15)) (justify left bottom))
      )
      (property "Value" "C_47u_ELEC_100V" (id 1) (at 13.97 -5.08 0)
        (effects (font (size 1.27 1.27) (thickness 0.15)) (justify left bottom) hide)
      )
      (property "Footprint" "antmicro-footprints:C_Elec_10x10.5mm" (id 2) (at 13.97 -7.62 0)
        (effects (font (size 1.27 1.27) (thickness 0.15)) (justify left bottom) hide)
      )
      (property "Datasheet" "https://industrial.panasonic.com/cdbs/www-data/pdf/RDE0000/ABA0000C1151.pdf" (id 3) (at 13.97 -10.16 0)
        (effects (font (size 1.27 1.27) (thickness 0.15)) (justify left bottom) hide)
      )
      (property "MPN" "EEEHA2A470UP" (id 4) (at 13.97 -12.7 0)
        (effects (font (size 1.27 1.27) (thickness 0.15)) (justify left bottom) hide)
      )
      (property "Manufacturer" "Panasonic" (id 5) (at 13.97 -15.24 0)
        (effects (font (size 1.27 1.27) (thickness 0.15)) (justify left bottom) hide)
      )
      (property "License" "Apache-2.0" (id 6) (at 13.97 -17.78 0)
        (effects (font (size 1.27 1.27) (thickness 0.15)) (justify left bottom) hide)
      )
      (property "Author" "Antmicro" (id 7) (at 13.97 -20.32 0)
        (effects (font (size 1.27 1.27) (thickness 0.15)) (justify left bottom) hide)
      )
      (property "Val" "47u/100V" (id 8) (at 13.97 -2.54 0)
        (effects (font (size 1.27 1.27) (thickness 0.15)) (justify left bottom))
      )
      (property "Voltage" "" (id 9) (at 13.97 -22.86 0)
        (effects (font (size 1.27 1.27)) (justify left bottom) hide)
      )
      (property "Dielectric" "" (id 10) (at 13.97 -25.4 0)
        (effects (font (size 1.27 1.27)) (justify left bottom) hide)
      )
      (property "ki_description" " " (id 11) (at 0 0 0)
        (effects (font (size 1.27 1.27)) hide)
      )
      (symbol "C_47u_ELEC_100V_0_1"
        (rectangle (start -1.524 -2.921) (end 1.524 -3.302)
          (stroke (width 0) (type default) (color 0 0 0 0))
          (fill (type outline))
        )
        (rectangle (start -1.524 -1.905) (end 1.524 -2.286)
          (stroke (width 0) (type default) (color 0 0 0 0))
          (fill (type none))
        )
        (polyline
          (pts
            (xy -1.27 -0.9652)
            (xy -0.762 -0.9652)
          )
          (stroke (width 0) (type default) (color 0 0 0 0))
          (fill (type none))
        )
        (polyline
          (pts
            (xy -1.016 -1.2192)
            (xy -1.016 -0.7112)
          )
          (stroke (width 0) (type default) (color 0 0 0 0))
          (fill (type none))
        )
      )
      (symbol "C_47u_ELEC_100V_1_1"
        (pin passive line (at 0 0 270) (length 1.8542)
          (name "~" (effects (font (size 1.27 1.27))))
          (number "1" (effects (font (size 1.27 1.27))))
        )
        (pin passive line (at 0 -5.08 90) (length 1.8542)
          (name "~" (effects (font (size 1.27 1.27))))
          (number "2" (effects (font (size 1.27 1.27))))
        )
      )
    )
	(symbol "sa800u-baseboard-hw:C_4u7_0402" (pin_numbers hide) (pin_names hide) (in_bom yes) (on_board yes)
      (property "Reference" "C" (id 0) (at 20.32 -5.08 0)
        (effects (font (size 1.27 1.27) (thickness 0.15)) (justify left bottom))
      )
      (property "Value" "C_4u7_0402" (id 1) (at 20.32 -10.16 0)
        (effects (font (size 1.27 1.27) (thickness 0.15)) (justify left bottom) hide)
      )
      (property "Footprint" "sa800u-baseboard-hw-footprints:C_0402_1005Metric" (id 2) (at 20.32 -12.7 0)
        (effects (font (size 1.27 1.27) (thickness 0.15)) (justify left bottom) hide)
      )
      (property "Datasheet" " " (id 3) (at 20.32 -15.24 0)
        (effects (font (size 1.27 1.27) (thickness 0.15)) (justify left bottom) hide)
      )
      (property "MPN" "GRM155R61A475MEAAD" (id 4) (at 20.32 -17.78 0)
        (effects (font (size 1.27 1.27) (thickness 0.15)) (justify left bottom) hide)
      )
      (property "Manufacturer" "Murata" (id 5) (at 20.32 -20.32 0)
        (effects (font (size 1.27 1.27) (thickness 0.15)) (justify left bottom) hide)
      )
      (property "License" "Apache-2.0" (id 6) (at 20.32 -22.86 0)
        (effects (font (size 1.27 1.27) (thickness 0.15)) (justify left bottom) hide)
      )
      (property "Author" "Antmicro" (id 7) (at 20.32 -25.4 0)
        (effects (font (size 1.27 1.27) (thickness 0.15)) (justify left bottom) hide)
      )
      (property "Val" "4u7" (id 8) (at 20.32 -7.62 0)
        (effects (font (size 1.27 1.27) (thickness 0.15)) (justify left bottom))
      )
      (property "Voltage" "" (id 9) (at 20.32 -27.94 0)
        (effects (font (size 1.27 1.27)) (justify left bottom) hide)
      )
      (property "Dielectric" "" (id 10) (at 20.32 -30.48 0)
        (effects (font (size 1.27 1.27)) (justify left bottom) hide)
      )
      (property "ki_description" " " (id 11) (at 0 0 0)
        (effects (font (size 1.27 1.27)) hide)
      )
      (symbol "C_4u7_0402_0_1"
        (polyline
          (pts
            (xy 2.032 -1.524)
            (xy 2.032 1.524)
          )
          (stroke (width 0.3048) (type default) (color 0 0 0 0))
          (fill (type none))
        )
        (polyline
          (pts
            (xy 3.048 -1.524)
            (xy 3.048 1.524)
          )
          (stroke (width 0.3302) (type default) (color 0 0 0 0))
          (fill (type none))
        )
      )
      (symbol "C_4u7_0402_1_1"
        (pin passive line (at 0 0 0) (length 2.032)
          (name "~" (effects (font (size 1.27 1.27))))
          (number "1" (effects (font (size 1.27 1.27))))
        )
        (pin passive line (at 5.08 0 180) (length 2.032)
          (name "~" (effects (font (size 1.27 1.27))))
          (number "2" (effects (font (size 1.27 1.27))))
        )
      )
    )
	(symbol "sa800u-baseboard-hw:C_4u7_0603" (pin_numbers hide) (pin_names hide) (in_bom yes) (on_board yes)
      (property "Reference" "C" (id 0) (at 20.32 -5.08 0)
        (effects (font (size 1.27 1.27) (thickness 0.15)) (justify left bottom))
      )
      (property "Value" "C_4u7_0603" (id 1) (at 20.32 -10.16 0)
        (effects (font (size 1.27 1.27) (thickness 0.15)) (justify left bottom) hide)
      )
      (property "Footprint" "sa800u-baseboard-hw-footprints:C_0603_1608Metric" (id 2) (at 20.32 -12.7 0)
        (effects (font (size 1.27 1.27) (thickness 0.15)) (justify left bottom) hide)
      )
      (property "Datasheet" " " (id 3) (at 20.32 -15.24 0)
        (effects (font (size 1.27 1.27) (thickness 0.15)) (justify left bottom) hide)
      )
      (property "MPN" "C1608X5R1V475M080AC" (id 4) (at 20.32 -17.78 0)
        (effects (font (size 1.27 1.27) (thickness 0.15)) (justify left bottom) hide)
      )
      (property "Manufacturer" "TDK" (id 5) (at 20.32 -20.32 0)
        (effects (font (size 1.27 1.27) (thickness 0.15)) (justify left bottom) hide)
      )
      (property "License" "Apache-2.0" (id 6) (at 20.32 -22.86 0)
        (effects (font (size 1.27 1.27) (thickness 0.15)) (justify left bottom) hide)
      )
      (property "Author" "Antmicro" (id 7) (at 20.32 -25.4 0)
        (effects (font (size 1.27 1.27) (thickness 0.15)) (justify left bottom) hide)
      )
      (property "Val" "4u7" (id 8) (at 20.32 -7.62 0)
        (effects (font (size 1.27 1.27) (thickness 0.15)) (justify left bottom))
      )
      (property "Voltage" "" (id 9) (at 20.32 -27.94 0)
        (effects (font (size 1.27 1.27)) (justify left bottom) hide)
      )
      (property "Dielectric" "" (id 10) (at 20.32 -30.48 0)
        (effects (font (size 1.27 1.27)) (justify left bottom) hide)
      )
      (property "ki_description" " " (id 11) (at 0 0 0)
        (effects (font (size 1.27 1.27)) hide)
      )
      (symbol "C_4u7_0603_0_1"
        (polyline
          (pts
            (xy 2.032 -1.524)
            (xy 2.032 1.524)
          )
          (stroke (width 0.3048) (type default) (color 0 0 0 0))
          (fill (type none))
        )
        (polyline
          (pts
            (xy 3.048 -1.524)
            (xy 3.048 1.524)
          )
          (stroke (width 0.3302) (type default) (color 0 0 0 0))
          (fill (type none))
        )
      )
      (symbol "C_4u7_0603_1_1"
        (pin passive line (at 0 0 0) (length 2.032)
          (name "~" (effects (font (size 1.27 1.27))))
          (number "1" (effects (font (size 1.27 1.27))))
        )
        (pin passive line (at 5.08 0 180) (length 2.032)
          (name "~" (effects (font (size 1.27 1.27))))
          (number "2" (effects (font (size 1.27 1.27))))
        )
      )
    )
	(symbol "sa800u-baseboard-hw:C_4u7_0805" (pin_numbers hide) (pin_names hide) (in_bom yes) (on_board yes)
      (property "Reference" "C" (id 0) (at 20.32 -5.08 0)
        (effects (font (size 1.27 1.27) (thickness 0.15)) (justify left bottom))
      )
      (property "Value" "C_4u7_0805" (id 1) (at 20.32 -10.16 0)
        (effects (font (size 1.27 1.27) (thickness 0.15)) (justify left bottom) hide)
      )
      (property "Footprint" "sa800u-baseboard-hw-footprints:C_0805_2012Metric" (id 2) (at 20.32 -12.7 0)
        (effects (font (size 1.27 1.27) (thickness 0.15)) (justify left bottom) hide)
      )
      (property "Datasheet" " " (id 3) (at 20.32 -15.24 0)
        (effects (font (size 1.27 1.27) (thickness 0.15)) (justify left bottom) hide)
      )
      (property "MPN" "0805X475K250CT" (id 4) (at 20.32 -17.78 0)
        (effects (font (size 1.27 1.27) (thickness 0.15)) (justify left bottom) hide)
      )
      (property "Manufacturer" "Walsin" (id 5) (at 20.32 -20.32 0)
        (effects (font (size 1.27 1.27) (thickness 0.15)) (justify left bottom) hide)
      )
      (property "License" "Apache-2.0" (id 6) (at 20.32 -22.86 0)
        (effects (font (size 1.27 1.27) (thickness 0.15)) (justify left bottom) hide)
      )
      (property "Author" "Antmicro" (id 7) (at 20.32 -25.4 0)
        (effects (font (size 1.27 1.27) (thickness 0.15)) (justify left bottom) hide)
      )
      (property "Val" "4u7" (id 8) (at 20.32 -7.62 0)
        (effects (font (size 1.27 1.27) (thickness 0.15)) (justify left bottom))
      )
      (property "Voltage" "" (id 9) (at 20.32 -27.94 0)
        (effects (font (size 1.27 1.27)) (justify left bottom) hide)
      )
      (property "Dielectric" "" (id 10) (at 20.32 -30.48 0)
        (effects (font (size 1.27 1.27)) (justify left bottom) hide)
      )
      (property "ki_description" " " (id 11) (at 0 0 0)
        (effects (font (size 1.27 1.27)) hide)
      )
      (symbol "C_4u7_0805_0_1"
        (polyline
          (pts
            (xy 2.032 -1.524)
            (xy 2.032 1.524)
          )
          (stroke (width 0.3048) (type default) (color 0 0 0 0))
          (fill (type none))
        )
        (polyline
          (pts
            (xy 3.048 -1.524)
            (xy 3.048 1.524)
          )
          (stroke (width 0.3302) (type default) (color 0 0 0 0))
          (fill (type none))
        )
      )
      (symbol "C_4u7_0805_1_1"
        (pin passive line (at 0 0 0) (length 2.032)
          (name "~" (effects (font (size 1.27 1.27))))
          (number "1" (effects (font (size 1.27 1.27))))
        )
        (pin passive line (at 5.08 0 180) (length 2.032)
          (name "~" (effects (font (size 1.27 1.27))))
          (number "2" (effects (font (size 1.27 1.27))))
        )
      )
    )
	(symbol "sa800u-baseboard-hw:Conn_FFC_WE_68715014522_TWO-SIDES" (in_bom yes) (on_board yes)
      (property "Reference" "J" (id 0) (at 19.05 -5.08 0)
        (effects (font (size 1.27 1.27) (thickness 0.15)) (justify left bottom))
      )
      (property "Value" "Conn_FFC_WE_68715014522_TWO-SIDES" (id 1) (at 19.05 -7.62 0)
        (effects (font (size 1.27 1.27) (thickness 0.15)) (justify left bottom))
      )
      (property "Footprint" "sa800u-baseboard-hw-footprints:Conn_FFC_WE_68715014x22_ALT" (id 2) (at 19.05 -10.16 0)
        (effects (font (size 1.27 1.27) (thickness 0.15)) (justify left bottom) hide)
      )
      (property "Datasheet" "https://www.we-online.com/components/products/datasheet/68715014522.pdf" (id 3) (at 19.05 -12.7 0)
        (effects (font (size 1.27 1.27) (thickness 0.15)) (justify left bottom) hide)
      )
      (property "MPN" "68715014522" (id 4) (at 19.05 -15.24 0)
        (effects (font (size 1.27 1.27) (thickness 0.15)) (justify left bottom) hide)
      )
      (property "Manufacturer" "Würth Elektronik" (id 5) (at 19.05 -17.78 0)
        (effects (font (size 1.27 1.27) (thickness 0.15)) (justify left bottom) hide)
      )
      (property "Author" "Antmicro" (id 6) (at 19.05 -20.32 0)
        (effects (font (size 1.27 1.27) (thickness 0.15)) (justify left bottom) hide)
      )
      (property "License" "Apache-2.0" (id 7) (at 19.05 -22.86 0)
        (effects (font (size 1.27 1.27) (thickness 0.15)) (justify left bottom) hide)
      )
      (property "ki_description" "BottomContact" (id 8) (at 0 0 0)
        (effects (font (size 1.27 1.27)) hide)
      )
      (symbol "Conn_FFC_WE_68715014522_TWO-SIDES_1_1"
        (rectangle (start 3.81 -124.333) (end 5.08 -124.587)
          (stroke (width 0.254) (type default) (color 0 0 0 0))
          (fill (type background))
        )
        (rectangle (start 3.81 -121.793) (end 5.08 -122.047)
          (stroke (width 0.254) (type default) (color 0 0 0 0))
          (fill (type background))
        )
        (rectangle (start 3.81 -119.253) (end 5.08 -119.507)
          (stroke (width 0.254) (type default) (color 0 0 0 0))
          (fill (type background))
        )
        (rectangle (start 3.81 -116.713) (end 5.08 -116.967)
          (stroke (width 0.254) (type default) (color 0 0 0 0))
          (fill (type background))
        )
        (rectangle (start 3.81 -114.173) (end 5.08 -114.427)
          (stroke (width 0.254) (type default) (color 0 0 0 0))
          (fill (type background))
        )
        (rectangle (start 3.81 -111.633) (end 5.08 -111.887)
          (stroke (width 0.254) (type default) (color 0 0 0 0))
          (fill (type background))
        )
        (rectangle (start 3.81 -109.093) (end 5.08 -109.347)
          (stroke (width 0.254) (type default) (color 0 0 0 0))
          (fill (type background))
        )
        (rectangle (start 3.81 -106.553) (end 5.08 -106.807)
          (stroke (width 0.254) (type default) (color 0 0 0 0))
          (fill (type background))
        )
        (rectangle (start 3.81 -104.013) (end 5.08 -104.267)
          (stroke (width 0.254) (type default) (color 0 0 0 0))
          (fill (type background))
        )
        (rectangle (start 3.81 -101.473) (end 5.08 -101.727)
          (stroke (width 0.254) (type default) (color 0 0 0 0))
          (fill (type background))
        )
        (rectangle (start 3.81 -98.933) (end 5.08 -99.187)
          (stroke (width 0.254) (type default) (color 0 0 0 0))
          (fill (type background))
        )
        (rectangle (start 3.81 -96.393) (end 5.08 -96.647)
          (stroke (width 0.254) (type default) (color 0 0 0 0))
          (fill (type background))
        )
        (rectangle (start 3.81 -93.853) (end 5.08 -94.107)
          (stroke (width 0.254) (type default) (color 0 0 0 0))
          (fill (type background))
        )
        (rectangle (start 3.81 -91.313) (end 5.08 -91.567)
          (stroke (width 0.254) (type default) (color 0 0 0 0))
          (fill (type background))
        )
        (rectangle (start 3.81 -88.773) (end 5.08 -89.027)
          (stroke (width 0.254) (type default) (color 0 0 0 0))
          (fill (type background))
        )
        (rectangle (start 3.81 -86.233) (end 5.08 -86.487)
          (stroke (width 0.254) (type default) (color 0 0 0 0))
          (fill (type background))
        )
        (rectangle (start 3.81 -83.693) (end 5.08 -83.947)
          (stroke (width 0.254) (type default) (color 0 0 0 0))
          (fill (type background))
        )
        (rectangle (start 3.81 -81.153) (end 5.08 -81.407)
          (stroke (width 0.254) (type default) (color 0 0 0 0))
          (fill (type background))
        )
        (rectangle (start 3.81 -78.613) (end 5.08 -78.867)
          (stroke (width 0.254) (type default) (color 0 0 0 0))
          (fill (type background))
        )
        (rectangle (start 3.81 -76.073) (end 5.08 -76.327)
          (stroke (width 0.254) (type default) (color 0 0 0 0))
          (fill (type background))
        )
        (rectangle (start 3.81 -73.533) (end 5.08 -73.787)
          (stroke (width 0.254) (type default) (color 0 0 0 0))
          (fill (type background))
        )
        (rectangle (start 3.81 -70.993) (end 5.08 -71.247)
          (stroke (width 0.254) (type default) (color 0 0 0 0))
          (fill (type background))
        )
        (rectangle (start 3.81 -68.453) (end 5.08 -68.707)
          (stroke (width 0.254) (type default) (color 0 0 0 0))
          (fill (type background))
        )
        (rectangle (start 3.81 -65.913) (end 5.08 -66.167)
          (stroke (width 0.254) (type default) (color 0 0 0 0))
          (fill (type background))
        )
        (rectangle (start 3.81 -63.373) (end 5.08 -63.627)
          (stroke (width 0.254) (type default) (color 0 0 0 0))
          (fill (type background))
        )
        (rectangle (start 3.81 -60.833) (end 5.08 -61.087)
          (stroke (width 0.254) (type default) (color 0 0 0 0))
          (fill (type background))
        )
        (rectangle (start 3.81 -58.293) (end 5.08 -58.547)
          (stroke (width 0.254) (type default) (color 0 0 0 0))
          (fill (type background))
        )
        (rectangle (start 3.81 -55.753) (end 5.08 -56.007)
          (stroke (width 0.254) (type default) (color 0 0 0 0))
          (fill (type background))
        )
        (rectangle (start 3.81 -53.213) (end 5.08 -53.467)
          (stroke (width 0.254) (type default) (color 0 0 0 0))
          (fill (type background))
        )
        (rectangle (start 3.81 -50.673) (end 5.08 -50.927)
          (stroke (width 0.254) (type default) (color 0 0 0 0))
          (fill (type background))
        )
        (rectangle (start 3.81 -48.133) (end 5.08 -48.387)
          (stroke (width 0.254) (type default) (color 0 0 0 0))
          (fill (type background))
        )
        (rectangle (start 3.81 -45.593) (end 5.08 -45.847)
          (stroke (width 0.254) (type default) (color 0 0 0 0))
          (fill (type background))
        )
        (rectangle (start 3.81 -43.053) (end 5.08 -43.307)
          (stroke (width 0.254) (type default) (color 0 0 0 0))
          (fill (type background))
        )
        (rectangle (start 3.81 -40.513) (end 5.08 -40.767)
          (stroke (width 0.254) (type default) (color 0 0 0 0))
          (fill (type background))
        )
        (rectangle (start 3.81 -37.973) (end 5.08 -38.227)
          (stroke (width 0.254) (type default) (color 0 0 0 0))
          (fill (type background))
        )
        (rectangle (start 3.81 -35.433) (end 5.08 -35.687)
          (stroke (width 0.254) (type default) (color 0 0 0 0))
          (fill (type background))
        )
        (rectangle (start 3.81 -32.893) (end 5.08 -33.147)
          (stroke (width 0.254) (type default) (color 0 0 0 0))
          (fill (type background))
        )
        (rectangle (start 3.81 -30.353) (end 5.08 -30.607)
          (stroke (width 0.254) (type default) (color 0 0 0 0))
          (fill (type background))
        )
        (rectangle (start 3.81 -27.813) (end 5.08 -28.067)
          (stroke (width 0.254) (type default) (color 0 0 0 0))
          (fill (type background))
        )
        (rectangle (start 3.81 -25.273) (end 5.08 -25.527)
          (stroke (width 0.254) (type default) (color 0 0 0 0))
          (fill (type background))
        )
        (rectangle (start 3.81 -22.733) (end 5.08 -22.987)
          (stroke (width 0.254) (type default) (color 0 0 0 0))
          (fill (type background))
        )
        (rectangle (start 3.81 -20.193) (end 5.08 -20.447)
          (stroke (width 0.254) (type default) (color 0 0 0 0))
          (fill (type background))
        )
        (rectangle (start 3.81 -17.653) (end 5.08 -17.907)
          (stroke (width 0.254) (type default) (color 0 0 0 0))
          (fill (type background))
        )
        (rectangle (start 3.81 -15.113) (end 5.08 -15.367)
          (stroke (width 0.254) (type default) (color 0 0 0 0))
          (fill (type background))
        )
        (rectangle (start 3.81 -12.573) (end 5.08 -12.827)
          (stroke (width 0.254) (type default) (color 0 0 0 0))
          (fill (type background))
        )
        (rectangle (start 3.81 -10.033) (end 5.08 -10.287)
          (stroke (width 0.254) (type default) (color 0 0 0 0))
          (fill (type background))
        )
        (rectangle (start 3.81 -7.493) (end 5.08 -7.747)
          (stroke (width 0.254) (type default) (color 0 0 0 0))
          (fill (type background))
        )
        (rectangle (start 3.81 -4.953) (end 5.08 -5.207)
          (stroke (width 0.254) (type default) (color 0 0 0 0))
          (fill (type background))
        )
        (rectangle (start 3.81 -2.413) (end 5.08 -2.667)
          (stroke (width 0.254) (type default) (color 0 0 0 0))
          (fill (type background))
        )
        (rectangle (start 3.81 0.127) (end 5.08 -0.127)
          (stroke (width 0.254) (type default) (color 0 0 0 0))
          (fill (type background))
        )
        (rectangle (start 3.81 1.27) (end 7.62 -132.08)
          (stroke (width 0.254) (type default) (color 0 0 0 0))
          (fill (type background))
        )
        (pin passive line (at 0 0 0) (length 3.81)
          (name "~" (effects (font (size 1.27 1.27))))
          (number "1" (effects (font (size 1.27 1.27))))
        )
        (pin passive line (at 0 -22.86 0) (length 3.81)
          (name "~" (effects (font (size 1.27 1.27))))
          (number "10" (effects (font (size 1.27 1.27))))
        )
        (pin passive line (at 0 -25.4 0) (length 3.81)
          (name "~" (effects (font (size 1.27 1.27))))
          (number "11" (effects (font (size 1.27 1.27))))
        )
        (pin passive line (at 0 -27.94 0) (length 3.81)
          (name "~" (effects (font (size 1.27 1.27))))
          (number "12" (effects (font (size 1.27 1.27))))
        )
        (pin passive line (at 0 -30.48 0) (length 3.81)
          (name "~" (effects (font (size 1.27 1.27))))
          (number "13" (effects (font (size 1.27 1.27))))
        )
        (pin passive line (at 0 -33.02 0) (length 3.81)
          (name "~" (effects (font (size 1.27 1.27))))
          (number "14" (effects (font (size 1.27 1.27))))
        )
        (pin passive line (at 0 -35.56 0) (length 3.81)
          (name "~" (effects (font (size 1.27 1.27))))
          (number "15" (effects (font (size 1.27 1.27))))
        )
        (pin passive line (at 0 -38.1 0) (length 3.81)
          (name "~" (effects (font (size 1.27 1.27))))
          (number "16" (effects (font (size 1.27 1.27))))
        )
        (pin passive line (at 0 -40.64 0) (length 3.81)
          (name "~" (effects (font (size 1.27 1.27))))
          (number "17" (effects (font (size 1.27 1.27))))
        )
        (pin passive line (at 0 -43.18 0) (length 3.81)
          (name "~" (effects (font (size 1.27 1.27))))
          (number "18" (effects (font (size 1.27 1.27))))
        )
        (pin passive line (at 0 -45.72 0) (length 3.81)
          (name "~" (effects (font (size 1.27 1.27))))
          (number "19" (effects (font (size 1.27 1.27))))
        )
        (pin passive line (at 0 -2.54 0) (length 3.81)
          (name "~" (effects (font (size 1.27 1.27))))
          (number "2" (effects (font (size 1.27 1.27))))
        )
        (pin passive line (at 0 -48.26 0) (length 3.81)
          (name "~" (effects (font (size 1.27 1.27))))
          (number "20" (effects (font (size 1.27 1.27))))
        )
        (pin passive line (at 0 -50.8 0) (length 3.81)
          (name "~" (effects (font (size 1.27 1.27))))
          (number "21" (effects (font (size 1.27 1.27))))
        )
        (pin passive line (at 0 -53.34 0) (length 3.81)
          (name "~" (effects (font (size 1.27 1.27))))
          (number "22" (effects (font (size 1.27 1.27))))
        )
        (pin passive line (at 0 -55.88 0) (length 3.81)
          (name "~" (effects (font (size 1.27 1.27))))
          (number "23" (effects (font (size 1.27 1.27))))
        )
        (pin passive line (at 0 -58.42 0) (length 3.81)
          (name "~" (effects (font (size 1.27 1.27))))
          (number "24" (effects (font (size 1.27 1.27))))
        )
        (pin passive line (at 0 -60.96 0) (length 3.81)
          (name "~" (effects (font (size 1.27 1.27))))
          (number "25" (effects (font (size 1.27 1.27))))
        )
        (pin passive line (at 0 -63.5 0) (length 3.81)
          (name "~" (effects (font (size 1.27 1.27))))
          (number "26" (effects (font (size 1.27 1.27))))
        )
        (pin passive line (at 0 -66.04 0) (length 3.81)
          (name "~" (effects (font (size 1.27 1.27))))
          (number "27" (effects (font (size 1.27 1.27))))
        )
        (pin passive line (at 0 -68.58 0) (length 3.81)
          (name "~" (effects (font (size 1.27 1.27))))
          (number "28" (effects (font (size 1.27 1.27))))
        )
        (pin passive line (at 0 -71.12 0) (length 3.81)
          (name "~" (effects (font (size 1.27 1.27))))
          (number "29" (effects (font (size 1.27 1.27))))
        )
        (pin passive line (at 0 -5.08 0) (length 3.81)
          (name "~" (effects (font (size 1.27 1.27))))
          (number "3" (effects (font (size 1.27 1.27))))
        )
        (pin passive line (at 0 -73.66 0) (length 3.81)
          (name "~" (effects (font (size 1.27 1.27))))
          (number "30" (effects (font (size 1.27 1.27))))
        )
        (pin passive line (at 0 -76.2 0) (length 3.81)
          (name "~" (effects (font (size 1.27 1.27))))
          (number "31" (effects (font (size 1.27 1.27))))
        )
        (pin passive line (at 0 -78.74 0) (length 3.81)
          (name "~" (effects (font (size 1.27 1.27))))
          (number "32" (effects (font (size 1.27 1.27))))
        )
        (pin passive line (at 0 -81.28 0) (length 3.81)
          (name "~" (effects (font (size 1.27 1.27))))
          (number "33" (effects (font (size 1.27 1.27))))
        )
        (pin passive line (at 0 -83.82 0) (length 3.81)
          (name "~" (effects (font (size 1.27 1.27))))
          (number "34" (effects (font (size 1.27 1.27))))
        )
        (pin passive line (at 0 -86.36 0) (length 3.81)
          (name "~" (effects (font (size 1.27 1.27))))
          (number "35" (effects (font (size 1.27 1.27))))
        )
        (pin passive line (at 0 -88.9 0) (length 3.81)
          (name "~" (effects (font (size 1.27 1.27))))
          (number "36" (effects (font (size 1.27 1.27))))
        )
        (pin passive line (at 0 -91.44 0) (length 3.81)
          (name "~" (effects (font (size 1.27 1.27))))
          (number "37" (effects (font (size 1.27 1.27))))
        )
        (pin passive line (at 0 -93.98 0) (length 3.81)
          (name "~" (effects (font (size 1.27 1.27))))
          (number "38" (effects (font (size 1.27 1.27))))
        )
        (pin passive line (at 0 -96.52 0) (length 3.81)
          (name "~" (effects (font (size 1.27 1.27))))
          (number "39" (effects (font (size 1.27 1.27))))
        )
        (pin passive line (at 0 -7.62 0) (length 3.81)
          (name "~" (effects (font (size 1.27 1.27))))
          (number "4" (effects (font (size 1.27 1.27))))
        )
        (pin passive line (at 0 -99.06 0) (length 3.81)
          (name "~" (effects (font (size 1.27 1.27))))
          (number "40" (effects (font (size 1.27 1.27))))
        )
        (pin passive line (at 0 -101.6 0) (length 3.81)
          (name "~" (effects (font (size 1.27 1.27))))
          (number "41" (effects (font (size 1.27 1.27))))
        )
        (pin passive line (at 0 -104.14 0) (length 3.81)
          (name "~" (effects (font (size 1.27 1.27))))
          (number "42" (effects (font (size 1.27 1.27))))
        )
        (pin passive line (at 0 -106.68 0) (length 3.81)
          (name "~" (effects (font (size 1.27 1.27))))
          (number "43" (effects (font (size 1.27 1.27))))
        )
        (pin passive line (at 0 -109.22 0) (length 3.81)
          (name "~" (effects (font (size 1.27 1.27))))
          (number "44" (effects (font (size 1.27 1.27))))
        )
        (pin passive line (at 0 -111.76 0) (length 3.81)
          (name "~" (effects (font (size 1.27 1.27))))
          (number "45" (effects (font (size 1.27 1.27))))
        )
        (pin passive line (at 0 -114.3 0) (length 3.81)
          (name "~" (effects (font (size 1.27 1.27))))
          (number "46" (effects (font (size 1.27 1.27))))
        )
        (pin passive line (at 0 -116.84 0) (length 3.81)
          (name "~" (effects (font (size 1.27 1.27))))
          (number "47" (effects (font (size 1.27 1.27))))
        )
        (pin passive line (at 0 -119.38 0) (length 3.81)
          (name "~" (effects (font (size 1.27 1.27))))
          (number "48" (effects (font (size 1.27 1.27))))
        )
        (pin passive line (at 0 -121.92 0) (length 3.81)
          (name "~" (effects (font (size 1.27 1.27))))
          (number "49" (effects (font (size 1.27 1.27))))
        )
        (pin passive line (at 0 -10.16 0) (length 3.81)
          (name "~" (effects (font (size 1.27 1.27))))
          (number "5" (effects (font (size 1.27 1.27))))
        )
        (pin passive line (at 0 -124.46 0) (length 3.81)
          (name "~" (effects (font (size 1.27 1.27))))
          (number "50" (effects (font (size 1.27 1.27))))
        )
        (pin passive line (at 0 -12.7 0) (length 3.81)
          (name "~" (effects (font (size 1.27 1.27))))
          (number "6" (effects (font (size 1.27 1.27))))
        )
        (pin passive line (at 0 -15.24 0) (length 3.81)
          (name "~" (effects (font (size 1.27 1.27))))
          (number "7" (effects (font (size 1.27 1.27))))
        )
        (pin passive line (at 0 -17.78 0) (length 3.81)
          (name "~" (effects (font (size 1.27 1.27))))
          (number "8" (effects (font (size 1.27 1.27))))
        )
        (pin passive line (at 0 -20.32 0) (length 3.81)
          (name "~" (effects (font (size 1.27 1.27))))
          (number "9" (effects (font (size 1.27 1.27))))
        )
        (pin passive line (at 0 -127 0) (length 3.81)
          (name "SH" (effects (font (size 1.27 1.27))))
          (number "SH1" (effects (font (size 1.27 1.27))))
        )
        (pin passive line (at 0 -129.54 0) (length 3.81)
          (name "SH" (effects (font (size 1.27 1.27))))
          (number "SH2" (effects (font (size 1.27 1.27))))
        )
      )
    )
	(symbol "sa800u-baseboard-hw:Conn_Molex_NanoFit_1053131202" (in_bom yes) (on_board yes)
      (property "Reference" "J" (id 0) (at 20.32 -5.08 0)
        (effects (font (size 1.27 1.27) (thickness 0.15)) (justify left bottom))
      )
      (property "Value" "Conn_Molex_NanoFit_1053131202" (id 1) (at 20.32 -7.62 0)
        (effects (font (size 1.27 1.27) (thickness 0.15)) (justify left bottom))
      )
      (property "Footprint" "antmicro-footprints:Conn_Molex_NanoFit_1053131202" (id 2) (at 20.32 -10.16 0)
        (effects (font (size 1.27 1.27) (thickness 0.15)) (justify left bottom) hide)
      )
      (property "Datasheet" "https://www.molex.com/molex/products/part-detail/pcb_headers/1053131202" (id 3) (at 20.32 -12.7 0)
        (effects (font (size 1.27 1.27) (thickness 0.15)) (justify left bottom) hide)
      )
      (property "Manufacturer" "Molex" (id 4) (at 20.32 -15.24 0)
        (effects (font (size 1.27 1.27) (thickness 0.15)) (justify left bottom) hide)
      )
      (property "MPN" "1053131202" (id 5) (at 20.32 -17.78 0)
        (effects (font (size 1.27 1.27) (thickness 0.15)) (justify left bottom) hide)
      )
      (property "Author" "Antmicro" (id 6) (at 20.32 -20.32 0)
        (effects (font (size 1.27 1.27) (thickness 0.15)) (justify left bottom) hide)
      )
      (property "License" "Apache-2.0" (id 7) (at 20.32 -22.86 0)
        (effects (font (size 1.27 1.27) (thickness 0.15)) (justify left bottom) hide)
      )
      (property "ki_description" "Nano-Fit Right-Angle and Vertiacal Header, through hole, right angle, 2 pin, 2.50mm" (id 8) (at 0 0 0)
        (effects (font (size 1.27 1.27)) hide)
      )
      (symbol "Conn_Molex_NanoFit_1053131202_1_1"
        (rectangle (start -5.08 1.905) (end -2.54 -4.445)
          (stroke (width 0.254) (type default) (color 0 0 0 0))
          (fill (type background))
        )
        (rectangle (start -4.445 -1.905) (end -3.175 -3.175)
          (stroke (width 0.254) (type default) (color 0 0 0 0))
          (fill (type background))
        )
        (rectangle (start -4.445 0.635) (end -3.175 -0.635)
          (stroke (width 0.254) (type default) (color 0 0 0 0))
          (fill (type background))
        )
        (pin input line (at 0 0 180) (length 2.54)
          (name "~" (effects (font (size 1.27 1.27))))
          (number "1" (effects (font (size 1.27 1.27))))
        )
        (pin input line (at 0 -2.54 180) (length 2.54)
          (name "~" (effects (font (size 1.27 1.27))))
          (number "2" (effects (font (size 1.27 1.27))))
        )
      )
    )
	(symbol "sa800u-baseboard-hw:DM3AT-SF-PEJM5" (in_bom yes) (on_board yes)
      (property "Reference" "J" (id 0) (at 57.15 0 0)
        (effects (font (size 1.27 1.27) (thickness 0.15)) (justify left bottom))
      )
      (property "Value" "DM3AT-SF-PEJM5" (id 1) (at 57.15 -2.54 0)
        (effects (font (size 1.27 1.27) (thickness 0.15)) (justify left bottom))
      )
      (property "Footprint" "sa800u-baseboard-hw-footprints:MicroSD_DM3AT-SF-PEJM5" (id 2) (at 57.15 -5.08 0)
        (effects (font (size 1.27 1.27) (thickness 0.15)) (justify left bottom) hide)
      )
      (property "Datasheet" "https://www.hirose.com/en/product/document?clcode=CL0609-0031-0-00&productname=DM3AT-SF-PEJM5&series=DM3&documenttype=2DDrawing&lang=en&documentid=0000947170" (id 3) (at 57.15 -7.62 0)
        (effects (font (size 1.27 1.27) (thickness 0.15)) (justify left bottom) hide)
      )
      (property "Manufacturer" "Hirose" (id 4) (at 57.15 -10.16 0)
        (effects (font (size 1.27 1.27) (thickness 0.15)) (justify left bottom) hide)
      )
      (property "MPN" "DM3AT-SF-PEJM5" (id 5) (at 57.15 -12.7 0)
        (effects (font (size 1.27 1.27) (thickness 0.15)) (justify left bottom) hide)
      )
      (property "Author" "Antmicro" (id 6) (at 57.15 -15.24 0)
        (effects (font (size 1.27 1.27) (thickness 0.15)) (justify left bottom) hide)
      )
      (property "License" "Apache-2.0" (id 7) (at 57.15 -17.78 0)
        (effects (font (size 1.27 1.27) (thickness 0.15)) (justify left bottom) hide)
      )
      (symbol "DM3AT-SF-PEJM5_1_1"
        (polyline
          (pts
            (xy 38.1 5.08)
            (xy 38.1 6.35)
            (xy 2.54 6.35)
            (xy 2.54 -26.67)
            (xy 38.1 -26.67)
            (xy 38.1 -19.05)
          )
          (stroke (width 0.254) (type default) (color 0 0 0 0))
          (fill (type background))
        )
        (polyline
          (pts
            (xy 12.7 -19.05)
            (xy 12.7 1.27)
            (xy 20.32 1.27)
            (xy 24.13 5.08)
            (xy 25.4 5.08)
            (xy 25.4 3.81)
            (xy 27.94 3.81)
            (xy 29.21 5.08)
            (xy 41.91 5.08)
            (xy 41.91 -19.05)
            (xy 12.7 -19.05)
          )
          (stroke (width 0.254) (type default) (color 0 0 0 0))
          (fill (type background))
        )
        (rectangle (start 13.97 -17.145) (end 16.51 -18.415)
          (stroke (width 0.254) (type default) (color 0 0 0 0))
          (fill (type background))
        )
        (rectangle (start 13.97 -14.605) (end 16.51 -15.875)
          (stroke (width 0.254) (type default) (color 0 0 0 0))
          (fill (type background))
        )
        (rectangle (start 13.97 -12.065) (end 16.51 -13.335)
          (stroke (width 0.254) (type default) (color 0 0 0 0))
          (fill (type background))
        )
        (rectangle (start 13.97 -9.525) (end 16.51 -10.795)
          (stroke (width 0.254) (type default) (color 0 0 0 0))
          (fill (type background))
        )
        (rectangle (start 13.97 -6.985) (end 16.51 -8.255)
          (stroke (width 0.254) (type default) (color 0 0 0 0))
          (fill (type background))
        )
        (rectangle (start 13.97 -4.445) (end 16.51 -5.715)
          (stroke (width 0.254) (type default) (color 0 0 0 0))
          (fill (type background))
        )
        (rectangle (start 13.97 -1.905) (end 16.51 -3.175)
          (stroke (width 0.254) (type default) (color 0 0 0 0))
          (fill (type background))
        )
        (rectangle (start 13.97 0.635) (end 16.51 -0.635)
          (stroke (width 0.254) (type default) (color 0 0 0 0))
          (fill (type background))
        )
        (pin bidirectional line (at 0 0 0) (length 2.54)
          (name "DAT2" (effects (font (size 1.27 1.27))))
          (number "1" (effects (font (size 1.27 1.27))))
        )
        (pin passive line (at 0 -20.32 0) (length 2.54)
          (name "DET_A" (effects (font (size 1.27 1.27))))
          (number "10" (effects (font (size 1.27 1.27))))
        )
        (pin passive line (at 40.64 -22.86 180) (length 2.54)
          (name "SHIELD" (effects (font (size 1.27 1.27))))
          (number "11" (effects (font (size 1.27 1.27))))
        )
        (pin bidirectional line (at 0 -2.54 0) (length 2.54)
          (name "DAT3/CD" (effects (font (size 1.27 1.27))))
          (number "2" (effects (font (size 1.27 1.27))))
        )
        (pin input line (at 0 -5.08 0) (length 2.54)
          (name "CMD" (effects (font (size 1.27 1.27))))
          (number "3" (effects (font (size 1.27 1.27))))
        )
        (pin power_in line (at 0 -7.62 0) (length 2.54)
          (name "VDD" (effects (font (size 1.27 1.27))))
          (number "4" (effects (font (size 1.27 1.27))))
        )
        (pin input line (at 0 -10.16 0) (length 2.54)
          (name "CLK" (effects (font (size 1.27 1.27))))
          (number "5" (effects (font (size 1.27 1.27))))
        )
        (pin power_in line (at 0 -12.7 0) (length 2.54)
          (name "VSS" (effects (font (size 1.27 1.27))))
          (number "6" (effects (font (size 1.27 1.27))))
        )
        (pin input line (at 0 -15.24 0) (length 2.54)
          (name "DAT0" (effects (font (size 1.27 1.27))))
          (number "7" (effects (font (size 1.27 1.27))))
        )
        (pin input line (at 0 -17.78 0) (length 2.54)
          (name "DAT1" (effects (font (size 1.27 1.27))))
          (number "8" (effects (font (size 1.27 1.27))))
        )
        (pin passive line (at 0 -22.86 0) (length 2.54)
          (name "DET_B" (effects (font (size 1.27 1.27))))
          (number "9" (effects (font (size 1.27 1.27))))
        )
      )
    )
	(symbol "sa800u-baseboard-hw:Earth" (power) (pin_names (offset 0)) (in_bom yes) (on_board yes)
      (property "Reference" "#PWR" (id 0) (at 0 -6.35 0)
        (effects (font (size 1.27 1.27)) hide)
      )
      (property "Value" "Earth" (id 1) (at 0 -3.81 0)
        (effects (font (size 1.27 1.27)) hide)
      )
      (property "Footprint" "" (id 2) (at 0 0 0)
        (effects (font (size 1.27 1.27)) hide)
      )
      (property "Datasheet" "" (id 3) (at 0 0 0)
        (effects (font (size 1.27 1.27)) hide)
      )
      (symbol "Earth_0_1"
        (polyline
          (pts
            (xy -0.635 -1.905)
            (xy 0.635 -1.905)
          )
          (stroke (width 0) (type default) (color 0 0 0 0))
          (fill (type none))
        )
        (polyline
          (pts
            (xy -0.127 -2.54)
            (xy 0.127 -2.54)
          )
          (stroke (width 0) (type default) (color 0 0 0 0))
          (fill (type none))
        )
        (polyline
          (pts
            (xy 0 -1.27)
            (xy 0 0)
          )
          (stroke (width 0) (type default) (color 0 0 0 0))
          (fill (type none))
        )
        (polyline
          (pts
            (xy 1.27 -1.27)
            (xy -1.27 -1.27)
          )
          (stroke (width 0) (type default) (color 0 0 0 0))
          (fill (type none))
        )
      )
      (symbol "Earth_1_1"
        (pin power_in line (at 0 0 270) (length 0) hide
          (name "Earth" (effects (font (size 1.27 1.27))))
          (number "1" (effects (font (size 1.27 1.27))))
        )
      )
    )
	(symbol "sa800u-baseboard-hw:F52R-1A7H1-11020" (in_bom yes) (on_board yes)
      (property "Reference" "J" (id 0) (at 25.4 -5.08 0)
        (effects (font (size 1.27 1.27) (thickness 0.15)) (justify left bottom))
      )
      (property "Value" "F52R-1A7H1-11020" (id 1) (at 25.4 -10.16 0)
        (effects (font (size 1.27 1.27) (thickness 0.15)) (justify left bottom) hide)
      )
      (property "Footprint" "sa800u-baseboard-hw-footprints:F52R-1A7H1-11020" (id 2) (at 25.4 -12.7 0)
        (effects (font (size 1.27 1.27) (thickness 0.15)) (justify left bottom) hide)
      )
      (property "Datasheet" "https://www.snapeda.com/parts/F52R-1A7H1-11020/Amphenol%20ICC%20(FCI)/datasheet/" (id 3) (at 25.4 -15.24 0)
        (effects (font (size 1.27 1.27) (thickness 0.15)) (justify left bottom) hide)
      )
      (property "MPN" "F52R-1A7H1-11020" (id 4) (at 25.4 -7.62 0)
        (effects (font (size 1.27 1.27) (thickness 0.15)) (justify left bottom))
      )
      (property "Manufacturer" "Amphenol" (id 5) (at 25.4 -17.78 0)
        (effects (font (size 1.27 1.27) (thickness 0.15)) (justify left bottom) hide)
      )
      (property "Author" "Antmicro" (id 6) (at 25.4 -20.32 0)
        (effects (font (size 1.27 1.27) (thickness 0.15)) (justify left bottom) hide)
      )
      (property "License" "Apache-2.0" (id 7) (at 25.4 -22.86 0)
        (effects (font (size 1.27 1.27) (thickness 0.15)) (justify left bottom) hide)
      )
      (property "ki_description" "20pin, 1mm, horizontal" (id 8) (at 0 0 0)
        (effects (font (size 1.27 1.27)) hide)
      )
      (symbol "F52R-1A7H1-11020_1_1"
        (polyline
          (pts
            (xy 2.54 -1.27)
            (xy 3.81 0)
          )
          (stroke (width 0.254) (type default) (color 0 0 0 0))
          (fill (type background))
        )
        (rectangle (start 2.54 0) (end 10.16 -58.42)
          (stroke (width 0.254) (type default) (color 0 0 0 0))
          (fill (type background))
        )
        (pin unspecified line (at 0 -2.54 0) (length 2.54)
          (name "1" (effects (font (size 1.27 1.27))))
          (number "1" (effects (font (size 1.27 1.27))))
        )
        (pin unspecified line (at 0 -25.4 0) (length 2.54)
          (name "10" (effects (font (size 1.27 1.27))))
          (number "10" (effects (font (size 1.27 1.27))))
        )
        (pin unspecified line (at 0 -27.94 0) (length 2.54)
          (name "11" (effects (font (size 1.27 1.27))))
          (number "11" (effects (font (size 1.27 1.27))))
        )
        (pin unspecified line (at 0 -30.48 0) (length 2.54)
          (name "12" (effects (font (size 1.27 1.27))))
          (number "12" (effects (font (size 1.27 1.27))))
        )
        (pin unspecified line (at 0 -33.02 0) (length 2.54)
          (name "13" (effects (font (size 1.27 1.27))))
          (number "13" (effects (font (size 1.27 1.27))))
        )
        (pin unspecified line (at 0 -35.56 0) (length 2.54)
          (name "14" (effects (font (size 1.27 1.27))))
          (number "14" (effects (font (size 1.27 1.27))))
        )
        (pin unspecified line (at 0 -38.1 0) (length 2.54)
          (name "15" (effects (font (size 1.27 1.27))))
          (number "15" (effects (font (size 1.27 1.27))))
        )
        (pin unspecified line (at 0 -40.64 0) (length 2.54)
          (name "16" (effects (font (size 1.27 1.27))))
          (number "16" (effects (font (size 1.27 1.27))))
        )
        (pin unspecified line (at 0 -43.18 0) (length 2.54)
          (name "17" (effects (font (size 1.27 1.27))))
          (number "17" (effects (font (size 1.27 1.27))))
        )
        (pin unspecified line (at 0 -45.72 0) (length 2.54)
          (name "18" (effects (font (size 1.27 1.27))))
          (number "18" (effects (font (size 1.27 1.27))))
        )
        (pin unspecified line (at 0 -48.26 0) (length 2.54)
          (name "19" (effects (font (size 1.27 1.27))))
          (number "19" (effects (font (size 1.27 1.27))))
        )
        (pin unspecified line (at 0 -5.08 0) (length 2.54)
          (name "2" (effects (font (size 1.27 1.27))))
          (number "2" (effects (font (size 1.27 1.27))))
        )
        (pin unspecified line (at 0 -50.8 0) (length 2.54)
          (name "20" (effects (font (size 1.27 1.27))))
          (number "20" (effects (font (size 1.27 1.27))))
        )
        (pin unspecified line (at 0 -53.34 0) (length 2.54)
          (name "SH1" (effects (font (size 1.27 1.27))))
          (number "21" (effects (font (size 1.27 1.27))))
        )
        (pin unspecified line (at 0 -55.88 0) (length 2.54)
          (name "SH2" (effects (font (size 1.27 1.27))))
          (number "22" (effects (font (size 1.27 1.27))))
        )
        (pin unspecified line (at 0 -7.62 0) (length 2.54)
          (name "3" (effects (font (size 1.27 1.27))))
          (number "3" (effects (font (size 1.27 1.27))))
        )
        (pin unspecified line (at 0 -10.16 0) (length 2.54)
          (name "4" (effects (font (size 1.27 1.27))))
          (number "4" (effects (font (size 1.27 1.27))))
        )
        (pin unspecified line (at 0 -12.7 0) (length 2.54)
          (name "5" (effects (font (size 1.27 1.27))))
          (number "5" (effects (font (size 1.27 1.27))))
        )
        (pin unspecified line (at 0 -15.24 0) (length 2.54)
          (name "6" (effects (font (size 1.27 1.27))))
          (number "6" (effects (font (size 1.27 1.27))))
        )
        (pin unspecified line (at 0 -17.78 0) (length 2.54)
          (name "7" (effects (font (size 1.27 1.27))))
          (number "7" (effects (font (size 1.27 1.27))))
        )
        (pin unspecified line (at 0 -20.32 0) (length 2.54)
          (name "8" (effects (font (size 1.27 1.27))))
          (number "8" (effects (font (size 1.27 1.27))))
        )
        (pin unspecified line (at 0 -22.86 0) (length 2.54)
          (name "9" (effects (font (size 1.27 1.27))))
          (number "9" (effects (font (size 1.27 1.27))))
        )
      )
    )
	(symbol "sa800u-baseboard-hw:FB_120Z_3A_0603" (pin_numbers hide) (pin_names hide) (in_bom yes) (on_board yes)
      (property "Reference" "FB" (id 0) (at 13.97 0 0)
        (effects (font (size 1.27 1.27) (thickness 0.15)) (justify left bottom))
      )
      (property "Value" "FB_120Z_3A_0603" (id 1) (at 13.97 -2.54 0)
        (effects (font (size 1.27 1.27) (thickness 0.15)) (justify left bottom))
      )
      (property "Footprint" "sa800u-baseboard-hw-footprints:FB_0603_1608Metric" (id 2) (at 13.97 -5.08 0)
        (effects (font (size 1.27 1.27) (thickness 0.15)) (justify left bottom) hide)
      )
      (property "Datasheet" "https://www.murata.com/en-global/api/pdfdownloadapi?cate=luNoiseSupprFilteChipFerriBead&partno=BLM18SG121TN1%23" (id 3) (at 13.97 -7.62 0)
        (effects (font (size 1.27 1.27) (thickness 0.15)) (justify left bottom) hide)
      )
      (property "MPN" "BLM18SG121TN1D" (id 4) (at 13.97 -10.16 0)
        (effects (font (size 1.27 1.27) (thickness 0.15)) (justify left bottom) hide)
      )
      (property "Manufacturer" "Murata" (id 5) (at 13.97 -12.7 0)
        (effects (font (size 1.27 1.27) (thickness 0.15)) (justify left bottom) hide)
      )
      (property "Author" "Antmicro" (id 6) (at 13.97 -15.24 0)
        (effects (font (size 1.27 1.27) (thickness 0.15)) (justify left bottom) hide)
      )
      (property "License" "Apache-2.0" (id 7) (at 13.97 -17.78 0)
        (effects (font (size 1.27 1.27) (thickness 0.15)) (justify left bottom) hide)
      )
      (symbol "FB_120Z_3A_0603_0_1"
        (polyline
          (pts
            (xy 1.651 0)
            (xy 1.2446 0)
          )
          (stroke (width 0) (type default) (color 0 0 0 0))
          (fill (type none))
        )
        (polyline
          (pts
            (xy 3.81 0)
            (xy 3.3274 0)
          )
          (stroke (width 0) (type default) (color 0 0 0 0))
          (fill (type none))
        )
        (polyline
          (pts
            (xy 2.2606 -1.8288)
            (xy 1.0414 -1.1176)
            (xy 2.7432 1.8288)
            (xy 3.9624 1.1176)
            (xy 2.2606 -1.8288)
          )
          (stroke (width 0) (type default) (color 0 0 0 0))
          (fill (type none))
        )
      )
      (symbol "FB_120Z_3A_0603_1_1"
        (pin passive line (at 0 0 0) (length 1.27)
          (name "~" (effects (font (size 1.27 1.27))))
          (number "1" (effects (font (size 1.27 1.27))))
        )
        (pin passive line (at 5.08 0 180) (length 1.27)
          (name "~" (effects (font (size 1.27 1.27))))
          (number "2" (effects (font (size 1.27 1.27))))
        )
      )
    )
	(symbol "sa800u-baseboard-hw:FB_220Z_1A_0603" (pin_numbers hide) (pin_names hide) (in_bom yes) (on_board yes)
      (property "Reference" "FB" (id 0) (at 15.24 -5.08 0)
        (effects (font (size 1.27 1.27) (thickness 0.15)) (justify left bottom))
      )
      (property "Value" "FB_220Z_1A_0603" (id 1) (at 15.24 -7.62 0)
        (effects (font (size 1.27 1.27) (thickness 0.15)) (justify left bottom) hide)
      )
      (property "Footprint" "sa800u-baseboard-hw-footprints:FB_0603_1608Metric" (id 2) (at 15.24 -10.16 0)
        (effects (font (size 1.27 1.27) (thickness 0.15)) (justify left bottom) hide)
      )
      (property "Datasheet" "https://www.murata.com/en-global/api/pdfdownloadapi?cate=luNoiseSupprFilteChipFerriBead&partno=BLM18EG221SN1%23" (id 3) (at 15.24 -12.7 0)
        (effects (font (size 1.27 1.27) (thickness 0.15)) (justify left bottom) hide)
      )
      (property "MPN" "BLM18EG221SN1D" (id 4) (at 15.24 -15.24 0)
        (effects (font (size 1.27 1.27) (thickness 0.15)) (justify left bottom) hide)
      )
      (property "Manufacturer" "Murata" (id 5) (at 15.24 -17.78 0)
        (effects (font (size 1.27 1.27) (thickness 0.15)) (justify left bottom) hide)
      )
      (property "Val" "" (id 6) (at 20.32 -10.16 0)
        (effects (font (size 1.27 1.27) (thickness 0.15)) (justify left bottom))
      )
      (property "Author" "Antmicro" (id 7) (at 15.24 -20.32 0)
        (effects (font (size 1.27 1.27) (thickness 0.15)) (justify left bottom) hide)
      )
      (property "Current" "" (id 8) (at 20.32 -22.86 0)
        (effects (font (size 1.27 1.27) (thickness 0.15)) (justify left bottom) hide)
      )
      (property "License" "Apache-2.0" (id 9) (at 15.24 -22.86 0)
        (effects (font (size 1.27 1.27) (thickness 0.15)) (justify left bottom) hide)
      )
      (symbol "FB_220Z_1A_0603_0_1"
        (polyline
          (pts
            (xy 1.651 0)
            (xy 1.2446 0)
          )
          (stroke (width 0) (type default) (color 0 0 0 0))
          (fill (type none))
        )
        (polyline
          (pts
            (xy 3.81 0)
            (xy 3.3274 0)
          )
          (stroke (width 0) (type default) (color 0 0 0 0))
          (fill (type none))
        )
        (polyline
          (pts
            (xy 2.2606 -1.8288)
            (xy 1.0414 -1.1176)
            (xy 2.7432 1.8288)
            (xy 3.9624 1.1176)
            (xy 2.2606 -1.8288)
          )
          (stroke (width 0) (type default) (color 0 0 0 0))
          (fill (type none))
        )
      )
      (symbol "FB_220Z_1A_0603_1_1"
        (pin passive line (at 0 0 0) (length 1.27)
          (name "~" (effects (font (size 1.27 1.27))))
          (number "1" (effects (font (size 1.27 1.27))))
        )
        (pin passive line (at 5.08 0 180) (length 1.27)
          (name "~" (effects (font (size 1.27 1.27))))
          (number "2" (effects (font (size 1.27 1.27))))
        )
      )
    )
	(symbol "sa800u-baseboard-hw:FB_220Z_2A_0805" (pin_numbers hide) (pin_names hide) (in_bom yes) (on_board yes)
      (property "Reference" "FB" (id 0) (at 13.97 0 0)
        (effects (font (size 1.27 1.27) (thickness 0.15)) (justify left bottom))
      )
      (property "Value" "FB_220Z_2A_0805" (id 1) (at 13.97 -2.54 0)
        (effects (font (size 1.27 1.27) (thickness 0.15)) (justify left bottom))
      )
      (property "Footprint" "sa800u-baseboard-hw-footprints:FB_0805_2012Metric" (id 2) (at 13.97 -5.08 0)
        (effects (font (size 1.27 1.27) (thickness 0.15)) (justify left bottom) hide)
      )
      (property "Datasheet" "https://www.murata.com/products/productdata/8796738977822/ENFA0005.pdf?1653276712000" (id 3) (at 13.97 -7.62 0)
        (effects (font (size 1.27 1.27) (thickness 0.15)) (justify left bottom) hide)
      )
      (property "MPN" "BLM21PG221SN1D" (id 4) (at 13.97 -10.16 0)
        (effects (font (size 1.27 1.27) (thickness 0.15)) (justify left bottom) hide)
      )
      (property "Manufacturer" "Murata" (id 5) (at 13.97 -12.7 0)
        (effects (font (size 1.27 1.27) (thickness 0.15)) (justify left bottom) hide)
      )
      (property "Author" "Antmicro" (id 6) (at 13.97 -15.24 0)
        (effects (font (size 1.27 1.27) (thickness 0.15)) (justify left bottom) hide)
      )
      (property "License" "Apache-2.0" (id 7) (at 13.97 -17.78 0)
        (effects (font (size 1.27 1.27) (thickness 0.15)) (justify left bottom) hide)
      )
      (symbol "FB_220Z_2A_0805_0_1"
        (polyline
          (pts
            (xy 1.651 0)
            (xy 1.2446 0)
          )
          (stroke (width 0) (type default) (color 0 0 0 0))
          (fill (type none))
        )
        (polyline
          (pts
            (xy 3.81 0)
            (xy 3.3274 0)
          )
          (stroke (width 0) (type default) (color 0 0 0 0))
          (fill (type none))
        )
        (polyline
          (pts
            (xy 2.2606 -1.8288)
            (xy 1.0414 -1.1176)
            (xy 2.7432 1.8288)
            (xy 3.9624 1.1176)
            (xy 2.2606 -1.8288)
          )
          (stroke (width 0) (type default) (color 0 0 0 0))
          (fill (type none))
        )
      )
      (symbol "FB_220Z_2A_0805_1_1"
        (pin passive line (at 0 0 0) (length 1.27)
          (name "~" (effects (font (size 1.27 1.27))))
          (number "1" (effects (font (size 1.27 1.27))))
        )
        (pin passive line (at 5.08 0 180) (length 1.27)
          (name "~" (effects (font (size 1.27 1.27))))
          (number "2" (effects (font (size 1.27 1.27))))
        )
      )
    )
	(symbol "sa800u-baseboard-hw:FT232R_QFN" (in_bom yes) (on_board yes)
      (property "Reference" "U" (id 0) (at 40.64 -5.08 0)
        (effects (font (size 1.27 1.27) (thickness 0.15)) (justify left bottom))
      )
      (property "Value" "FT232R_QFN" (id 1) (at 40.64 -7.62 0)
        (effects (font (size 1.27 1.27) (thickness 0.15)) (justify left bottom))
      )
      (property "Footprint" "sa800u-baseboard-hw-footprints:QFN-32-1EP_5x5mm" (id 2) (at 40.64 -10.16 0)
        (effects (font (size 1.27 1.27) (thickness 0.15)) (justify left bottom) hide)
      )
      (property "Datasheet" "https://www.ftdichip.com/Support/Documents/DataSheets/ICs/DS_FT232R.pdf" (id 3) (at 40.64 -12.7 0)
        (effects (font (size 1.27 1.27) (thickness 0.15)) (justify left bottom) hide)
      )
      (property "Manufacturer" "FTDI" (id 4) (at 40.64 -15.24 0)
        (effects (font (size 1.27 1.27) (thickness 0.15)) (justify left bottom) hide)
      )
      (property "MPN" "FT232RQ-REEL" (id 5) (at 40.64 -17.78 0)
        (effects (font (size 1.27 1.27) (thickness 0.15)) (justify left bottom) hide)
      )
      (property "Author" "Antmicro" (id 6) (at 40.64 -20.32 0)
        (effects (font (size 1.27 1.27) (thickness 0.15)) (justify left bottom) hide)
      )
      (property "License" "Apache-2.0" (id 7) (at 40.64 -22.86 0)
        (effects (font (size 1.27 1.27) (thickness 0.15)) (justify left bottom) hide)
      )
      (symbol "FT232R_QFN_1_1"
        (rectangle (start 2.54 2.54) (end 22.86 -43.18)
          (stroke (width 0.254) (type default) (color 0 0 0 0))
          (fill (type background))
        )
        (pin power_in line (at 0 -2.54 0) (length 2.54)
          (name "VCCIO" (effects (font (size 1.27 1.27))))
          (number "1" (effects (font (size 1.27 1.27))))
        )
        (pin bidirectional line (at 25.4 -30.48 180) (length 2.54)
          (name "CBUS2" (effects (font (size 1.27 1.27))))
          (number "10" (effects (font (size 1.27 1.27))))
        )
        (pin bidirectional line (at 25.4 -33.02 180) (length 2.54)
          (name "CBUS3" (effects (font (size 1.27 1.27))))
          (number "11" (effects (font (size 1.27 1.27))))
        )
        (pin no_connect line (at 22.86 -40.64 180) (length 2.54) hide
          (name "NC" (effects (font (size 1.27 1.27))))
          (number "12" (effects (font (size 1.27 1.27))))
        )
        (pin no_connect line (at 2.54 -17.78 0) (length 2.54) hide
          (name "NC" (effects (font (size 1.27 1.27))))
          (number "13" (effects (font (size 1.27 1.27))))
        )
        (pin bidirectional line (at 0 -10.16 0) (length 2.54)
          (name "USBDP" (effects (font (size 1.27 1.27))))
          (number "14" (effects (font (size 1.27 1.27))))
        )
        (pin bidirectional line (at 0 -12.7 0) (length 2.54)
          (name "USBDM" (effects (font (size 1.27 1.27))))
          (number "15" (effects (font (size 1.27 1.27))))
        )
        (pin output line (at 25.4 0 180) (length 2.54)
          (name "3V3OUT" (effects (font (size 1.27 1.27))))
          (number "16" (effects (font (size 1.27 1.27))))
        )
        (pin power_in line (at 0 -35.56 0) (length 2.54)
          (name "GND" (effects (font (size 1.27 1.27))))
          (number "17" (effects (font (size 1.27 1.27))))
        )
        (pin input line (at 0 -5.08 0) (length 2.54)
          (name "RESET#" (effects (font (size 1.27 1.27))))
          (number "18" (effects (font (size 1.27 1.27))))
        )
        (pin power_in line (at 0 0 0) (length 2.54)
          (name "VCC" (effects (font (size 1.27 1.27))))
          (number "19" (effects (font (size 1.27 1.27))))
        )
        (pin input line (at 25.4 -5.08 180) (length 2.54)
          (name "RXD" (effects (font (size 1.27 1.27))))
          (number "2" (effects (font (size 1.27 1.27))))
        )
        (pin passive line (at 0 -35.56 0) (length 2.54) hide
          (name "GND" (effects (font (size 1.27 1.27))))
          (number "20" (effects (font (size 1.27 1.27))))
        )
        (pin bidirectional line (at 25.4 -27.94 180) (length 2.54)
          (name "CBUS1" (effects (font (size 1.27 1.27))))
          (number "21" (effects (font (size 1.27 1.27))))
        )
        (pin bidirectional line (at 25.4 -25.4 180) (length 2.54)
          (name "CBUS0" (effects (font (size 1.27 1.27))))
          (number "22" (effects (font (size 1.27 1.27))))
        )
        (pin no_connect line (at 2.54 -20.32 0) (length 2.54) hide
          (name "NC" (effects (font (size 1.27 1.27))))
          (number "23" (effects (font (size 1.27 1.27))))
        )
        (pin power_in line (at 0 -38.1 0) (length 2.54)
          (name "AGND" (effects (font (size 1.27 1.27))))
          (number "24" (effects (font (size 1.27 1.27))))
        )
        (pin no_connect line (at 2.54 -22.86 0) (length 2.54) hide
          (name "NC" (effects (font (size 1.27 1.27))))
          (number "25" (effects (font (size 1.27 1.27))))
        )
        (pin input line (at 0 -33.02 0) (length 2.54)
          (name "TEST" (effects (font (size 1.27 1.27))))
          (number "26" (effects (font (size 1.27 1.27))))
        )
        (pin input line (at 0 -27.94 0) (length 2.54)
          (name "OSCI" (effects (font (size 1.27 1.27))))
          (number "27" (effects (font (size 1.27 1.27))))
        )
        (pin output line (at 0 -30.48 0) (length 2.54)
          (name "OSCO" (effects (font (size 1.27 1.27))))
          (number "28" (effects (font (size 1.27 1.27))))
        )
        (pin no_connect line (at 2.54 -25.4 0) (length 2.54) hide
          (name "NC" (effects (font (size 1.27 1.27))))
          (number "29" (effects (font (size 1.27 1.27))))
        )
        (pin input line (at 25.4 -22.86 180) (length 2.54)
          (name "RI#" (effects (font (size 1.27 1.27))))
          (number "3" (effects (font (size 1.27 1.27))))
        )
        (pin output line (at 25.4 -2.54 180) (length 2.54)
          (name "TXD" (effects (font (size 1.27 1.27))))
          (number "30" (effects (font (size 1.27 1.27))))
        )
        (pin output line (at 25.4 -7.62 180) (length 2.54)
          (name "DTR#" (effects (font (size 1.27 1.27))))
          (number "31" (effects (font (size 1.27 1.27))))
        )
        (pin output line (at 25.4 -10.16 180) (length 2.54)
          (name "RTS#" (effects (font (size 1.27 1.27))))
          (number "32" (effects (font (size 1.27 1.27))))
        )
        (pin unspecified line (at 0 -40.64 0) (length 2.54)
          (name "EP" (effects (font (size 1.27 1.27))))
          (number "33" (effects (font (size 1.27 1.27))))
        )
        (pin passive line (at 0 -35.56 0) (length 2.54) hide
          (name "GND" (effects (font (size 1.27 1.27))))
          (number "4" (effects (font (size 1.27 1.27))))
        )
        (pin no_connect line (at 22.86 -38.1 180) (length 2.54) hide
          (name "NC" (effects (font (size 1.27 1.27))))
          (number "5" (effects (font (size 1.27 1.27))))
        )
        (pin input line (at 25.4 -15.24 180) (length 2.54)
          (name "DSR#" (effects (font (size 1.27 1.27))))
          (number "6" (effects (font (size 1.27 1.27))))
        )
        (pin input line (at 25.4 -17.78 180) (length 2.54)
          (name "DCD#" (effects (font (size 1.27 1.27))))
          (number "7" (effects (font (size 1.27 1.27))))
        )
        (pin input line (at 25.4 -20.32 180) (length 2.54)
          (name "CTS#" (effects (font (size 1.27 1.27))))
          (number "8" (effects (font (size 1.27 1.27))))
        )
        (pin bidirectional line (at 25.4 -35.56 180) (length 2.54)
          (name "CBUS4" (effects (font (size 1.27 1.27))))
          (number "9" (effects (font (size 1.27 1.27))))
        )
      )
    )
	(symbol "sa800u-baseboard-hw:GND" (power) (pin_numbers hide) (pin_names hide) (in_bom yes) (on_board yes)
      (property "Reference" "#PWR" (id 0) (at 8.89 -2.54 0)
        (effects (font (size 1.27 1.27) (thickness 0.15)) (justify left bottom) hide)
      )
      (property "Value" "GND" (id 1) (at 8.89 -5.08 0)
        (effects (font (size 1.27 1.27) (thickness 0.15)) (justify left bottom))
      )
      (property "Footprint" "" (id 2) (at 8.89 -7.62 0)
        (effects (font (size 1.27 1.27) (thickness 0.15)) (justify left bottom) hide)
      )
      (property "Datasheet" "" (id 3) (at 8.89 -12.7 0)
        (effects (font (size 1.27 1.27) (thickness 0.15)) (justify left bottom) hide)
      )
      (property "Author" "Antmicro" (id 4) (at 8.89 -7.62 0)
        (effects (font (size 1.27 1.27) (thickness 0.15)) (justify left bottom) hide)
      )
      (property "License" "Apache-2.0" (id 5) (at 8.89 -10.16 0)
        (effects (font (size 1.27 1.27) (thickness 0.15)) (justify left bottom) hide)
      )
      (symbol "GND_1_1"
        (polyline
          (pts
            (xy 0 0)
            (xy 0 -1.27)
            (xy 1.27 -1.27)
            (xy 0 -2.54)
            (xy -1.27 -1.27)
            (xy 0 -1.27)
          )
          (stroke (width 0) (type default) (color 0 0 0 0))
          (fill (type none))
        )
        (pin power_in line (at 0 0 270) (length 0)
          (name "GND" (effects (font (size 1.27 1.27))))
          (number "1" (effects (font (size 1.27 1.27))))
        )
      )
    )
	(symbol "sa800u-baseboard-hw:GNDD" (power) (pin_numbers hide) (pin_names hide) (in_bom yes) (on_board yes)
      (property "Reference" "#PWR" (id 0) (at 15.24 -2.54 0)
        (effects (font (size 1.27 1.27) (thickness 0.15)) (justify left bottom) hide)
      )
      (property "Value" "GNDD" (id 1) (at 15.24 -5.08 0)
        (effects (font (size 1.27 1.27) (thickness 0.15)) (justify left bottom))
      )
      (property "Footprint" "" (id 2) (at 15.24 -10.16 0)
        (effects (font (size 1.27 1.27) (thickness 0.15)) (justify left bottom) hide)
      )
      (property "Datasheet" "" (id 3) (at 15.24 -12.7 0)
        (effects (font (size 1.27 1.27) (thickness 0.15)) (justify left bottom) hide)
      )
      (property "Author" "Antmicro" (id 4) (at 15.24 -7.62 0)
        (effects (font (size 1.27 1.27) (thickness 0.15)) (justify left bottom) hide)
      )
      (property "License" "Apache-2.0" (id 5) (at 15.24 -10.16 0)
        (effects (font (size 1.27 1.27) (thickness 0.15)) (justify left bottom) hide)
      )
      (symbol "GNDD_1_1"
        (rectangle (start -1.27 -1.524) (end 1.27 -2.032)
          (stroke (width 0) (type default) (color 0 0 0 0))
          (fill (type outline))
        )
        (polyline
          (pts
            (xy 0 0)
            (xy 0 -1.524)
          )
          (stroke (width 0) (type default) (color 0 0 0 0))
          (fill (type background))
        )
        (pin power_in line (at 0 0 270) (length 0)
          (name "GNDD" (effects (font (size 1.27 1.27))))
          (number "1" (effects (font (size 1.27 1.27))))
        )
      )
    )
	(symbol "sa800u-baseboard-hw:GND_10" (power) (pin_numbers hide) (pin_names hide) (in_bom yes) (on_board yes)
      (property "Reference" "#PWR" (id 0) (at 8.89 -2.54 0)
        (effects (font (size 1.27 1.27) (thickness 0.15)) (justify left bottom) hide)
      )
      (property "Value" "GND_10" (id 1) (at 8.89 -5.08 0)
        (effects (font (size 1.27 1.27) (thickness 0.15)) (justify left bottom))
      )
      (property "Footprint" "" (id 2) (at 8.89 -7.62 0)
        (effects (font (size 1.27 1.27) (thickness 0.15)) (justify left bottom) hide)
      )
      (property "Datasheet" "" (id 3) (at 8.89 -12.7 0)
        (effects (font (size 1.27 1.27) (thickness 0.15)) (justify left bottom) hide)
      )
      (property "Author" "Antmicro" (id 4) (at 8.89 -7.62 0)
        (effects (font (size 1.27 1.27) (thickness 0.15)) (justify left bottom) hide)
      )
      (property "License" "Apache-2.0" (id 5) (at 8.89 -10.16 0)
        (effects (font (size 1.27 1.27) (thickness 0.15)) (justify left bottom) hide)
      )
      (symbol "GND_10_1_1"
        (polyline
          (pts
            (xy 0 0)
            (xy 0 -1.27)
            (xy 1.27 -1.27)
            (xy 0 -2.54)
            (xy -1.27 -1.27)
            (xy 0 -1.27)
          )
          (stroke (width 0) (type default) (color 0 0 0 0))
          (fill (type none))
        )
        (pin power_in line (at 0 0 270) (length 0)
          (name "GND" (effects (font (size 1.27 1.27))))
          (number "1" (effects (font (size 1.27 1.27))))
        )
      )
    )
	(symbol "sa800u-baseboard-hw:GND_11" (power) (pin_numbers hide) (pin_names hide) (in_bom yes) (on_board yes)
      (property "Reference" "#PWR" (id 0) (at 8.89 -2.54 0)
        (effects (font (size 1.27 1.27) (thickness 0.15)) (justify left bottom) hide)
      )
      (property "Value" "GND_11" (id 1) (at 8.89 -5.08 0)
        (effects (font (size 1.27 1.27) (thickness 0.15)) (justify left bottom))
      )
      (property "Footprint" "" (id 2) (at 8.89 -7.62 0)
        (effects (font (size 1.27 1.27) (thickness 0.15)) (justify left bottom) hide)
      )
      (property "Datasheet" "" (id 3) (at 8.89 -12.7 0)
        (effects (font (size 1.27 1.27) (thickness 0.15)) (justify left bottom) hide)
      )
      (property "Author" "Antmicro" (id 4) (at 8.89 -7.62 0)
        (effects (font (size 1.27 1.27) (thickness 0.15)) (justify left bottom) hide)
      )
      (property "License" "Apache-2.0" (id 5) (at 8.89 -10.16 0)
        (effects (font (size 1.27 1.27) (thickness 0.15)) (justify left bottom) hide)
      )
      (symbol "GND_11_1_1"
        (polyline
          (pts
            (xy 0 0)
            (xy 0 -1.27)
            (xy 1.27 -1.27)
            (xy 0 -2.54)
            (xy -1.27 -1.27)
            (xy 0 -1.27)
          )
          (stroke (width 0) (type default) (color 0 0 0 0))
          (fill (type none))
        )
        (pin power_in line (at 0 0 270) (length 0)
          (name "GND" (effects (font (size 1.27 1.27))))
          (number "1" (effects (font (size 1.27 1.27))))
        )
      )
    )
	(symbol "sa800u-baseboard-hw:GND_12" (power) (pin_numbers hide) (pin_names hide) (in_bom yes) (on_board yes)
      (property "Reference" "#PWR" (id 0) (at 8.89 -2.54 0)
        (effects (font (size 1.27 1.27) (thickness 0.15)) (justify left bottom) hide)
      )
      (property "Value" "GND_12" (id 1) (at 8.89 -5.08 0)
        (effects (font (size 1.27 1.27) (thickness 0.15)) (justify left bottom))
      )
      (property "Footprint" "" (id 2) (at 8.89 -7.62 0)
        (effects (font (size 1.27 1.27) (thickness 0.15)) (justify left bottom) hide)
      )
      (property "Datasheet" "" (id 3) (at 8.89 -12.7 0)
        (effects (font (size 1.27 1.27) (thickness 0.15)) (justify left bottom) hide)
      )
      (property "Author" "Antmicro" (id 4) (at 8.89 -7.62 0)
        (effects (font (size 1.27 1.27) (thickness 0.15)) (justify left bottom) hide)
      )
      (property "License" "Apache-2.0" (id 5) (at 8.89 -10.16 0)
        (effects (font (size 1.27 1.27) (thickness 0.15)) (justify left bottom) hide)
      )
      (symbol "GND_12_1_1"
        (polyline
          (pts
            (xy 0 0)
            (xy 0 -1.27)
            (xy 1.27 -1.27)
            (xy 0 -2.54)
            (xy -1.27 -1.27)
            (xy 0 -1.27)
          )
          (stroke (width 0) (type default) (color 0 0 0 0))
          (fill (type none))
        )
        (pin power_in line (at 0 0 270) (length 0)
          (name "GND" (effects (font (size 1.27 1.27))))
          (number "1" (effects (font (size 1.27 1.27))))
        )
      )
    )
	(symbol "sa800u-baseboard-hw:GND_13" (power) (pin_numbers hide) (pin_names hide) (in_bom yes) (on_board yes)
      (property "Reference" "#PWR" (id 0) (at 8.89 -2.54 0)
        (effects (font (size 1.27 1.27) (thickness 0.15)) (justify left bottom) hide)
      )
      (property "Value" "GND_13" (id 1) (at 8.89 -5.08 0)
        (effects (font (size 1.27 1.27) (thickness 0.15)) (justify left bottom))
      )
      (property "Footprint" "" (id 2) (at 8.89 -7.62 0)
        (effects (font (size 1.27 1.27) (thickness 0.15)) (justify left bottom) hide)
      )
      (property "Datasheet" "" (id 3) (at 8.89 -12.7 0)
        (effects (font (size 1.27 1.27) (thickness 0.15)) (justify left bottom) hide)
      )
      (property "Author" "Antmicro" (id 4) (at 8.89 -7.62 0)
        (effects (font (size 1.27 1.27) (thickness 0.15)) (justify left bottom) hide)
      )
      (property "License" "Apache-2.0" (id 5) (at 8.89 -10.16 0)
        (effects (font (size 1.27 1.27) (thickness 0.15)) (justify left bottom) hide)
      )
      (symbol "GND_13_1_1"
        (polyline
          (pts
            (xy 0 0)
            (xy 0 -1.27)
            (xy 1.27 -1.27)
            (xy 0 -2.54)
            (xy -1.27 -1.27)
            (xy 0 -1.27)
          )
          (stroke (width 0) (type default) (color 0 0 0 0))
          (fill (type none))
        )
        (pin power_in line (at 0 0 270) (length 0)
          (name "GND" (effects (font (size 1.27 1.27))))
          (number "1" (effects (font (size 1.27 1.27))))
        )
      )
    )
	(symbol "sa800u-baseboard-hw:GND_14" (power) (pin_numbers hide) (pin_names hide) (in_bom yes) (on_board yes)
      (property "Reference" "#PWR" (id 0) (at 8.89 -2.54 0)
        (effects (font (size 1.27 1.27) (thickness 0.15)) (justify left bottom) hide)
      )
      (property "Value" "GND_14" (id 1) (at 8.89 -5.08 0)
        (effects (font (size 1.27 1.27) (thickness 0.15)) (justify left bottom))
      )
      (property "Footprint" "" (id 2) (at 8.89 -7.62 0)
        (effects (font (size 1.27 1.27) (thickness 0.15)) (justify left bottom) hide)
      )
      (property "Datasheet" "" (id 3) (at 8.89 -12.7 0)
        (effects (font (size 1.27 1.27) (thickness 0.15)) (justify left bottom) hide)
      )
      (property "Author" "Antmicro" (id 4) (at 8.89 -7.62 0)
        (effects (font (size 1.27 1.27) (thickness 0.15)) (justify left bottom) hide)
      )
      (property "License" "Apache-2.0" (id 5) (at 8.89 -10.16 0)
        (effects (font (size 1.27 1.27) (thickness 0.15)) (justify left bottom) hide)
      )
      (symbol "GND_14_1_1"
        (polyline
          (pts
            (xy 0 0)
            (xy 0 -1.27)
            (xy 1.27 -1.27)
            (xy 0 -2.54)
            (xy -1.27 -1.27)
            (xy 0 -1.27)
          )
          (stroke (width 0) (type default) (color 0 0 0 0))
          (fill (type none))
        )
        (pin power_in line (at 0 0 270) (length 0)
          (name "GND" (effects (font (size 1.27 1.27))))
          (number "1" (effects (font (size 1.27 1.27))))
        )
      )
    )
	(symbol "sa800u-baseboard-hw:GND_15" (power) (pin_numbers hide) (pin_names hide) (in_bom yes) (on_board yes)
      (property "Reference" "#PWR" (id 0) (at 8.89 -2.54 0)
        (effects (font (size 1.27 1.27) (thickness 0.15)) (justify left bottom) hide)
      )
      (property "Value" "GND_15" (id 1) (at 8.89 -5.08 0)
        (effects (font (size 1.27 1.27) (thickness 0.15)) (justify left bottom))
      )
      (property "Footprint" "" (id 2) (at 8.89 -7.62 0)
        (effects (font (size 1.27 1.27) (thickness 0.15)) (justify left bottom) hide)
      )
      (property "Datasheet" "" (id 3) (at 8.89 -12.7 0)
        (effects (font (size 1.27 1.27) (thickness 0.15)) (justify left bottom) hide)
      )
      (property "Author" "Antmicro" (id 4) (at 8.89 -7.62 0)
        (effects (font (size 1.27 1.27) (thickness 0.15)) (justify left bottom) hide)
      )
      (property "License" "Apache-2.0" (id 5) (at 8.89 -10.16 0)
        (effects (font (size 1.27 1.27) (thickness 0.15)) (justify left bottom) hide)
      )
      (symbol "GND_15_1_1"
        (polyline
          (pts
            (xy 0 0)
            (xy 0 -1.27)
            (xy 1.27 -1.27)
            (xy 0 -2.54)
            (xy -1.27 -1.27)
            (xy 0 -1.27)
          )
          (stroke (width 0) (type default) (color 0 0 0 0))
          (fill (type none))
        )
        (pin power_in line (at 0 0 270) (length 0)
          (name "GND" (effects (font (size 1.27 1.27))))
          (number "1" (effects (font (size 1.27 1.27))))
        )
      )
    )
	(symbol "sa800u-baseboard-hw:GND_16" (power) (pin_numbers hide) (pin_names hide) (in_bom yes) (on_board yes)
      (property "Reference" "#PWR" (id 0) (at 8.89 -2.54 0)
        (effects (font (size 1.27 1.27) (thickness 0.15)) (justify left bottom) hide)
      )
      (property "Value" "GND_16" (id 1) (at 8.89 -5.08 0)
        (effects (font (size 1.27 1.27) (thickness 0.15)) (justify left bottom))
      )
      (property "Footprint" "" (id 2) (at 8.89 -7.62 0)
        (effects (font (size 1.27 1.27) (thickness 0.15)) (justify left bottom) hide)
      )
      (property "Datasheet" "" (id 3) (at 8.89 -12.7 0)
        (effects (font (size 1.27 1.27) (thickness 0.15)) (justify left bottom) hide)
      )
      (property "Author" "Antmicro" (id 4) (at 8.89 -7.62 0)
        (effects (font (size 1.27 1.27) (thickness 0.15)) (justify left bottom) hide)
      )
      (property "License" "Apache-2.0" (id 5) (at 8.89 -10.16 0)
        (effects (font (size 1.27 1.27) (thickness 0.15)) (justify left bottom) hide)
      )
      (symbol "GND_16_1_1"
        (polyline
          (pts
            (xy 0 0)
            (xy 0 -1.27)
            (xy 1.27 -1.27)
            (xy 0 -2.54)
            (xy -1.27 -1.27)
            (xy 0 -1.27)
          )
          (stroke (width 0) (type default) (color 0 0 0 0))
          (fill (type none))
        )
        (pin power_in line (at 0 0 270) (length 0)
          (name "GND" (effects (font (size 1.27 1.27))))
          (number "1" (effects (font (size 1.27 1.27))))
        )
      )
    )
	(symbol "sa800u-baseboard-hw:GND_17" (power) (pin_numbers hide) (pin_names hide) (in_bom yes) (on_board yes)
      (property "Reference" "#PWR" (id 0) (at 8.89 -2.54 0)
        (effects (font (size 1.27 1.27) (thickness 0.15)) (justify left bottom) hide)
      )
      (property "Value" "GND_17" (id 1) (at 8.89 -5.08 0)
        (effects (font (size 1.27 1.27) (thickness 0.15)) (justify left bottom))
      )
      (property "Footprint" "" (id 2) (at 8.89 -7.62 0)
        (effects (font (size 1.27 1.27) (thickness 0.15)) (justify left bottom) hide)
      )
      (property "Datasheet" "" (id 3) (at 8.89 -12.7 0)
        (effects (font (size 1.27 1.27) (thickness 0.15)) (justify left bottom) hide)
      )
      (property "Author" "Antmicro" (id 4) (at 8.89 -7.62 0)
        (effects (font (size 1.27 1.27) (thickness 0.15)) (justify left bottom) hide)
      )
      (property "License" "Apache-2.0" (id 5) (at 8.89 -10.16 0)
        (effects (font (size 1.27 1.27) (thickness 0.15)) (justify left bottom) hide)
      )
      (symbol "GND_17_1_1"
        (polyline
          (pts
            (xy 0 0)
            (xy 0 -1.27)
            (xy 1.27 -1.27)
            (xy 0 -2.54)
            (xy -1.27 -1.27)
            (xy 0 -1.27)
          )
          (stroke (width 0) (type default) (color 0 0 0 0))
          (fill (type none))
        )
        (pin power_in line (at 0 0 270) (length 0)
          (name "GND" (effects (font (size 1.27 1.27))))
          (number "1" (effects (font (size 1.27 1.27))))
        )
      )
    )
	(symbol "sa800u-baseboard-hw:GND_18" (power) (pin_numbers hide) (pin_names hide) (in_bom yes) (on_board yes)
      (property "Reference" "#PWR" (id 0) (at 8.89 -2.54 0)
        (effects (font (size 1.27 1.27) (thickness 0.15)) (justify left bottom) hide)
      )
      (property "Value" "GND_18" (id 1) (at 8.89 -5.08 0)
        (effects (font (size 1.27 1.27) (thickness 0.15)) (justify left bottom))
      )
      (property "Footprint" "" (id 2) (at 8.89 -7.62 0)
        (effects (font (size 1.27 1.27) (thickness 0.15)) (justify left bottom) hide)
      )
      (property "Datasheet" "" (id 3) (at 8.89 -12.7 0)
        (effects (font (size 1.27 1.27) (thickness 0.15)) (justify left bottom) hide)
      )
      (property "Author" "Antmicro" (id 4) (at 8.89 -7.62 0)
        (effects (font (size 1.27 1.27) (thickness 0.15)) (justify left bottom) hide)
      )
      (property "License" "Apache-2.0" (id 5) (at 8.89 -10.16 0)
        (effects (font (size 1.27 1.27) (thickness 0.15)) (justify left bottom) hide)
      )
      (symbol "GND_18_1_1"
        (polyline
          (pts
            (xy 0 0)
            (xy 0 -1.27)
            (xy 1.27 -1.27)
            (xy 0 -2.54)
            (xy -1.27 -1.27)
            (xy 0 -1.27)
          )
          (stroke (width 0) (type default) (color 0 0 0 0))
          (fill (type none))
        )
        (pin power_in line (at 0 0 270) (length 0)
          (name "GND" (effects (font (size 1.27 1.27))))
          (number "1" (effects (font (size 1.27 1.27))))
        )
      )
    )
	(symbol "sa800u-baseboard-hw:GND_19" (power) (pin_numbers hide) (pin_names hide) (in_bom yes) (on_board yes)
      (property "Reference" "#PWR" (id 0) (at 8.89 -2.54 0)
        (effects (font (size 1.27 1.27) (thickness 0.15)) (justify left bottom) hide)
      )
      (property "Value" "GND_19" (id 1) (at 8.89 -5.08 0)
        (effects (font (size 1.27 1.27) (thickness 0.15)) (justify left bottom))
      )
      (property "Footprint" "" (id 2) (at 8.89 -7.62 0)
        (effects (font (size 1.27 1.27) (thickness 0.15)) (justify left bottom) hide)
      )
      (property "Datasheet" "" (id 3) (at 8.89 -12.7 0)
        (effects (font (size 1.27 1.27) (thickness 0.15)) (justify left bottom) hide)
      )
      (property "Author" "Antmicro" (id 4) (at 8.89 -7.62 0)
        (effects (font (size 1.27 1.27) (thickness 0.15)) (justify left bottom) hide)
      )
      (property "License" "Apache-2.0" (id 5) (at 8.89 -10.16 0)
        (effects (font (size 1.27 1.27) (thickness 0.15)) (justify left bottom) hide)
      )
      (symbol "GND_19_1_1"
        (polyline
          (pts
            (xy 0 0)
            (xy 0 -1.27)
            (xy 1.27 -1.27)
            (xy 0 -2.54)
            (xy -1.27 -1.27)
            (xy 0 -1.27)
          )
          (stroke (width 0) (type default) (color 0 0 0 0))
          (fill (type none))
        )
        (pin power_in line (at 0 0 270) (length 0)
          (name "GND" (effects (font (size 1.27 1.27))))
          (number "1" (effects (font (size 1.27 1.27))))
        )
      )
    )
	(symbol "sa800u-baseboard-hw:GND_20" (power) (pin_numbers hide) (pin_names hide) (in_bom yes) (on_board yes)
      (property "Reference" "#PWR" (id 0) (at 8.89 -2.54 0)
        (effects (font (size 1.27 1.27) (thickness 0.15)) (justify left bottom) hide)
      )
      (property "Value" "GND_20" (id 1) (at 8.89 -5.08 0)
        (effects (font (size 1.27 1.27) (thickness 0.15)) (justify left bottom))
      )
      (property "Footprint" "" (id 2) (at 8.89 -7.62 0)
        (effects (font (size 1.27 1.27) (thickness 0.15)) (justify left bottom) hide)
      )
      (property "Datasheet" "" (id 3) (at 8.89 -12.7 0)
        (effects (font (size 1.27 1.27) (thickness 0.15)) (justify left bottom) hide)
      )
      (property "Author" "Antmicro" (id 4) (at 8.89 -7.62 0)
        (effects (font (size 1.27 1.27) (thickness 0.15)) (justify left bottom) hide)
      )
      (property "License" "Apache-2.0" (id 5) (at 8.89 -10.16 0)
        (effects (font (size 1.27 1.27) (thickness 0.15)) (justify left bottom) hide)
      )
      (symbol "GND_20_1_1"
        (polyline
          (pts
            (xy 0 0)
            (xy 0 -1.27)
            (xy 1.27 -1.27)
            (xy 0 -2.54)
            (xy -1.27 -1.27)
            (xy 0 -1.27)
          )
          (stroke (width 0) (type default) (color 0 0 0 0))
          (fill (type none))
        )
        (pin power_in line (at 0 0 270) (length 0)
          (name "GND" (effects (font (size 1.27 1.27))))
          (number "1" (effects (font (size 1.27 1.27))))
        )
      )
    )
	(symbol "sa800u-baseboard-hw:GND_21" (power) (pin_numbers hide) (pin_names hide) (in_bom yes) (on_board yes)
      (property "Reference" "#PWR" (id 0) (at 8.89 -2.54 0)
        (effects (font (size 1.27 1.27) (thickness 0.15)) (justify left bottom) hide)
      )
      (property "Value" "GND_21" (id 1) (at 8.89 -5.08 0)
        (effects (font (size 1.27 1.27) (thickness 0.15)) (justify left bottom))
      )
      (property "Footprint" "" (id 2) (at 8.89 -7.62 0)
        (effects (font (size 1.27 1.27) (thickness 0.15)) (justify left bottom) hide)
      )
      (property "Datasheet" "" (id 3) (at 8.89 -12.7 0)
        (effects (font (size 1.27 1.27) (thickness 0.15)) (justify left bottom) hide)
      )
      (property "Author" "Antmicro" (id 4) (at 8.89 -7.62 0)
        (effects (font (size 1.27 1.27) (thickness 0.15)) (justify left bottom) hide)
      )
      (property "License" "Apache-2.0" (id 5) (at 8.89 -10.16 0)
        (effects (font (size 1.27 1.27) (thickness 0.15)) (justify left bottom) hide)
      )
      (symbol "GND_21_1_1"
        (polyline
          (pts
            (xy 0 0)
            (xy 0 -1.27)
            (xy 1.27 -1.27)
            (xy 0 -2.54)
            (xy -1.27 -1.27)
            (xy 0 -1.27)
          )
          (stroke (width 0) (type default) (color 0 0 0 0))
          (fill (type none))
        )
        (pin power_in line (at 0 0 270) (length 0)
          (name "GND" (effects (font (size 1.27 1.27))))
          (number "1" (effects (font (size 1.27 1.27))))
        )
      )
    )
	(symbol "sa800u-baseboard-hw:GND_22" (power) (pin_numbers hide) (pin_names hide) (in_bom yes) (on_board yes)
      (property "Reference" "#PWR" (id 0) (at 8.89 -2.54 0)
        (effects (font (size 1.27 1.27) (thickness 0.15)) (justify left bottom) hide)
      )
      (property "Value" "GND_22" (id 1) (at 8.89 -5.08 0)
        (effects (font (size 1.27 1.27) (thickness 0.15)) (justify left bottom))
      )
      (property "Footprint" "" (id 2) (at 8.89 -7.62 0)
        (effects (font (size 1.27 1.27) (thickness 0.15)) (justify left bottom) hide)
      )
      (property "Datasheet" "" (id 3) (at 8.89 -12.7 0)
        (effects (font (size 1.27 1.27) (thickness 0.15)) (justify left bottom) hide)
      )
      (property "Author" "Antmicro" (id 4) (at 8.89 -7.62 0)
        (effects (font (size 1.27 1.27) (thickness 0.15)) (justify left bottom) hide)
      )
      (property "License" "Apache-2.0" (id 5) (at 8.89 -10.16 0)
        (effects (font (size 1.27 1.27) (thickness 0.15)) (justify left bottom) hide)
      )
      (symbol "GND_22_1_1"
        (polyline
          (pts
            (xy 0 0)
            (xy 0 -1.27)
            (xy 1.27 -1.27)
            (xy 0 -2.54)
            (xy -1.27 -1.27)
            (xy 0 -1.27)
          )
          (stroke (width 0) (type default) (color 0 0 0 0))
          (fill (type none))
        )
        (pin power_in line (at 0 0 270) (length 0)
          (name "GND" (effects (font (size 1.27 1.27))))
          (number "1" (effects (font (size 1.27 1.27))))
        )
      )
    )
	(symbol "sa800u-baseboard-hw:GND_23" (power) (pin_numbers hide) (pin_names hide) (in_bom yes) (on_board yes)
      (property "Reference" "#PWR" (id 0) (at 8.89 -2.54 0)
        (effects (font (size 1.27 1.27) (thickness 0.15)) (justify left bottom) hide)
      )
      (property "Value" "GND_23" (id 1) (at 8.89 -5.08 0)
        (effects (font (size 1.27 1.27) (thickness 0.15)) (justify left bottom))
      )
      (property "Footprint" "" (id 2) (at 8.89 -7.62 0)
        (effects (font (size 1.27 1.27) (thickness 0.15)) (justify left bottom) hide)
      )
      (property "Datasheet" "" (id 3) (at 8.89 -12.7 0)
        (effects (font (size 1.27 1.27) (thickness 0.15)) (justify left bottom) hide)
      )
      (property "Author" "Antmicro" (id 4) (at 8.89 -7.62 0)
        (effects (font (size 1.27 1.27) (thickness 0.15)) (justify left bottom) hide)
      )
      (property "License" "Apache-2.0" (id 5) (at 8.89 -10.16 0)
        (effects (font (size 1.27 1.27) (thickness 0.15)) (justify left bottom) hide)
      )
      (symbol "GND_23_1_1"
        (polyline
          (pts
            (xy 0 0)
            (xy 0 -1.27)
            (xy 1.27 -1.27)
            (xy 0 -2.54)
            (xy -1.27 -1.27)
            (xy 0 -1.27)
          )
          (stroke (width 0) (type default) (color 0 0 0 0))
          (fill (type none))
        )
        (pin power_in line (at 0 0 270) (length 0)
          (name "GND" (effects (font (size 1.27 1.27))))
          (number "1" (effects (font (size 1.27 1.27))))
        )
      )
    )
	(symbol "sa800u-baseboard-hw:GND_24" (power) (pin_numbers hide) (pin_names hide) (in_bom yes) (on_board yes)
      (property "Reference" "#PWR" (id 0) (at 8.89 -2.54 0)
        (effects (font (size 1.27 1.27) (thickness 0.15)) (justify left bottom) hide)
      )
      (property "Value" "GND_24" (id 1) (at 8.89 -5.08 0)
        (effects (font (size 1.27 1.27) (thickness 0.15)) (justify left bottom))
      )
      (property "Footprint" "" (id 2) (at 8.89 -7.62 0)
        (effects (font (size 1.27 1.27) (thickness 0.15)) (justify left bottom) hide)
      )
      (property "Datasheet" "" (id 3) (at 8.89 -12.7 0)
        (effects (font (size 1.27 1.27) (thickness 0.15)) (justify left bottom) hide)
      )
      (property "Author" "Antmicro" (id 4) (at 8.89 -7.62 0)
        (effects (font (size 1.27 1.27) (thickness 0.15)) (justify left bottom) hide)
      )
      (property "License" "Apache-2.0" (id 5) (at 8.89 -10.16 0)
        (effects (font (size 1.27 1.27) (thickness 0.15)) (justify left bottom) hide)
      )
      (symbol "GND_24_1_1"
        (polyline
          (pts
            (xy 0 0)
            (xy 0 -1.27)
            (xy 1.27 -1.27)
            (xy 0 -2.54)
            (xy -1.27 -1.27)
            (xy 0 -1.27)
          )
          (stroke (width 0) (type default) (color 0 0 0 0))
          (fill (type none))
        )
        (pin power_in line (at 0 0 270) (length 0)
          (name "GND" (effects (font (size 1.27 1.27))))
          (number "1" (effects (font (size 1.27 1.27))))
        )
      )
    )
	(symbol "sa800u-baseboard-hw:GND_25" (power) (pin_numbers hide) (pin_names hide) (in_bom yes) (on_board yes)
      (property "Reference" "#PWR" (id 0) (at 8.89 -2.54 0)
        (effects (font (size 1.27 1.27) (thickness 0.15)) (justify left bottom) hide)
      )
      (property "Value" "GND_25" (id 1) (at 8.89 -5.08 0)
        (effects (font (size 1.27 1.27) (thickness 0.15)) (justify left bottom))
      )
      (property "Footprint" "" (id 2) (at 8.89 -7.62 0)
        (effects (font (size 1.27 1.27) (thickness 0.15)) (justify left bottom) hide)
      )
      (property "Datasheet" "" (id 3) (at 8.89 -12.7 0)
        (effects (font (size 1.27 1.27) (thickness 0.15)) (justify left bottom) hide)
      )
      (property "Author" "Antmicro" (id 4) (at 8.89 -7.62 0)
        (effects (font (size 1.27 1.27) (thickness 0.15)) (justify left bottom) hide)
      )
      (property "License" "Apache-2.0" (id 5) (at 8.89 -10.16 0)
        (effects (font (size 1.27 1.27) (thickness 0.15)) (justify left bottom) hide)
      )
      (symbol "GND_25_1_1"
        (polyline
          (pts
            (xy 0 0)
            (xy 0 -1.27)
            (xy 1.27 -1.27)
            (xy 0 -2.54)
            (xy -1.27 -1.27)
            (xy 0 -1.27)
          )
          (stroke (width 0) (type default) (color 0 0 0 0))
          (fill (type none))
        )
        (pin power_in line (at 0 0 270) (length 0)
          (name "GND" (effects (font (size 1.27 1.27))))
          (number "1" (effects (font (size 1.27 1.27))))
        )
      )
    )
	(symbol "sa800u-baseboard-hw:GND_26" (power) (pin_numbers hide) (pin_names hide) (in_bom yes) (on_board yes)
      (property "Reference" "#PWR" (id 0) (at 8.89 -2.54 0)
        (effects (font (size 1.27 1.27) (thickness 0.15)) (justify left bottom) hide)
      )
      (property "Value" "GND_26" (id 1) (at 8.89 -5.08 0)
        (effects (font (size 1.27 1.27) (thickness 0.15)) (justify left bottom))
      )
      (property "Footprint" "" (id 2) (at 8.89 -7.62 0)
        (effects (font (size 1.27 1.27) (thickness 0.15)) (justify left bottom) hide)
      )
      (property "Datasheet" "" (id 3) (at 8.89 -12.7 0)
        (effects (font (size 1.27 1.27) (thickness 0.15)) (justify left bottom) hide)
      )
      (property "Author" "Antmicro" (id 4) (at 8.89 -7.62 0)
        (effects (font (size 1.27 1.27) (thickness 0.15)) (justify left bottom) hide)
      )
      (property "License" "Apache-2.0" (id 5) (at 8.89 -10.16 0)
        (effects (font (size 1.27 1.27) (thickness 0.15)) (justify left bottom) hide)
      )
      (symbol "GND_26_1_1"
        (polyline
          (pts
            (xy 0 0)
            (xy 0 -1.27)
            (xy 1.27 -1.27)
            (xy 0 -2.54)
            (xy -1.27 -1.27)
            (xy 0 -1.27)
          )
          (stroke (width 0) (type default) (color 0 0 0 0))
          (fill (type none))
        )
        (pin power_in line (at 0 0 270) (length 0)
          (name "GND" (effects (font (size 1.27 1.27))))
          (number "1" (effects (font (size 1.27 1.27))))
        )
      )
    )
	(symbol "sa800u-baseboard-hw:GND_27" (power) (pin_numbers hide) (pin_names hide) (in_bom yes) (on_board yes)
      (property "Reference" "#PWR" (id 0) (at 8.89 -2.54 0)
        (effects (font (size 1.27 1.27) (thickness 0.15)) (justify left bottom) hide)
      )
      (property "Value" "GND_27" (id 1) (at 8.89 -5.08 0)
        (effects (font (size 1.27 1.27) (thickness 0.15)) (justify left bottom))
      )
      (property "Footprint" "" (id 2) (at 8.89 -7.62 0)
        (effects (font (size 1.27 1.27) (thickness 0.15)) (justify left bottom) hide)
      )
      (property "Datasheet" "" (id 3) (at 8.89 -12.7 0)
        (effects (font (size 1.27 1.27) (thickness 0.15)) (justify left bottom) hide)
      )
      (property "Author" "Antmicro" (id 4) (at 8.89 -7.62 0)
        (effects (font (size 1.27 1.27) (thickness 0.15)) (justify left bottom) hide)
      )
      (property "License" "Apache-2.0" (id 5) (at 8.89 -10.16 0)
        (effects (font (size 1.27 1.27) (thickness 0.15)) (justify left bottom) hide)
      )
      (symbol "GND_27_1_1"
        (polyline
          (pts
            (xy 0 0)
            (xy 0 -1.27)
            (xy 1.27 -1.27)
            (xy 0 -2.54)
            (xy -1.27 -1.27)
            (xy 0 -1.27)
          )
          (stroke (width 0) (type default) (color 0 0 0 0))
          (fill (type none))
        )
        (pin power_in line (at 0 0 270) (length 0)
          (name "GND" (effects (font (size 1.27 1.27))))
          (number "1" (effects (font (size 1.27 1.27))))
        )
      )
    )
	(symbol "sa800u-baseboard-hw:GND_28" (power) (pin_numbers hide) (pin_names hide) (in_bom yes) (on_board yes)
      (property "Reference" "#PWR" (id 0) (at 8.89 -2.54 0)
        (effects (font (size 1.27 1.27) (thickness 0.15)) (justify left bottom) hide)
      )
      (property "Value" "GND_28" (id 1) (at 8.89 -5.08 0)
        (effects (font (size 1.27 1.27) (thickness 0.15)) (justify left bottom))
      )
      (property "Footprint" "" (id 2) (at 8.89 -7.62 0)
        (effects (font (size 1.27 1.27) (thickness 0.15)) (justify left bottom) hide)
      )
      (property "Datasheet" "" (id 3) (at 8.89 -12.7 0)
        (effects (font (size 1.27 1.27) (thickness 0.15)) (justify left bottom) hide)
      )
      (property "Author" "Antmicro" (id 4) (at 8.89 -7.62 0)
        (effects (font (size 1.27 1.27) (thickness 0.15)) (justify left bottom) hide)
      )
      (property "License" "Apache-2.0" (id 5) (at 8.89 -10.16 0)
        (effects (font (size 1.27 1.27) (thickness 0.15)) (justify left bottom) hide)
      )
      (symbol "GND_28_1_1"
        (polyline
          (pts
            (xy 0 0)
            (xy 0 -1.27)
            (xy 1.27 -1.27)
            (xy 0 -2.54)
            (xy -1.27 -1.27)
            (xy 0 -1.27)
          )
          (stroke (width 0) (type default) (color 0 0 0 0))
          (fill (type none))
        )
        (pin power_in line (at 0 0 270) (length 0)
          (name "GND" (effects (font (size 1.27 1.27))))
          (number "1" (effects (font (size 1.27 1.27))))
        )
      )
    )
	(symbol "sa800u-baseboard-hw:GND_29" (power) (pin_numbers hide) (pin_names hide) (in_bom yes) (on_board yes)
      (property "Reference" "#PWR" (id 0) (at 8.89 -2.54 0)
        (effects (font (size 1.27 1.27) (thickness 0.15)) (justify left bottom) hide)
      )
      (property "Value" "GND_29" (id 1) (at 8.89 -5.08 0)
        (effects (font (size 1.27 1.27) (thickness 0.15)) (justify left bottom))
      )
      (property "Footprint" "" (id 2) (at 8.89 -7.62 0)
        (effects (font (size 1.27 1.27) (thickness 0.15)) (justify left bottom) hide)
      )
      (property "Datasheet" "" (id 3) (at 8.89 -12.7 0)
        (effects (font (size 1.27 1.27) (thickness 0.15)) (justify left bottom) hide)
      )
      (property "Author" "Antmicro" (id 4) (at 8.89 -7.62 0)
        (effects (font (size 1.27 1.27) (thickness 0.15)) (justify left bottom) hide)
      )
      (property "License" "Apache-2.0" (id 5) (at 8.89 -10.16 0)
        (effects (font (size 1.27 1.27) (thickness 0.15)) (justify left bottom) hide)
      )
      (symbol "GND_29_1_1"
        (polyline
          (pts
            (xy 0 0)
            (xy 0 -1.27)
            (xy 1.27 -1.27)
            (xy 0 -2.54)
            (xy -1.27 -1.27)
            (xy 0 -1.27)
          )
          (stroke (width 0) (type default) (color 0 0 0 0))
          (fill (type none))
        )
        (pin power_in line (at 0 0 270) (length 0)
          (name "GND" (effects (font (size 1.27 1.27))))
          (number "1" (effects (font (size 1.27 1.27))))
        )
      )
    )
	(symbol "sa800u-baseboard-hw:GND_30" (power) (pin_numbers hide) (pin_names hide) (in_bom yes) (on_board yes)
      (property "Reference" "#PWR" (id 0) (at 8.89 -2.54 0)
        (effects (font (size 1.27 1.27) (thickness 0.15)) (justify left bottom) hide)
      )
      (property "Value" "GND_30" (id 1) (at 8.89 -5.08 0)
        (effects (font (size 1.27 1.27) (thickness 0.15)) (justify left bottom))
      )
      (property "Footprint" "" (id 2) (at 8.89 -7.62 0)
        (effects (font (size 1.27 1.27) (thickness 0.15)) (justify left bottom) hide)
      )
      (property "Datasheet" "" (id 3) (at 8.89 -12.7 0)
        (effects (font (size 1.27 1.27) (thickness 0.15)) (justify left bottom) hide)
      )
      (property "Author" "Antmicro" (id 4) (at 8.89 -7.62 0)
        (effects (font (size 1.27 1.27) (thickness 0.15)) (justify left bottom) hide)
      )
      (property "License" "Apache-2.0" (id 5) (at 8.89 -10.16 0)
        (effects (font (size 1.27 1.27) (thickness 0.15)) (justify left bottom) hide)
      )
      (symbol "GND_30_1_1"
        (polyline
          (pts
            (xy 0 0)
            (xy 0 -1.27)
            (xy 1.27 -1.27)
            (xy 0 -2.54)
            (xy -1.27 -1.27)
            (xy 0 -1.27)
          )
          (stroke (width 0) (type default) (color 0 0 0 0))
          (fill (type none))
        )
        (pin power_in line (at 0 0 270) (length 0)
          (name "GND" (effects (font (size 1.27 1.27))))
          (number "1" (effects (font (size 1.27 1.27))))
        )
      )
    )
	(symbol "sa800u-baseboard-hw:GND_31" (power) (pin_numbers hide) (pin_names hide) (in_bom yes) (on_board yes)
      (property "Reference" "#PWR" (id 0) (at 8.89 -2.54 0)
        (effects (font (size 1.27 1.27) (thickness 0.15)) (justify left bottom) hide)
      )
      (property "Value" "GND_31" (id 1) (at 8.89 -5.08 0)
        (effects (font (size 1.27 1.27) (thickness 0.15)) (justify left bottom))
      )
      (property "Footprint" "" (id 2) (at 8.89 -7.62 0)
        (effects (font (size 1.27 1.27) (thickness 0.15)) (justify left bottom) hide)
      )
      (property "Datasheet" "" (id 3) (at 8.89 -12.7 0)
        (effects (font (size 1.27 1.27) (thickness 0.15)) (justify left bottom) hide)
      )
      (property "Author" "Antmicro" (id 4) (at 8.89 -7.62 0)
        (effects (font (size 1.27 1.27) (thickness 0.15)) (justify left bottom) hide)
      )
      (property "License" "Apache-2.0" (id 5) (at 8.89 -10.16 0)
        (effects (font (size 1.27 1.27) (thickness 0.15)) (justify left bottom) hide)
      )
      (symbol "GND_31_1_1"
        (polyline
          (pts
            (xy 0 0)
            (xy 0 -1.27)
            (xy 1.27 -1.27)
            (xy 0 -2.54)
            (xy -1.27 -1.27)
            (xy 0 -1.27)
          )
          (stroke (width 0) (type default) (color 0 0 0 0))
          (fill (type none))
        )
        (pin power_in line (at 0 0 270) (length 0)
          (name "GND" (effects (font (size 1.27 1.27))))
          (number "1" (effects (font (size 1.27 1.27))))
        )
      )
    )
	(symbol "sa800u-baseboard-hw:GND_32" (power) (pin_numbers hide) (pin_names hide) (in_bom yes) (on_board yes)
      (property "Reference" "#PWR" (id 0) (at 8.89 -2.54 0)
        (effects (font (size 1.27 1.27) (thickness 0.15)) (justify left bottom) hide)
      )
      (property "Value" "GND_32" (id 1) (at 8.89 -5.08 0)
        (effects (font (size 1.27 1.27) (thickness 0.15)) (justify left bottom))
      )
      (property "Footprint" "" (id 2) (at 8.89 -7.62 0)
        (effects (font (size 1.27 1.27) (thickness 0.15)) (justify left bottom) hide)
      )
      (property "Datasheet" "" (id 3) (at 8.89 -12.7 0)
        (effects (font (size 1.27 1.27) (thickness 0.15)) (justify left bottom) hide)
      )
      (property "Author" "Antmicro" (id 4) (at 8.89 -7.62 0)
        (effects (font (size 1.27 1.27) (thickness 0.15)) (justify left bottom) hide)
      )
      (property "License" "Apache-2.0" (id 5) (at 8.89 -10.16 0)
        (effects (font (size 1.27 1.27) (thickness 0.15)) (justify left bottom) hide)
      )
      (symbol "GND_32_1_1"
        (polyline
          (pts
            (xy 0 0)
            (xy 0 -1.27)
            (xy 1.27 -1.27)
            (xy 0 -2.54)
            (xy -1.27 -1.27)
            (xy 0 -1.27)
          )
          (stroke (width 0) (type default) (color 0 0 0 0))
          (fill (type none))
        )
        (pin power_in line (at 0 0 270) (length 0)
          (name "GND" (effects (font (size 1.27 1.27))))
          (number "1" (effects (font (size 1.27 1.27))))
        )
      )
    )
	(symbol "sa800u-baseboard-hw:GND_33" (power) (pin_numbers hide) (pin_names hide) (in_bom yes) (on_board yes)
      (property "Reference" "#PWR" (id 0) (at 8.89 -2.54 0)
        (effects (font (size 1.27 1.27) (thickness 0.15)) (justify left bottom) hide)
      )
      (property "Value" "GND_33" (id 1) (at 8.89 -5.08 0)
        (effects (font (size 1.27 1.27) (thickness 0.15)) (justify left bottom))
      )
      (property "Footprint" "" (id 2) (at 8.89 -7.62 0)
        (effects (font (size 1.27 1.27) (thickness 0.15)) (justify left bottom) hide)
      )
      (property "Datasheet" "" (id 3) (at 8.89 -12.7 0)
        (effects (font (size 1.27 1.27) (thickness 0.15)) (justify left bottom) hide)
      )
      (property "Author" "Antmicro" (id 4) (at 8.89 -7.62 0)
        (effects (font (size 1.27 1.27) (thickness 0.15)) (justify left bottom) hide)
      )
      (property "License" "Apache-2.0" (id 5) (at 8.89 -10.16 0)
        (effects (font (size 1.27 1.27) (thickness 0.15)) (justify left bottom) hide)
      )
      (symbol "GND_33_1_1"
        (polyline
          (pts
            (xy 0 0)
            (xy 0 -1.27)
            (xy 1.27 -1.27)
            (xy 0 -2.54)
            (xy -1.27 -1.27)
            (xy 0 -1.27)
          )
          (stroke (width 0) (type default) (color 0 0 0 0))
          (fill (type none))
        )
        (pin power_in line (at 0 0 270) (length 0)
          (name "GND" (effects (font (size 1.27 1.27))))
          (number "1" (effects (font (size 1.27 1.27))))
        )
      )
    )
	(symbol "sa800u-baseboard-hw:GND_34" (power) (pin_numbers hide) (pin_names hide) (in_bom yes) (on_board yes)
      (property "Reference" "#PWR" (id 0) (at 8.89 -2.54 0)
        (effects (font (size 1.27 1.27) (thickness 0.15)) (justify left bottom) hide)
      )
      (property "Value" "GND_34" (id 1) (at 8.89 -5.08 0)
        (effects (font (size 1.27 1.27) (thickness 0.15)) (justify left bottom))
      )
      (property "Footprint" "" (id 2) (at 8.89 -7.62 0)
        (effects (font (size 1.27 1.27) (thickness 0.15)) (justify left bottom) hide)
      )
      (property "Datasheet" "" (id 3) (at 8.89 -12.7 0)
        (effects (font (size 1.27 1.27) (thickness 0.15)) (justify left bottom) hide)
      )
      (property "Author" "Antmicro" (id 4) (at 8.89 -7.62 0)
        (effects (font (size 1.27 1.27) (thickness 0.15)) (justify left bottom) hide)
      )
      (property "License" "Apache-2.0" (id 5) (at 8.89 -10.16 0)
        (effects (font (size 1.27 1.27) (thickness 0.15)) (justify left bottom) hide)
      )
      (symbol "GND_34_1_1"
        (polyline
          (pts
            (xy 0 0)
            (xy 0 -1.27)
            (xy 1.27 -1.27)
            (xy 0 -2.54)
            (xy -1.27 -1.27)
            (xy 0 -1.27)
          )
          (stroke (width 0) (type default) (color 0 0 0 0))
          (fill (type none))
        )
        (pin power_in line (at 0 0 270) (length 0)
          (name "GND" (effects (font (size 1.27 1.27))))
          (number "1" (effects (font (size 1.27 1.27))))
        )
      )
    )
	(symbol "sa800u-baseboard-hw:GND_35" (power) (pin_numbers hide) (pin_names hide) (in_bom yes) (on_board yes)
      (property "Reference" "#PWR" (id 0) (at 8.89 -2.54 0)
        (effects (font (size 1.27 1.27) (thickness 0.15)) (justify left bottom) hide)
      )
      (property "Value" "GND_35" (id 1) (at 8.89 -5.08 0)
        (effects (font (size 1.27 1.27) (thickness 0.15)) (justify left bottom))
      )
      (property "Footprint" "" (id 2) (at 8.89 -7.62 0)
        (effects (font (size 1.27 1.27) (thickness 0.15)) (justify left bottom) hide)
      )
      (property "Datasheet" "" (id 3) (at 8.89 -12.7 0)
        (effects (font (size 1.27 1.27) (thickness 0.15)) (justify left bottom) hide)
      )
      (property "Author" "Antmicro" (id 4) (at 8.89 -7.62 0)
        (effects (font (size 1.27 1.27) (thickness 0.15)) (justify left bottom) hide)
      )
      (property "License" "Apache-2.0" (id 5) (at 8.89 -10.16 0)
        (effects (font (size 1.27 1.27) (thickness 0.15)) (justify left bottom) hide)
      )
      (symbol "GND_35_1_1"
        (polyline
          (pts
            (xy 0 0)
            (xy 0 -1.27)
            (xy 1.27 -1.27)
            (xy 0 -2.54)
            (xy -1.27 -1.27)
            (xy 0 -1.27)
          )
          (stroke (width 0) (type default) (color 0 0 0 0))
          (fill (type none))
        )
        (pin power_in line (at 0 0 270) (length 0)
          (name "GND" (effects (font (size 1.27 1.27))))
          (number "1" (effects (font (size 1.27 1.27))))
        )
      )
    )
	(symbol "sa800u-baseboard-hw:GND_36" (power) (pin_numbers hide) (pin_names hide) (in_bom yes) (on_board yes)
      (property "Reference" "#PWR" (id 0) (at 8.89 -2.54 0)
        (effects (font (size 1.27 1.27) (thickness 0.15)) (justify left bottom) hide)
      )
      (property "Value" "GND_36" (id 1) (at 8.89 -5.08 0)
        (effects (font (size 1.27 1.27) (thickness 0.15)) (justify left bottom))
      )
      (property "Footprint" "" (id 2) (at 8.89 -7.62 0)
        (effects (font (size 1.27 1.27) (thickness 0.15)) (justify left bottom) hide)
      )
      (property "Datasheet" "" (id 3) (at 8.89 -12.7 0)
        (effects (font (size 1.27 1.27) (thickness 0.15)) (justify left bottom) hide)
      )
      (property "Author" "Antmicro" (id 4) (at 8.89 -7.62 0)
        (effects (font (size 1.27 1.27) (thickness 0.15)) (justify left bottom) hide)
      )
      (property "License" "Apache-2.0" (id 5) (at 8.89 -10.16 0)
        (effects (font (size 1.27 1.27) (thickness 0.15)) (justify left bottom) hide)
      )
      (symbol "GND_36_1_1"
        (polyline
          (pts
            (xy 0 0)
            (xy 0 -1.27)
            (xy 1.27 -1.27)
            (xy 0 -2.54)
            (xy -1.27 -1.27)
            (xy 0 -1.27)
          )
          (stroke (width 0) (type default) (color 0 0 0 0))
          (fill (type none))
        )
        (pin power_in line (at 0 0 270) (length 0)
          (name "GND" (effects (font (size 1.27 1.27))))
          (number "1" (effects (font (size 1.27 1.27))))
        )
      )
    )
	(symbol "sa800u-baseboard-hw:GND_37" (power) (pin_numbers hide) (pin_names hide) (in_bom yes) (on_board yes)
      (property "Reference" "#PWR" (id 0) (at 8.89 -2.54 0)
        (effects (font (size 1.27 1.27) (thickness 0.15)) (justify left bottom) hide)
      )
      (property "Value" "GND_37" (id 1) (at 8.89 -5.08 0)
        (effects (font (size 1.27 1.27) (thickness 0.15)) (justify left bottom))
      )
      (property "Footprint" "" (id 2) (at 8.89 -7.62 0)
        (effects (font (size 1.27 1.27) (thickness 0.15)) (justify left bottom) hide)
      )
      (property "Datasheet" "" (id 3) (at 8.89 -12.7 0)
        (effects (font (size 1.27 1.27) (thickness 0.15)) (justify left bottom) hide)
      )
      (property "Author" "Antmicro" (id 4) (at 8.89 -7.62 0)
        (effects (font (size 1.27 1.27) (thickness 0.15)) (justify left bottom) hide)
      )
      (property "License" "Apache-2.0" (id 5) (at 8.89 -10.16 0)
        (effects (font (size 1.27 1.27) (thickness 0.15)) (justify left bottom) hide)
      )
      (symbol "GND_37_1_1"
        (polyline
          (pts
            (xy 0 0)
            (xy 0 -1.27)
            (xy 1.27 -1.27)
            (xy 0 -2.54)
            (xy -1.27 -1.27)
            (xy 0 -1.27)
          )
          (stroke (width 0) (type default) (color 0 0 0 0))
          (fill (type none))
        )
        (pin power_in line (at 0 0 270) (length 0)
          (name "GND" (effects (font (size 1.27 1.27))))
          (number "1" (effects (font (size 1.27 1.27))))
        )
      )
    )
	(symbol "sa800u-baseboard-hw:GND_38" (power) (pin_numbers hide) (pin_names hide) (in_bom yes) (on_board yes)
      (property "Reference" "#PWR" (id 0) (at 8.89 -2.54 0)
        (effects (font (size 1.27 1.27) (thickness 0.15)) (justify left bottom) hide)
      )
      (property "Value" "GND_38" (id 1) (at 8.89 -5.08 0)
        (effects (font (size 1.27 1.27) (thickness 0.15)) (justify left bottom))
      )
      (property "Footprint" "" (id 2) (at 8.89 -7.62 0)
        (effects (font (size 1.27 1.27) (thickness 0.15)) (justify left bottom) hide)
      )
      (property "Datasheet" "" (id 3) (at 8.89 -12.7 0)
        (effects (font (size 1.27 1.27) (thickness 0.15)) (justify left bottom) hide)
      )
      (property "Author" "Antmicro" (id 4) (at 8.89 -7.62 0)
        (effects (font (size 1.27 1.27) (thickness 0.15)) (justify left bottom) hide)
      )
      (property "License" "Apache-2.0" (id 5) (at 8.89 -10.16 0)
        (effects (font (size 1.27 1.27) (thickness 0.15)) (justify left bottom) hide)
      )
      (symbol "GND_38_1_1"
        (polyline
          (pts
            (xy 0 0)
            (xy 0 -1.27)
            (xy 1.27 -1.27)
            (xy 0 -2.54)
            (xy -1.27 -1.27)
            (xy 0 -1.27)
          )
          (stroke (width 0) (type default) (color 0 0 0 0))
          (fill (type none))
        )
        (pin power_in line (at 0 0 270) (length 0)
          (name "GND" (effects (font (size 1.27 1.27))))
          (number "1" (effects (font (size 1.27 1.27))))
        )
      )
    )
	(symbol "sa800u-baseboard-hw:GND_39" (power) (pin_numbers hide) (pin_names hide) (in_bom yes) (on_board yes)
      (property "Reference" "#PWR" (id 0) (at 8.89 -2.54 0)
        (effects (font (size 1.27 1.27) (thickness 0.15)) (justify left bottom) hide)
      )
      (property "Value" "GND_39" (id 1) (at 8.89 -5.08 0)
        (effects (font (size 1.27 1.27) (thickness 0.15)) (justify left bottom))
      )
      (property "Footprint" "" (id 2) (at 8.89 -7.62 0)
        (effects (font (size 1.27 1.27) (thickness 0.15)) (justify left bottom) hide)
      )
      (property "Datasheet" "" (id 3) (at 8.89 -12.7 0)
        (effects (font (size 1.27 1.27) (thickness 0.15)) (justify left bottom) hide)
      )
      (property "Author" "Antmicro" (id 4) (at 8.89 -7.62 0)
        (effects (font (size 1.27 1.27) (thickness 0.15)) (justify left bottom) hide)
      )
      (property "License" "Apache-2.0" (id 5) (at 8.89 -10.16 0)
        (effects (font (size 1.27 1.27) (thickness 0.15)) (justify left bottom) hide)
      )
      (symbol "GND_39_1_1"
        (polyline
          (pts
            (xy 0 0)
            (xy 0 -1.27)
            (xy 1.27 -1.27)
            (xy 0 -2.54)
            (xy -1.27 -1.27)
            (xy 0 -1.27)
          )
          (stroke (width 0) (type default) (color 0 0 0 0))
          (fill (type none))
        )
        (pin power_in line (at 0 0 270) (length 0)
          (name "GND" (effects (font (size 1.27 1.27))))
          (number "1" (effects (font (size 1.27 1.27))))
        )
      )
    )
	(symbol "sa800u-baseboard-hw:GND_40" (power) (pin_numbers hide) (pin_names hide) (in_bom yes) (on_board yes)
      (property "Reference" "#PWR" (id 0) (at 8.89 -2.54 0)
        (effects (font (size 1.27 1.27) (thickness 0.15)) (justify left bottom) hide)
      )
      (property "Value" "GND_40" (id 1) (at 8.89 -5.08 0)
        (effects (font (size 1.27 1.27) (thickness 0.15)) (justify left bottom))
      )
      (property "Footprint" "" (id 2) (at 8.89 -7.62 0)
        (effects (font (size 1.27 1.27) (thickness 0.15)) (justify left bottom) hide)
      )
      (property "Datasheet" "" (id 3) (at 8.89 -12.7 0)
        (effects (font (size 1.27 1.27) (thickness 0.15)) (justify left bottom) hide)
      )
      (property "Author" "Antmicro" (id 4) (at 8.89 -7.62 0)
        (effects (font (size 1.27 1.27) (thickness 0.15)) (justify left bottom) hide)
      )
      (property "License" "Apache-2.0" (id 5) (at 8.89 -10.16 0)
        (effects (font (size 1.27 1.27) (thickness 0.15)) (justify left bottom) hide)
      )
      (symbol "GND_40_1_1"
        (polyline
          (pts
            (xy 0 0)
            (xy 0 -1.27)
            (xy 1.27 -1.27)
            (xy 0 -2.54)
            (xy -1.27 -1.27)
            (xy 0 -1.27)
          )
          (stroke (width 0) (type default) (color 0 0 0 0))
          (fill (type none))
        )
        (pin power_in line (at 0 0 270) (length 0)
          (name "GND" (effects (font (size 1.27 1.27))))
          (number "1" (effects (font (size 1.27 1.27))))
        )
      )
    )
	(symbol "sa800u-baseboard-hw:GND_41" (power) (pin_numbers hide) (pin_names hide) (in_bom yes) (on_board yes)
      (property "Reference" "#PWR" (id 0) (at 8.89 -2.54 0)
        (effects (font (size 1.27 1.27) (thickness 0.15)) (justify left bottom) hide)
      )
      (property "Value" "GND_41" (id 1) (at 8.89 -5.08 0)
        (effects (font (size 1.27 1.27) (thickness 0.15)) (justify left bottom))
      )
      (property "Footprint" "" (id 2) (at 8.89 -7.62 0)
        (effects (font (size 1.27 1.27) (thickness 0.15)) (justify left bottom) hide)
      )
      (property "Datasheet" "" (id 3) (at 8.89 -12.7 0)
        (effects (font (size 1.27 1.27) (thickness 0.15)) (justify left bottom) hide)
      )
      (property "Author" "Antmicro" (id 4) (at 8.89 -7.62 0)
        (effects (font (size 1.27 1.27) (thickness 0.15)) (justify left bottom) hide)
      )
      (property "License" "Apache-2.0" (id 5) (at 8.89 -10.16 0)
        (effects (font (size 1.27 1.27) (thickness 0.15)) (justify left bottom) hide)
      )
      (symbol "GND_41_1_1"
        (polyline
          (pts
            (xy 0 0)
            (xy 0 -1.27)
            (xy 1.27 -1.27)
            (xy 0 -2.54)
            (xy -1.27 -1.27)
            (xy 0 -1.27)
          )
          (stroke (width 0) (type default) (color 0 0 0 0))
          (fill (type none))
        )
        (pin power_in line (at 0 0 270) (length 0)
          (name "GND" (effects (font (size 1.27 1.27))))
          (number "1" (effects (font (size 1.27 1.27))))
        )
      )
    )
	(symbol "sa800u-baseboard-hw:GND_42" (power) (pin_numbers hide) (pin_names hide) (in_bom yes) (on_board yes)
      (property "Reference" "#PWR" (id 0) (at 8.89 -2.54 0)
        (effects (font (size 1.27 1.27) (thickness 0.15)) (justify left bottom) hide)
      )
      (property "Value" "GND_42" (id 1) (at 8.89 -5.08 0)
        (effects (font (size 1.27 1.27) (thickness 0.15)) (justify left bottom))
      )
      (property "Footprint" "" (id 2) (at 8.89 -7.62 0)
        (effects (font (size 1.27 1.27) (thickness 0.15)) (justify left bottom) hide)
      )
      (property "Datasheet" "" (id 3) (at 8.89 -12.7 0)
        (effects (font (size 1.27 1.27) (thickness 0.15)) (justify left bottom) hide)
      )
      (property "Author" "Antmicro" (id 4) (at 8.89 -7.62 0)
        (effects (font (size 1.27 1.27) (thickness 0.15)) (justify left bottom) hide)
      )
      (property "License" "Apache-2.0" (id 5) (at 8.89 -10.16 0)
        (effects (font (size 1.27 1.27) (thickness 0.15)) (justify left bottom) hide)
      )
      (symbol "GND_42_1_1"
        (polyline
          (pts
            (xy 0 0)
            (xy 0 -1.27)
            (xy 1.27 -1.27)
            (xy 0 -2.54)
            (xy -1.27 -1.27)
            (xy 0 -1.27)
          )
          (stroke (width 0) (type default) (color 0 0 0 0))
          (fill (type none))
        )
        (pin power_in line (at 0 0 270) (length 0)
          (name "GND" (effects (font (size 1.27 1.27))))
          (number "1" (effects (font (size 1.27 1.27))))
        )
      )
    )
	(symbol "sa800u-baseboard-hw:GND_43" (power) (pin_numbers hide) (pin_names hide) (in_bom yes) (on_board yes)
      (property "Reference" "#PWR" (id 0) (at 8.89 -2.54 0)
        (effects (font (size 1.27 1.27) (thickness 0.15)) (justify left bottom) hide)
      )
      (property "Value" "GND_43" (id 1) (at 8.89 -5.08 0)
        (effects (font (size 1.27 1.27) (thickness 0.15)) (justify left bottom))
      )
      (property "Footprint" "" (id 2) (at 8.89 -7.62 0)
        (effects (font (size 1.27 1.27) (thickness 0.15)) (justify left bottom) hide)
      )
      (property "Datasheet" "" (id 3) (at 8.89 -12.7 0)
        (effects (font (size 1.27 1.27) (thickness 0.15)) (justify left bottom) hide)
      )
      (property "Author" "Antmicro" (id 4) (at 8.89 -7.62 0)
        (effects (font (size 1.27 1.27) (thickness 0.15)) (justify left bottom) hide)
      )
      (property "License" "Apache-2.0" (id 5) (at 8.89 -10.16 0)
        (effects (font (size 1.27 1.27) (thickness 0.15)) (justify left bottom) hide)
      )
      (symbol "GND_43_1_1"
        (polyline
          (pts
            (xy 0 0)
            (xy 0 -1.27)
            (xy 1.27 -1.27)
            (xy 0 -2.54)
            (xy -1.27 -1.27)
            (xy 0 -1.27)
          )
          (stroke (width 0) (type default) (color 0 0 0 0))
          (fill (type none))
        )
        (pin power_in line (at 0 0 270) (length 0)
          (name "GND" (effects (font (size 1.27 1.27))))
          (number "1" (effects (font (size 1.27 1.27))))
        )
      )
    )
	(symbol "sa800u-baseboard-hw:HDMI_Micro-D_46756-1001" (in_bom yes) (on_board yes)
      (property "Reference" "J" (id 0) (at 38.1 -2.54 0)
        (effects (font (size 1.27 1.27) (thickness 0.15)) (justify left bottom))
      )
      (property "Value" "HDMI_Micro-D_46756-1001" (id 1) (at 38.1 -5.08 0)
        (effects (font (size 1.27 1.27) (thickness 0.15)) (justify left bottom))
      )
      (property "Footprint" "antmicro-footprints:HDMI_Micro-D_Molex_46765-1x01" (id 2) (at 38.1 -7.62 0)
        (effects (font (size 1.27 1.27) (thickness 0.15)) (justify left bottom) hide)
      )
      (property "Datasheet" "https://www.molex.com/webdocs/datasheets/pdf/en-us/0467651001_IO_CONNECTORS.pdf" (id 3) (at 38.1 -10.16 0)
        (effects (font (size 1.27 1.27) (thickness 0.15)) (justify left bottom) hide)
      )
      (property "MPN" "467651001" (id 4) (at 38.1 -12.7 0)
        (effects (font (size 1.27 1.27) (thickness 0.15)) (justify left bottom) hide)
      )
      (property "Manufacturer" "Molex" (id 5) (at 38.1 -15.24 0)
        (effects (font (size 1.27 1.27) (thickness 0.15)) (justify left bottom) hide)
      )
      (property "Author" "Antmicro" (id 6) (at 38.1 -17.78 0)
        (effects (font (size 1.27 1.27) (thickness 0.15)) (justify left bottom) hide)
      )
      (property "License" "Apache-2.0" (id 7) (at 38.1 -20.32 0)
        (effects (font (size 1.27 1.27) (thickness 0.15)) (justify left bottom) hide)
      )
      (property "ki_keywords" "Micro HDMI" (id 8) (at 0 0 0)
        (effects (font (size 1.27 1.27)) hide)
      )
      (property "ki_description" "Micro HDMI Connector, Right-Angle Receptacle" (id 9) (at 0 0 0)
        (effects (font (size 1.27 1.27)) hide)
      )
      (symbol "HDMI_Micro-D_46756-1001_0_0"
        (polyline
          (pts
            (xy 18.923 -5.08)
            (xy 18.923 -3.556)
          )
          (stroke (width 0.635) (type default) (color 0 0 0 0))
          (fill (type none))
        )
        (polyline
          (pts
            (xy 10.795 -5.08)
            (xy 10.795 -3.556)
            (xy 10.795 -4.318)
            (xy 12.7 -4.318)
            (xy 12.7 -3.556)
            (xy 12.7 -5.08)
          )
          (stroke (width 0.635) (type default) (color 0 0 0 0))
          (fill (type none))
        )
        (polyline
          (pts
            (xy 13.462 -3.556)
            (xy 15.113 -3.556)
            (xy 15.367 -3.81)
            (xy 15.367 -4.826)
            (xy 15.113 -5.08)
            (xy 13.462 -5.08)
            (xy 13.462 -4.318)
          )
          (stroke (width 0.635) (type default) (color 0 0 0 0))
          (fill (type none))
        )
        (text "micro" (at 14.605 -6.35 0)
          (effects (font (size 1.27 1.27) (thickness 0.15)) (justify left bottom))
        )
      )
      (symbol "HDMI_Micro-D_46756-1001_0_1"
        (polyline
          (pts
            (xy 16.129 -5.08)
            (xy 16.129 -3.556)
            (xy 17.145 -3.556)
            (xy 17.145 -5.08)
            (xy 17.145 -3.556)
            (xy 17.907 -3.556)
            (xy 18.161 -3.81)
            (xy 18.161 -5.08)
          )
          (stroke (width 0.635) (type default) (color 0 0 0 0))
          (fill (type none))
        )
      )
      (symbol "HDMI_Micro-D_46756-1001_1_1"
        (polyline
          (pts
            (xy 11.43 -13.97)
            (xy 15.24 -13.97)
            (xy 17.145 -15.875)
            (xy 17.145 -27.305)
            (xy 15.24 -29.21)
            (xy 11.43 -29.21)
            (xy 11.43 -13.97)
          )
          (stroke (width 0.254) (type default) (color 0 0 0 0))
          (fill (type background))
        )
        (polyline
          (pts
            (xy 13.335 -15.24)
            (xy 14.605 -15.24)
            (xy 15.24 -15.875)
            (xy 15.24 -27.305)
            (xy 14.605 -27.94)
            (xy 13.335 -27.94)
            (xy 13.335 -15.24)
          )
          (stroke (width 0.254) (type default) (color 0 0 0 0))
          (fill (type outline))
        )
        (rectangle (start 2.54 2.54) (end 22.86 -53.34)
          (stroke (width 0.254) (type default) (color 0 0 0 0))
          (fill (type background))
        )
        (pin passive line (at 0 -43.18 0) (length 2.54)
          (name "HPD/HEAC-" (effects (font (size 1.27 1.27))))
          (number "1" (effects (font (size 1.27 1.27))))
          (alternate "HEAC-" passive line)
          (alternate "HPD" passive line)
        )
        (pin power_in line (at 25.4 -43.18 180) (length 2.54)
          (name "D0S" (effects (font (size 1.27 1.27))))
          (number "10" (effects (font (size 1.27 1.27))))
        )
        (pin passive line (at 0 -17.78 0) (length 2.54)
          (name "D0-" (effects (font (size 1.27 1.27))))
          (number "11" (effects (font (size 1.27 1.27))))
        )
        (pin passive line (at 0 -22.86 0) (length 2.54)
          (name "CK+" (effects (font (size 1.27 1.27))))
          (number "12" (effects (font (size 1.27 1.27))))
        )
        (pin power_in line (at 25.4 -45.72 180) (length 2.54)
          (name "CKS" (effects (font (size 1.27 1.27))))
          (number "13" (effects (font (size 1.27 1.27))))
        )
        (pin passive line (at 0 -25.4 0) (length 2.54)
          (name "CK-" (effects (font (size 1.27 1.27))))
          (number "14" (effects (font (size 1.27 1.27))))
        )
        (pin bidirectional line (at 0 -38.1 0) (length 2.54)
          (name "CEC" (effects (font (size 1.27 1.27))))
          (number "15" (effects (font (size 1.27 1.27))))
        )
        (pin power_in line (at 25.4 -48.26 180) (length 2.54)
          (name "GND" (effects (font (size 1.27 1.27))))
          (number "16" (effects (font (size 1.27 1.27))))
        )
        (pin passive line (at 0 -30.48 0) (length 2.54)
          (name "SCL" (effects (font (size 1.27 1.27))))
          (number "17" (effects (font (size 1.27 1.27))))
        )
        (pin bidirectional line (at 0 -33.02 0) (length 2.54)
          (name "SDA" (effects (font (size 1.27 1.27))))
          (number "18" (effects (font (size 1.27 1.27))))
        )
        (pin power_in line (at 0 -50.8 0) (length 2.54)
          (name "+5V" (effects (font (size 1.27 1.27))))
          (number "19" (effects (font (size 1.27 1.27))))
        )
        (pin passive line (at 0 -45.72 0) (length 2.54)
          (name "UTILITY/HEAC+" (effects (font (size 1.27 1.27))))
          (number "2" (effects (font (size 1.27 1.27))))
          (alternate "HEAC+" passive line)
          (alternate "UTILITY" passive line)
        )
        (pin passive line (at 0 0 0) (length 2.54)
          (name "D2+" (effects (font (size 1.27 1.27))))
          (number "3" (effects (font (size 1.27 1.27))))
        )
        (pin power_in line (at 25.4 -38.1 180) (length 2.54)
          (name "D2S" (effects (font (size 1.27 1.27))))
          (number "4" (effects (font (size 1.27 1.27))))
        )
        (pin passive line (at 0 -2.54 0) (length 2.54)
          (name "D2-" (effects (font (size 1.27 1.27))))
          (number "5" (effects (font (size 1.27 1.27))))
        )
        (pin passive line (at 0 -7.62 0) (length 2.54)
          (name "D1+" (effects (font (size 1.27 1.27))))
          (number "6" (effects (font (size 1.27 1.27))))
        )
        (pin power_in line (at 25.4 -40.64 180) (length 2.54)
          (name "D1S" (effects (font (size 1.27 1.27))))
          (number "7" (effects (font (size 1.27 1.27))))
        )
        (pin passive line (at 0 -10.16 0) (length 2.54)
          (name "D1-" (effects (font (size 1.27 1.27))))
          (number "8" (effects (font (size 1.27 1.27))))
        )
        (pin passive line (at 0 -15.24 0) (length 2.54)
          (name "D0+" (effects (font (size 1.27 1.27))))
          (number "9" (effects (font (size 1.27 1.27))))
        )
        (pin passive line (at 25.4 -50.8 180) (length 2.54)
          (name "SH" (effects (font (size 1.27 1.27))))
          (number "SH" (effects (font (size 1.27 1.27))))
        )
      )
    )
	(symbol "sa800u-baseboard-hw:LED_G_0603_KP-1608ZGC" (pin_names hide) (in_bom yes) (on_board yes)
      (property "Reference" "D" (id 0) (at 22.86 -5.08 0)
        (effects (font (size 1.27 1.27) (thickness 0.15)) (justify left bottom))
      )
      (property "Value" "LED_G_0603_KP-1608ZGC" (id 1) (at 22.86 -7.62 0)
        (effects (font (size 1.27 1.27) (thickness 0.15)) (justify left bottom))
      )
      (property "Footprint" "sa800u-baseboard-hw-footprints:LED_0603_1608Metric_G" (id 2) (at 22.86 -10.16 0)
        (effects (font (size 1.27 1.27) (thickness 0.15)) (justify left bottom) hide)
      )
      (property "Datasheet" "https://www.farnell.com/datasheets/2045914.pdf" (id 3) (at 22.86 -12.7 0)
        (effects (font (size 1.27 1.27) (thickness 0.15)) (justify left bottom) hide)
      )
      (property "MPN" "KP-1608ZGC" (id 4) (at 22.86 -15.24 0)
        (effects (font (size 1.27 1.27) (thickness 0.15)) (justify left bottom) hide)
      )
      (property "Manufacturer" "Kingbright" (id 5) (at 22.86 -17.78 0)
        (effects (font (size 1.27 1.27) (thickness 0.15)) (justify left bottom) hide)
      )
      (property "Author" "Antmicro" (id 6) (at 22.86 -20.32 0)
        (effects (font (size 1.27 1.27) (thickness 0.15)) (justify left bottom) hide)
      )
      (property "License" "Apache-2.0" (id 7) (at 22.86 -22.86 0)
        (effects (font (size 1.27 1.27) (thickness 0.15)) (justify left bottom) hide)
      )
      (property "ki_description" "Red, 0603, 20mA" (id 8) (at 0 0 0)
        (effects (font (size 1.27 1.27)) hide)
      )
      (symbol "LED_G_0603_KP-1608ZGC_1_1"
        (polyline
          (pts
            (xy 5.08 1.27)
            (xy 5.08 -1.27)
          )
          (stroke (width 0.254) (type default) (color 0 0 0 0))
          (fill (type none))
        )
        (polyline
          (pts
            (xy 2.54 1.27)
            (xy 2.54 -1.27)
            (xy 5.08 0)
            (xy 2.54 1.27)
          )
          (stroke (width 0.254) (type default) (color 0 0 0 0))
          (fill (type outline))
        )
        (polyline
          (pts
            (xy 3.683 2.286)
            (xy 3.683 1.778)
            (xy 3.683 2.286)
            (xy 3.175 2.286)
            (xy 3.683 2.286)
            (xy 2.794 1.397)
          )
          (stroke (width 0.254) (type default) (color 0 0 0 0))
          (fill (type none))
        )
        (polyline
          (pts
            (xy 4.699 2.032)
            (xy 4.699 1.524)
            (xy 4.699 2.032)
            (xy 4.191 2.032)
            (xy 4.699 2.032)
            (xy 3.683 1.016)
          )
          (stroke (width 0.254) (type default) (color 0 0 0 0))
          (fill (type none))
        )
        (pin passive line (at 0 0 0) (length 2.54)
          (name "1" (effects (font (size 1.27 1.27))))
          (number "1" (effects (font (size 1.27 1.27))))
        )
        (pin passive line (at 7.62 0 180) (length 2.54)
          (name "2" (effects (font (size 1.27 1.27))))
          (number "2" (effects (font (size 1.27 1.27))))
        )
      )
    )
	(symbol "sa800u-baseboard-hw:LMV431_SOT-23-5" (in_bom yes) (on_board yes)
      (property "Reference" "U" (id 0) (at 11.43 -3.81 0)
        (effects (font (size 1.27 1.27) (thickness 0.15)) (justify left bottom))
      )
      (property "Value" "LMV431_SOT-23-5" (id 1) (at 11.43 -8.89 0)
        (effects (font (size 1.27 1.27) (thickness 0.15)) (justify left bottom) hide)
      )
      (property "Footprint" "sa800u-baseboard-hw-footprints:SOT-23-5" (id 2) (at 11.43 -11.43 0)
        (effects (font (size 1.27 1.27) (thickness 0.15)) (justify left bottom) hide)
      )
      (property "Datasheet" "https://www.ti.com/lit/ds/symlink/lmv431a.pdf?HQS=dis-dk-null-digikeymode-dsf-pf-null-wwe&ts=1640859539059&ref_url=https%253A%252F%252Fwww.ti.com%252Fgeneral%252Fdocs%252Fsuppproductinfo.tsp%253FdistId%253D10%2526gotoUrl%253Dhttps%253A%252F%252Fwww.ti.com%252Flit%252Fgpn%252Flmv431a" (id 3) (at 11.43 -13.97 0)
        (effects (font (size 1.27 1.27) (thickness 0.15)) (justify left bottom) hide)
      )
      (property "MPN" "LMV431IM5" (id 4) (at 11.43 -6.35 0)
        (effects (font (size 1.27 1.27) (thickness 0.15)) (justify left bottom))
      )
      (property "Manufacturer" "Texas Instruments" (id 5) (at 11.43 -16.51 0)
        (effects (font (size 1.27 1.27) (thickness 0.15)) (justify left bottom) hide)
      )
      (property "Author" "Antmicro" (id 6) (at 11.43 -19.05 0)
        (effects (font (size 1.27 1.27) (thickness 0.15)) (justify left bottom) hide)
      )
      (property "License" "Apache-2.0" (id 7) (at 11.43 -21.59 0)
        (effects (font (size 1.27 1.27) (thickness 0.15)) (justify left bottom) hide)
      )
      (property "ki_description" "Shunt Voltage Reference IC Adjustable 1.24V 30 VV ±1.5% 15 mA SOT-23-5" (id 8) (at 0 0 0)
        (effects (font (size 1.27 1.27)) hide)
      )
      (symbol "LMV431_SOT-23-5_1_1"
        (polyline
          (pts
            (xy 2.54 0)
            (xy 3.81 0)
          )
          (stroke (width 0) (type default) (color 0 0 0 0))
          (fill (type none))
        )
        (polyline
          (pts
            (xy 2.54 1.27)
            (xy 1.27 2.54)
          )
          (stroke (width 0.254) (type default) (color 0 0 0 0))
          (fill (type background))
        )
        (polyline
          (pts
            (xy 2.54 1.27)
            (xy 5.08 1.27)
          )
          (stroke (width 0.254) (type default) (color 0 0 0 0))
          (fill (type background))
        )
        (polyline
          (pts
            (xy 5.08 1.27)
            (xy 6.35 0)
          )
          (stroke (width 0.254) (type default) (color 0 0 0 0))
          (fill (type background))
        )
        (polyline
          (pts
            (xy 2.54 -1.27)
            (xy 5.08 -1.27)
            (xy 3.81 1.27)
            (xy 2.54 -1.27)
          )
          (stroke (width 0.254) (type default) (color 0 0 0 0))
          (fill (type outline))
        )
        (text "A" (at 5.08 -2.54 0)
          (effects (font (size 1.27 1.27) (thickness 0.15)) (justify left bottom))
        )
        (text "C" (at 5.08 2.54 0)
          (effects (font (size 1.27 1.27) (thickness 0.15)) (justify left bottom))
        )
        (text "REF" (at -1.27 -2.54 0)
          (effects (font (size 1.27 1.27) (thickness 0.15)) (justify left bottom))
        )
        (pin no_connect line (at 5.08 1.27 180) (length 2.54) hide
          (name "NC" (effects (font (size 1.27 1.27))))
          (number "1" (effects (font (size 1.27 1.27))))
        )
        (pin no_connect line (at 5.08 0 180) (length 2.54) hide
          (name "NC" (effects (font (size 1.27 1.27))))
          (number "2" (effects (font (size 1.27 1.27))))
        )
        (pin passive line (at 3.81 3.81 270) (length 2.54)
          (name "~" (effects (font (size 1.27 1.27))))
          (number "3" (effects (font (size 1.27 1.27))))
        )
        (pin passive line (at 0 0 0) (length 2.54)
          (name "~" (effects (font (size 1.27 1.27))))
          (number "4" (effects (font (size 1.27 1.27))))
        )
        (pin passive line (at 3.81 -3.81 90) (length 2.54)
          (name "~" (effects (font (size 1.27 1.27))))
          (number "5" (effects (font (size 1.27 1.27))))
        )
      )
    )
	(symbol "sa800u-baseboard-hw:LT9611" (in_bom yes) (on_board yes)
      (property "Reference" "U" (id 0) (at 48.26 -5.08 0)
        (effects (font (size 1.27 1.27) (thickness 0.15)) (justify left bottom))
      )
      (property "Value" "LT9611" (id 1) (at 48.26 -10.16 0)
        (effects (font (size 1.27 1.27) (thickness 0.15)) (justify left bottom) hide)
      )
      (property "Footprint" "sa800u-baseboard-hw-footprints:QFN-64-1EP_7.5x7.5mm_P0.4mm" (id 2) (at 48.26 -12.7 0)
        (effects (font (size 1.27 1.27) (thickness 0.15)) (justify left bottom) hide)
      )
      (property "Datasheet" "" (id 3) (at 48.26 -15.24 0)
        (effects (font (size 1.27 1.27) (thickness 0.15)) (justify left bottom) hide)
      )
      (property "MPN" "LT9611" (id 4) (at 48.26 -7.62 0)
        (effects (font (size 1.27 1.27) (thickness 0.15)) (justify left bottom))
      )
      (property "Manufacturer" "Lontium" (id 5) (at 48.26 -17.78 0)
        (effects (font (size 1.27 1.27) (thickness 0.15)) (justify left bottom) hide)
      )
      (property "Author" "Antmicro" (id 6) (at 48.26 -20.32 0)
        (effects (font (size 1.27 1.27) (thickness 0.15)) (justify left bottom) hide)
      )
      (property "License" "Apache-2.0" (id 7) (at 48.26 -22.86 0)
        (effects (font (size 1.27 1.27) (thickness 0.15)) (justify left bottom) hide)
      )
      (property "ki_description" "MIPI DSI/CSI to HDMI bridge." (id 8) (at 0 0 0)
        (effects (font (size 1.27 1.27)) hide)
      )
      (symbol "LT9611_1_1"
        (rectangle (start 2.54 1.27) (end 30.48 -106.68)
          (stroke (width 0.254) (type default) (color 0 0 0 0))
          (fill (type background))
        )
        (pin unspecified line (at 33.02 -96.52 180) (length 2.54)
          (name "M0_N2" (effects (font (size 1.27 1.27))))
          (number "1" (effects (font (size 1.27 1.27))))
        )
        (pin input line (at 0 -49.53 0) (length 2.54)
          (name "MC_P0" (effects (font (size 1.27 1.27))))
          (number "10" (effects (font (size 1.27 1.27))))
        )
        (pin input line (at 0 -52.07 0) (length 2.54)
          (name "M1_N0" (effects (font (size 1.27 1.27))))
          (number "11" (effects (font (size 1.27 1.27))))
        )
        (pin input line (at 0 -54.61 0) (length 2.54)
          (name "M1_P0" (effects (font (size 1.27 1.27))))
          (number "12" (effects (font (size 1.27 1.27))))
        )
        (pin input line (at 0 -57.15 0) (length 2.54)
          (name "M0_N0" (effects (font (size 1.27 1.27))))
          (number "13" (effects (font (size 1.27 1.27))))
        )
        (pin input line (at 0 -59.69 0) (length 2.54)
          (name "M0_P0" (effects (font (size 1.27 1.27))))
          (number "14" (effects (font (size 1.27 1.27))))
        )
        (pin power_in line (at 33.02 0 180) (length 2.54)
          (name "VDD1" (effects (font (size 1.27 1.27))))
          (number "15" (effects (font (size 1.27 1.27))))
        )
        (pin power_in line (at 33.02 -2.54 180) (length 2.54)
          (name "VDD2" (effects (font (size 1.27 1.27))))
          (number "16" (effects (font (size 1.27 1.27))))
        )
        (pin input line (at 0 -31.75 0) (length 2.54)
          (name "RST_N" (effects (font (size 1.27 1.27))))
          (number "17" (effects (font (size 1.27 1.27))))
        )
        (pin bidirectional line (at 0 -26.67 0) (length 2.54)
          (name "CSCL_GPIO10" (effects (font (size 1.27 1.27))))
          (number "18" (effects (font (size 1.27 1.27))))
        )
        (pin bidirectional line (at 0 -29.21 0) (length 2.54)
          (name "CSDA_GPIO11" (effects (font (size 1.27 1.27))))
          (number "19" (effects (font (size 1.27 1.27))))
        )
        (pin unspecified line (at 33.02 -99.06 180) (length 2.54)
          (name "M0_P2" (effects (font (size 1.27 1.27))))
          (number "2" (effects (font (size 1.27 1.27))))
        )
        (pin bidirectional line (at 33.02 -66.04 180) (length 2.54)
          (name "SPI_CSN" (effects (font (size 1.27 1.27))))
          (number "20" (effects (font (size 1.27 1.27))))
        )
        (pin bidirectional line (at 33.02 -68.58 180) (length 2.54)
          (name "SPI_MISO" (effects (font (size 1.27 1.27))))
          (number "21" (effects (font (size 1.27 1.27))))
        )
        (pin bidirectional line (at 33.02 -71.12 180) (length 2.54)
          (name "GPIO4" (effects (font (size 1.27 1.27))))
          (number "22" (effects (font (size 1.27 1.27))))
        )
        (pin bidirectional line (at 0 -22.86 0) (length 2.54)
          (name "INTIO_GPIO5" (effects (font (size 1.27 1.27))))
          (number "23" (effects (font (size 1.27 1.27))))
        )
        (pin bidirectional line (at 33.02 -53.34 180) (length 2.54)
          (name "CEC_GPIO6" (effects (font (size 1.27 1.27))))
          (number "24" (effects (font (size 1.27 1.27))))
        )
        (pin input line (at 0 -99.06 0) (length 2.54)
          (name "I2C_ADDR" (effects (font (size 1.27 1.27))))
          (number "25" (effects (font (size 1.27 1.27))))
        )
        (pin power_in line (at 0 -11.43 0) (length 2.54)
          (name "VC33_IO" (effects (font (size 1.27 1.27))))
          (number "26" (effects (font (size 1.27 1.27))))
        )
        (pin bidirectional line (at 0 -64.77 0) (length 2.54)
          (name "I2S_WS_GPIO7" (effects (font (size 1.27 1.27))))
          (number "27" (effects (font (size 1.27 1.27))))
        )
        (pin bidirectional line (at 0 -67.31 0) (length 2.54)
          (name "I2S_SCLK_GPIO8" (effects (font (size 1.27 1.27))))
          (number "28" (effects (font (size 1.27 1.27))))
        )
        (pin bidirectional line (at 0 -69.85 0) (length 2.54)
          (name "I2S_MCLK_GPIO9" (effects (font (size 1.27 1.27))))
          (number "29" (effects (font (size 1.27 1.27))))
        )
        (pin power_in line (at 0 0 0) (length 2.54)
          (name "VCC33_MRX01" (effects (font (size 1.27 1.27))))
          (number "3" (effects (font (size 1.27 1.27))))
        )
        (pin bidirectional line (at 0 -72.39 0) (length 2.54)
          (name "I2S_D0_SPDIF" (effects (font (size 1.27 1.27))))
          (number "30" (effects (font (size 1.27 1.27))))
        )
        (pin power_in line (at 33.02 -6.35 180) (length 2.54)
          (name "VDD3" (effects (font (size 1.27 1.27))))
          (number "31" (effects (font (size 1.27 1.27))))
        )
        (pin bidirectional line (at 33.02 -60.96 180) (length 2.54)
          (name "SPI_MOSI" (effects (font (size 1.27 1.27))))
          (number "32" (effects (font (size 1.27 1.27))))
        )
        (pin bidirectional line (at 33.02 -63.5 180) (length 2.54)
          (name "SPI_SCK" (effects (font (size 1.27 1.27))))
          (number "33" (effects (font (size 1.27 1.27))))
        )
        (pin power_in line (at 0 -13.97 0) (length 2.54)
          (name "VCC33_IO" (effects (font (size 1.27 1.27))))
          (number "34" (effects (font (size 1.27 1.27))))
        )
        (pin input line (at 33.02 -55.88 180) (length 2.54)
          (name "HTX_HPD" (effects (font (size 1.27 1.27))))
          (number "35" (effects (font (size 1.27 1.27))))
        )
        (pin bidirectional line (at 33.02 -30.48 180) (length 2.54)
          (name "HTX_DSDA" (effects (font (size 1.27 1.27))))
          (number "36" (effects (font (size 1.27 1.27))))
        )
        (pin output line (at 33.02 -27.94 180) (length 2.54)
          (name "HTX_DSCL" (effects (font (size 1.27 1.27))))
          (number "37" (effects (font (size 1.27 1.27))))
        )
        (pin output line (at 33.02 -50.8 180) (length 2.54)
          (name "HTX_C-" (effects (font (size 1.27 1.27))))
          (number "38" (effects (font (size 1.27 1.27))))
        )
        (pin output line (at 33.02 -48.26 180) (length 2.54)
          (name "HTX_C+" (effects (font (size 1.27 1.27))))
          (number "39" (effects (font (size 1.27 1.27))))
        )
        (pin power_in line (at 33.02 -15.24 180) (length 2.54)
          (name "VCC12_MRX01" (effects (font (size 1.27 1.27))))
          (number "4" (effects (font (size 1.27 1.27))))
        )
        (pin output line (at 33.02 -45.72 180) (length 2.54)
          (name "HTX_D0-" (effects (font (size 1.27 1.27))))
          (number "40" (effects (font (size 1.27 1.27))))
        )
        (pin output line (at 33.02 -43.18 180) (length 2.54)
          (name "HTX_D0+" (effects (font (size 1.27 1.27))))
          (number "41" (effects (font (size 1.27 1.27))))
        )
        (pin input line (at 33.02 -104.14 180) (length 2.54)
          (name "VCOM" (effects (font (size 1.27 1.27))))
          (number "42" (effects (font (size 1.27 1.27))))
        )
        (pin power_in line (at 0 -17.78 0) (length 2.54)
          (name "VCC33_HTX" (effects (font (size 1.27 1.27))))
          (number "43" (effects (font (size 1.27 1.27))))
        )
        (pin power_in line (at 33.02 -22.86 180) (length 2.54)
          (name "VCC12_HTX" (effects (font (size 1.27 1.27))))
          (number "44" (effects (font (size 1.27 1.27))))
        )
        (pin output line (at 33.02 -40.64 180) (length 2.54)
          (name "HTX_D1-" (effects (font (size 1.27 1.27))))
          (number "45" (effects (font (size 1.27 1.27))))
        )
        (pin output line (at 33.02 -38.1 180) (length 2.54)
          (name "HTX_D1+" (effects (font (size 1.27 1.27))))
          (number "46" (effects (font (size 1.27 1.27))))
        )
        (pin output line (at 33.02 -35.56 180) (length 2.54)
          (name "HTX_D2-" (effects (font (size 1.27 1.27))))
          (number "47" (effects (font (size 1.27 1.27))))
        )
        (pin output line (at 33.02 -33.02 180) (length 2.54)
          (name "HTX_D2+" (effects (font (size 1.27 1.27))))
          (number "48" (effects (font (size 1.27 1.27))))
        )
        (pin input line (at 0 -82.55 0) (length 2.54)
          (name "XTALI" (effects (font (size 1.27 1.27))))
          (number "49" (effects (font (size 1.27 1.27))))
        )
        (pin input line (at 0 -36.83 0) (length 2.54)
          (name "M3_N0" (effects (font (size 1.27 1.27))))
          (number "5" (effects (font (size 1.27 1.27))))
        )
        (pin output line (at 0 -80.01 0) (length 2.54)
          (name "XTALO" (effects (font (size 1.27 1.27))))
          (number "50" (effects (font (size 1.27 1.27))))
        )
        (pin power_in line (at 0 -2.54 0) (length 2.54)
          (name "VCC33_BG" (effects (font (size 1.27 1.27))))
          (number "51" (effects (font (size 1.27 1.27))))
        )
        (pin passive line (at 0 -101.6 0) (length 2.54)
          (name "REXT" (effects (font (size 1.27 1.27))))
          (number "52" (effects (font (size 1.27 1.27))))
        )
        (pin power_in line (at 33.02 -11.43 180) (length 2.54)
          (name "VCC12_SYSPLL" (effects (font (size 1.27 1.27))))
          (number "53" (effects (font (size 1.27 1.27))))
        )
        (pin power_in line (at 33.02 -8.89 180) (length 2.54)
          (name "VDD" (effects (font (size 1.27 1.27))))
          (number "54" (effects (font (size 1.27 1.27))))
        )
        (pin power_in line (at 0 -6.35 0) (length 2.54)
          (name "VCC33_MRX23" (effects (font (size 1.27 1.27))))
          (number "55" (effects (font (size 1.27 1.27))))
        )
        (pin power_in line (at 33.02 -17.78 180) (length 2.54)
          (name "VCC12_MRX23" (effects (font (size 1.27 1.27))))
          (number "56" (effects (font (size 1.27 1.27))))
        )
        (pin input line (at 33.02 -76.2 180) (length 2.54)
          (name "M3_N2" (effects (font (size 1.27 1.27))))
          (number "57" (effects (font (size 1.27 1.27))))
        )
        (pin input line (at 33.02 -78.74 180) (length 2.54)
          (name "M3_P2" (effects (font (size 1.27 1.27))))
          (number "58" (effects (font (size 1.27 1.27))))
        )
        (pin input line (at 33.02 -81.28 180) (length 2.54)
          (name "M2_N2" (effects (font (size 1.27 1.27))))
          (number "59" (effects (font (size 1.27 1.27))))
        )
        (pin input line (at 0 -39.37 0) (length 2.54)
          (name "M3_P0" (effects (font (size 1.27 1.27))))
          (number "6" (effects (font (size 1.27 1.27))))
        )
        (pin input line (at 33.02 -83.82 180) (length 2.54)
          (name "M2_P2" (effects (font (size 1.27 1.27))))
          (number "60" (effects (font (size 1.27 1.27))))
        )
        (pin input line (at 33.02 -86.36 180) (length 2.54)
          (name "MC_N2" (effects (font (size 1.27 1.27))))
          (number "61" (effects (font (size 1.27 1.27))))
        )
        (pin input line (at 33.02 -88.9 180) (length 2.54)
          (name "MC_P2" (effects (font (size 1.27 1.27))))
          (number "62" (effects (font (size 1.27 1.27))))
        )
        (pin input line (at 33.02 -91.44 180) (length 2.54)
          (name "M1_N2" (effects (font (size 1.27 1.27))))
          (number "63" (effects (font (size 1.27 1.27))))
        )
        (pin input line (at 33.02 -93.98 180) (length 2.54)
          (name "M1_P2" (effects (font (size 1.27 1.27))))
          (number "64" (effects (font (size 1.27 1.27))))
        )
        (pin power_in line (at 0 -104.14 0) (length 2.54)
          (name "GND" (effects (font (size 1.27 1.27))))
          (number "65" (effects (font (size 1.27 1.27))))
        )
        (pin input line (at 0 -41.91 0) (length 2.54)
          (name "M2_N0" (effects (font (size 1.27 1.27))))
          (number "7" (effects (font (size 1.27 1.27))))
        )
        (pin input line (at 0 -44.45 0) (length 2.54)
          (name "M2_P0" (effects (font (size 1.27 1.27))))
          (number "8" (effects (font (size 1.27 1.27))))
        )
        (pin input line (at 0 -46.99 0) (length 2.54)
          (name "MC_N0" (effects (font (size 1.27 1.27))))
          (number "9" (effects (font (size 1.27 1.27))))
        )
      )
    )
	(symbol "sa800u-baseboard-hw:LTC4417_QFN" (in_bom yes) (on_board yes)
      (property "Reference" "U" (id 0) (at 38.1 -7.62 0)
        (effects (font (size 1.27 1.27) (thickness 0.15)) (justify left bottom))
      )
      (property "Value" "LTC4417_QFN" (id 1) (at 38.1 -12.7 0)
        (effects (font (size 1.27 1.27) (thickness 0.15)) (justify left bottom) hide)
      )
      (property "Footprint" "antmicro-footprints:QFN-24-1EP_4x4mm_EP2.1x2.1mm" (id 2) (at 38.1 -15.24 0)
        (effects (font (size 1.27 1.27) (thickness 0.15)) (justify left bottom) hide)
      )
      (property "Datasheet" "https://www.mouser.pl/datasheet/2/609/4417f-1271526.pdf" (id 3) (at 38.1 -17.78 0)
        (effects (font (size 1.27 1.27) (thickness 0.15)) (justify left bottom) hide)
      )
      (property "MPN" "LTC4417IUF#TRPBF" (id 4) (at 38.1 -10.16 0)
        (effects (font (size 1.27 1.27) (thickness 0.15)) (justify left bottom))
      )
      (property "Manufacturer" "Analog Devices" (id 5) (at 38.1 -20.32 0)
        (effects (font (size 1.27 1.27) (thickness 0.15)) (justify left bottom) hide)
      )
      (property "Author" "Antmicro" (id 6) (at 38.1 -22.86 0)
        (effects (font (size 1.27 1.27) (thickness 0.15)) (justify left bottom) hide)
      )
      (property "License" "Apache-2.0" (id 7) (at 38.1 -25.4 0)
        (effects (font (size 1.27 1.27) (thickness 0.15)) (justify left bottom) hide)
      )
      (property "ki_description" "Highest priority supply selector" (id 8) (at 0 0 0)
        (effects (font (size 1.27 1.27)) hide)
      )
      (symbol "LTC4417_QFN_1_1"
        (rectangle (start 2.54 2.54) (end 22.86 -73.66)
          (stroke (width 0.254) (type default) (color 0 0 0 0))
          (fill (type background))
        )
        (pin input line (at 0 -8.89 0) (length 2.54)
          (name "UV1" (effects (font (size 1.27 1.27))))
          (number "1" (effects (font (size 1.27 1.27))))
        )
        (pin power_in line (at 25.4 -71.12 180) (length 2.54)
          (name "GND" (effects (font (size 1.27 1.27))))
          (number "10" (effects (font (size 1.27 1.27))))
        )
        (pin output line (at 25.4 -52.07 180) (length 2.54)
          (name "CAS" (effects (font (size 1.27 1.27))))
          (number "11" (effects (font (size 1.27 1.27))))
        )
        (pin output line (at 25.4 0 180) (length 2.54)
          (name "VOUT" (effects (font (size 1.27 1.27))))
          (number "12" (effects (font (size 1.27 1.27))))
        )
        (pin output line (at 25.4 -44.45 180) (length 2.54)
          (name "G3" (effects (font (size 1.27 1.27))))
          (number "13" (effects (font (size 1.27 1.27))))
        )
        (pin unspecified line (at 25.4 -41.91 180) (length 2.54)
          (name "VS3" (effects (font (size 1.27 1.27))))
          (number "14" (effects (font (size 1.27 1.27))))
        )
        (pin output line (at 25.4 -39.37 180) (length 2.54)
          (name "G2" (effects (font (size 1.27 1.27))))
          (number "15" (effects (font (size 1.27 1.27))))
        )
        (pin unspecified line (at 25.4 -36.83 180) (length 2.54)
          (name "VS2" (effects (font (size 1.27 1.27))))
          (number "16" (effects (font (size 1.27 1.27))))
        )
        (pin output line (at 25.4 -34.29 180) (length 2.54)
          (name "G1" (effects (font (size 1.27 1.27))))
          (number "17" (effects (font (size 1.27 1.27))))
        )
        (pin unspecified line (at 25.4 -31.75 180) (length 2.54)
          (name "VS1" (effects (font (size 1.27 1.27))))
          (number "18" (effects (font (size 1.27 1.27))))
        )
        (pin input line (at 0 -53.34 0) (length 2.54)
          (name "V3" (effects (font (size 1.27 1.27))))
          (number "19" (effects (font (size 1.27 1.27))))
        )
        (pin input line (at 0 -17.78 0) (length 2.54)
          (name "OV1" (effects (font (size 1.27 1.27))))
          (number "2" (effects (font (size 1.27 1.27))))
        )
        (pin input line (at 0 -26.67 0) (length 2.54)
          (name "V2" (effects (font (size 1.27 1.27))))
          (number "20" (effects (font (size 1.27 1.27))))
        )
        (pin input line (at 0 0 0) (length 2.54)
          (name "V1" (effects (font (size 1.27 1.27))))
          (number "21" (effects (font (size 1.27 1.27))))
        )
        (pin input line (at 25.4 -59.69 180) (length 2.54)
          (name "EN" (effects (font (size 1.27 1.27))))
          (number "22" (effects (font (size 1.27 1.27))))
        )
        (pin input line (at 25.4 -57.15 180) (length 2.54)
          (name "~{SHDN}" (effects (font (size 1.27 1.27))))
          (number "23" (effects (font (size 1.27 1.27))))
        )
        (pin input line (at 25.4 -54.61 180) (length 2.54)
          (name "HYS" (effects (font (size 1.27 1.27))))
          (number "24" (effects (font (size 1.27 1.27))))
        )
        (pin unspecified line (at 25.4 -68.58 180) (length 2.54)
          (name "EPAD" (effects (font (size 1.27 1.27))))
          (number "25" (effects (font (size 1.27 1.27))))
        )
        (pin input line (at 0 -35.56 0) (length 2.54)
          (name "UV2" (effects (font (size 1.27 1.27))))
          (number "3" (effects (font (size 1.27 1.27))))
        )
        (pin input line (at 0 -44.45 0) (length 2.54)
          (name "OV2" (effects (font (size 1.27 1.27))))
          (number "4" (effects (font (size 1.27 1.27))))
        )
        (pin input line (at 0 -62.23 0) (length 2.54)
          (name "UV3" (effects (font (size 1.27 1.27))))
          (number "5" (effects (font (size 1.27 1.27))))
        )
        (pin input line (at 0 -71.12 0) (length 2.54)
          (name "OV3" (effects (font (size 1.27 1.27))))
          (number "6" (effects (font (size 1.27 1.27))))
        )
        (pin output line (at 25.4 -21.59 180) (length 2.54)
          (name "~{VALID1}" (effects (font (size 1.27 1.27))))
          (number "7" (effects (font (size 1.27 1.27))))
        )
        (pin output line (at 25.4 -19.05 180) (length 2.54)
          (name "~{VALID2}" (effects (font (size 1.27 1.27))))
          (number "8" (effects (font (size 1.27 1.27))))
        )
        (pin output line (at 25.4 -16.51 180) (length 2.54)
          (name "~{VALID3}" (effects (font (size 1.27 1.27))))
          (number "9" (effects (font (size 1.27 1.27))))
        )
      )
    )
	(symbol "sa800u-baseboard-hw:L_2u2_6.1A_XEL4030" (pin_numbers hide) (pin_names hide) (in_bom yes) (on_board yes)
      (property "Reference" "L" (id 0) (at 13.97 0 0)
        (effects (font (size 1.27 1.27) (thickness 0.15)) (justify left bottom))
      )
      (property "Value" "L_2u2_6.1A_XEL4030" (id 1) (at 13.97 -2.54 0)
        (effects (font (size 1.27 1.27) (thickness 0.15)) (justify left bottom) hide)
      )
      (property "Footprint" "antmicro-footprints:L_Coilcraft_XEL4030" (id 2) (at 13.97 -7.62 0)
        (effects (font (size 1.27 1.27) (thickness 0.15)) (justify left bottom) hide)
      )
      (property "Datasheet" "https://www.coilcraft.com/getmedia/8245f050-f190-4295-8c41-7c03d662ee3d/xel4030.pdf" (id 3) (at 13.97 -10.16 0)
        (effects (font (size 1.27 1.27) (thickness 0.15)) (justify left bottom) hide)
      )
      (property "Val" "2u2/6.1A" (id 4) (at 13.97 -5.08 0)
        (effects (font (size 1.27 1.27) (thickness 0.15)) (justify left bottom))
      )
      (property "Manufacturer" "Coilcraft" (id 5) (at 13.97 -12.7 0)
        (effects (font (size 1.27 1.27) (thickness 0.15)) (justify left bottom) hide)
      )
      (property "MPN" "XEL4030-222MEC" (id 6) (at 13.97 -15.24 0)
        (effects (font (size 1.27 1.27) (thickness 0.15)) (justify left bottom) hide)
      )
      (property "ISat" "" (id 7) (at 13.97 -16.51 0)
        (effects (font (size 1.27 1.27)) (justify left) hide)
      )
      (property "IMax" "" (id 8) (at 13.97 -20.32 0)
        (effects (font (size 1.27 1.27) (thickness 0.15)) (justify left bottom) hide)
      )
      (property "Size" "4x4" (id 9) (at 13.97 -22.86 0)
        (effects (font (size 1.27 1.27) (thickness 0.15)) (justify left bottom) hide)
      )
      (property "Author" "Antmicro" (id 10) (at 13.97 -25.4 0)
        (effects (font (size 1.27 1.27) (thickness 0.15)) (justify left bottom) hide)
      )
      (property "License" "Apache-2.0" (id 11) (at 13.97 -27.94 0)
        (effects (font (size 1.27 1.27) (thickness 0.15)) (justify left bottom) hide)
      )
      (symbol "L_2u2_6.1A_XEL4030_0_1"
        (arc (start 1.524 0) (mid 1.016 0.508) (end 0.508 0)
          (stroke (width 0) (type default) (color 0 0 0 0))
          (fill (type none))
        )
        (arc (start 2.54 0) (mid 2.032 0.508) (end 1.524 0)
          (stroke (width 0) (type default) (color 0 0 0 0))
          (fill (type none))
        )
        (arc (start 3.556 0) (mid 3.048 0.508) (end 2.54 0)
          (stroke (width 0) (type default) (color 0 0 0 0))
          (fill (type none))
        )
        (arc (start 4.572 0) (mid 4.064 0.508) (end 3.556 0)
          (stroke (width 0) (type default) (color 0 0 0 0))
          (fill (type none))
        )
      )
      (symbol "L_2u2_6.1A_XEL4030_1_1"
        (pin passive line (at 0 0 0) (length 0.508)
          (name "~" (effects (font (size 1.27 1.27))))
          (number "1" (effects (font (size 1.27 1.27))))
        )
        (pin passive line (at 5.08 0 180) (length 0.508)
          (name "~" (effects (font (size 1.27 1.27))))
          (number "2" (effects (font (size 1.27 1.27))))
        )
      )
    )
	(symbol "sa800u-baseboard-hw:L_350n_1.4A_0603" (pin_numbers hide) (pin_names hide) (in_bom yes) (on_board yes)
      (property "Reference" "L" (id 0) (at 13.97 0 0)
        (effects (font (size 1.27 1.27) (thickness 0.15)) (justify left bottom))
      )
      (property "Value" "L_350n_1.4A_0603" (id 1) (at 13.97 -2.54 0)
        (effects (font (size 1.27 1.27) (thickness 0.15)) (justify left bottom) hide)
      )
      (property "Footprint" "sa800u-baseboard-hw-footprints:L_0603_1608Metric" (id 2) (at 13.97 -7.62 0)
        (effects (font (size 1.27 1.27) (thickness 0.15)) (justify left bottom) hide)
      )
      (property "Datasheet" "https://pl.mouser.com/datasheet/2/396/wound07_e-1628381.pdf" (id 3) (at 13.97 -10.16 0)
        (effects (font (size 1.27 1.27) (thickness 0.15)) (justify left bottom) hide)
      )
      (property "Val" "350n/1.4A" (id 4) (at 13.97 -5.08 0)
        (effects (font (size 1.27 1.27) (thickness 0.15)) (justify left bottom))
      )
      (property "Manufacturer" "Taiyo Yuden" (id 5) (at 13.97 -12.7 0)
        (effects (font (size 1.27 1.27) (thickness 0.15)) (justify left bottom) hide)
      )
      (property "MPN" "BRC1608TR35M" (id 6) (at 13.97 -15.24 0)
        (effects (font (size 1.27 1.27) (thickness 0.15)) (justify left bottom) hide)
      )
      (property "ISat" "" (id 7) (at 13.97 -16.51 0)
        (effects (font (size 1.27 1.27)) (justify left) hide)
      )
      (property "IMax" "" (id 8) (at 13.97 -20.32 0)
        (effects (font (size 1.27 1.27) (thickness 0.15)) (justify left bottom) hide)
      )
      (property "Size" "" (id 9) (at 13.97 -22.86 0)
        (effects (font (size 1.27 1.27) (thickness 0.15)) (justify left bottom) hide)
      )
      (property "Author" "Antmicro" (id 10) (at 13.97 -25.4 0)
        (effects (font (size 1.27 1.27) (thickness 0.15)) (justify left bottom) hide)
      )
      (property "License" "Apache-2.0" (id 11) (at 13.97 -27.94 0)
        (effects (font (size 1.27 1.27) (thickness 0.15)) (justify left bottom) hide)
      )
      (symbol "L_350n_1.4A_0603_0_1"
        (arc (start 1.524 0) (mid 1.016 0.508) (end 0.508 0)
          (stroke (width 0) (type default) (color 0 0 0 0))
          (fill (type none))
        )
        (arc (start 2.54 0) (mid 2.032 0.508) (end 1.524 0)
          (stroke (width 0) (type default) (color 0 0 0 0))
          (fill (type none))
        )
        (arc (start 3.556 0) (mid 3.048 0.508) (end 2.54 0)
          (stroke (width 0) (type default) (color 0 0 0 0))
          (fill (type none))
        )
        (arc (start 4.572 0) (mid 4.064 0.508) (end 3.556 0)
          (stroke (width 0) (type default) (color 0 0 0 0))
          (fill (type none))
        )
      )
      (symbol "L_350n_1.4A_0603_1_1"
        (pin passive line (at 0 0 0) (length 0.508)
          (name "~" (effects (font (size 1.27 1.27))))
          (number "1" (effects (font (size 1.27 1.27))))
        )
        (pin passive line (at 5.08 0 180) (length 0.508)
          (name "~" (effects (font (size 1.27 1.27))))
          (number "2" (effects (font (size 1.27 1.27))))
        )
      )
    )
	(symbol "sa800u-baseboard-hw:MB10S" (pin_names hide) (in_bom yes) (on_board yes)
      (property "Reference" "D" (id 0) (at 27.94 -2.54 0)
        (effects (font (size 1.27 1.27) (thickness 0.15)) (justify left bottom))
      )
      (property "Value" "MB10S" (id 1) (at 27.94 -5.08 0)
        (effects (font (size 1.27 1.27) (thickness 0.15)) (justify left bottom) hide)
      )
      (property "Footprint" "antmicro-footprints:SOIC-4_4.2x5.0mm_P5.7mm" (id 2) (at 27.94 -7.62 0)
        (effects (font (size 1.27 1.27) (thickness 0.15)) (justify left bottom) hide)
      )
      (property "Datasheet" "http://www.farnell.com/datasheets/2895435.pdf" (id 3) (at 27.94 -10.16 0)
        (effects (font (size 1.27 1.27) (thickness 0.15)) (justify left bottom) hide)
      )
      (property "MPN" "MB10S" (id 4) (at 27.94 -12.7 0)
        (effects (font (size 1.27 1.27) (thickness 0.15)) (justify left bottom))
      )
      (property "Manufacturer" "Multicomp" (id 5) (at 27.94 -15.24 0)
        (effects (font (size 1.27 1.27) (thickness 0.15)) (justify left bottom) hide)
      )
      (property "Author" "Antmicro" (id 6) (at 27.94 -17.78 0)
        (effects (font (size 1.27 1.27) (thickness 0.15)) (justify left bottom) hide)
      )
      (property "License" "Apache-2.0" (id 7) (at 27.94 -20.32 0)
        (effects (font (size 1.27 1.27) (thickness 0.15)) (justify left bottom) hide)
      )
      (property "ki_description" "Bridge Rectifier" (id 8) (at 0 0 0)
        (effects (font (size 1.27 1.27)) hide)
      )
      (symbol "MB10S_1_1"
        (polyline
          (pts
            (xy 2.54 -5.08)
            (xy 3.81 -5.08)
          )
          (stroke (width 0.254) (type default) (color 0 0 0 0))
          (fill (type none))
        )
        (polyline
          (pts
            (xy 3.81 -10.16)
            (xy 2.54 -10.16)
          )
          (stroke (width 0.254) (type default) (color 0 0 0 0))
          (fill (type none))
        )
        (polyline
          (pts
            (xy 3.81 -3.81)
            (xy 3.81 -7.62)
          )
          (stroke (width 0.254) (type default) (color 0 0 0 0))
          (fill (type none))
        )
        (polyline
          (pts
            (xy 3.81 -2.54)
            (xy 3.81 -3.81)
          )
          (stroke (width 0.254) (type default) (color 0 0 0 0))
          (fill (type none))
        )
        (polyline
          (pts
            (xy 3.81 0)
            (xy 2.54 0)
          )
          (stroke (width 0.254) (type default) (color 0 0 0 0))
          (fill (type none))
        )
        (polyline
          (pts
            (xy 5.08 -7.62)
            (xy 3.81 -7.62)
          )
          (stroke (width 0.254) (type default) (color 0 0 0 0))
          (fill (type none))
        )
        (polyline
          (pts
            (xy 5.08 -2.54)
            (xy 3.81 -2.54)
          )
          (stroke (width 0.254) (type default) (color 0 0 0 0))
          (fill (type none))
        )
        (polyline
          (pts
            (xy 7.62 -6.35)
            (xy 7.62 -8.89)
          )
          (stroke (width 0.254) (type default) (color 0 0 0 0))
          (fill (type none))
        )
        (polyline
          (pts
            (xy 7.62 -1.27)
            (xy 7.62 -3.81)
          )
          (stroke (width 0.254) (type default) (color 0 0 0 0))
          (fill (type none))
        )
        (polyline
          (pts
            (xy 8.89 -7.62)
            (xy 7.62 -7.62)
          )
          (stroke (width 0.254) (type default) (color 0 0 0 0))
          (fill (type none))
        )
        (polyline
          (pts
            (xy 8.89 -2.54)
            (xy 7.62 -2.54)
          )
          (stroke (width 0.254) (type default) (color 0 0 0 0))
          (fill (type none))
        )
        (polyline
          (pts
            (xy 10.16 -7.62)
            (xy 7.62 -7.62)
          )
          (stroke (width 0.254) (type default) (color 0 0 0 0))
          (fill (type none))
        )
        (polyline
          (pts
            (xy 10.16 -2.54)
            (xy 7.62 -2.54)
          )
          (stroke (width 0.254) (type default) (color 0 0 0 0))
          (fill (type none))
        )
        (polyline
          (pts
            (xy 12.7 -7.62)
            (xy 13.97 -7.62)
          )
          (stroke (width 0.254) (type default) (color 0 0 0 0))
          (fill (type none))
        )
        (polyline
          (pts
            (xy 12.7 -6.35)
            (xy 12.7 -8.89)
          )
          (stroke (width 0.254) (type default) (color 0 0 0 0))
          (fill (type none))
        )
        (polyline
          (pts
            (xy 12.7 -2.54)
            (xy 13.97 -2.54)
          )
          (stroke (width 0.254) (type default) (color 0 0 0 0))
          (fill (type none))
        )
        (polyline
          (pts
            (xy 12.7 -1.27)
            (xy 12.7 -3.81)
          )
          (stroke (width 0.254) (type default) (color 0 0 0 0))
          (fill (type none))
        )
        (polyline
          (pts
            (xy 13.97 -5.08)
            (xy 15.24 -5.08)
          )
          (stroke (width 0.254) (type default) (color 0 0 0 0))
          (fill (type none))
        )
        (polyline
          (pts
            (xy 13.97 -3.81)
            (xy 13.97 -7.62)
          )
          (stroke (width 0.254) (type default) (color 0 0 0 0))
          (fill (type none))
        )
        (polyline
          (pts
            (xy 13.97 -2.54)
            (xy 13.97 -3.81)
          )
          (stroke (width 0.254) (type default) (color 0 0 0 0))
          (fill (type none))
        )
        (polyline
          (pts
            (xy 8.89 -7.62)
            (xy 8.89 -10.16)
            (xy 3.81 -10.16)
          )
          (stroke (width 0.254) (type default) (color 0 0 0 0))
          (fill (type none))
        )
        (polyline
          (pts
            (xy 8.89 -2.54)
            (xy 8.89 0)
            (xy 3.81 0)
          )
          (stroke (width 0.254) (type default) (color 0 0 0 0))
          (fill (type none))
        )
        (polyline
          (pts
            (xy 5.08 -6.35)
            (xy 5.08 -8.89)
            (xy 7.62 -7.62)
            (xy 5.08 -6.35)
          )
          (stroke (width 0.254) (type default) (color 0 0 0 0))
          (fill (type outline))
        )
        (polyline
          (pts
            (xy 5.08 -1.27)
            (xy 5.08 -3.81)
            (xy 7.62 -2.54)
            (xy 5.08 -1.27)
          )
          (stroke (width 0.254) (type default) (color 0 0 0 0))
          (fill (type outline))
        )
        (polyline
          (pts
            (xy 10.16 -6.35)
            (xy 10.16 -8.89)
            (xy 12.7 -7.62)
            (xy 10.16 -6.35)
          )
          (stroke (width 0.254) (type default) (color 0 0 0 0))
          (fill (type outline))
        )
        (polyline
          (pts
            (xy 10.16 -1.27)
            (xy 10.16 -3.81)
            (xy 12.7 -2.54)
            (xy 10.16 -1.27)
          )
          (stroke (width 0.254) (type default) (color 0 0 0 0))
          (fill (type outline))
        )
        (rectangle (start 2.54 1.27) (end 15.24 -11.43)
          (stroke (width 0.254) (type default) (color 0 0 0 0))
          (fill (type background))
        )
        (pin passive line (at 17.78 -5.08 180) (length 2.54)
          (name "1" (effects (font (size 1.27 1.27))))
          (number "1" (effects (font (size 1.27 1.27))))
        )
        (pin passive line (at 0 -5.08 0) (length 2.54)
          (name "2" (effects (font (size 1.27 1.27))))
          (number "2" (effects (font (size 1.27 1.27))))
        )
        (pin passive line (at 0 0 0) (length 2.54)
          (name "3" (effects (font (size 1.27 1.27))))
          (number "3" (effects (font (size 1.27 1.27))))
        )
        (pin passive line (at 0 -10.16 0) (length 2.54)
          (name "4" (effects (font (size 1.27 1.27))))
          (number "4" (effects (font (size 1.27 1.27))))
        )
      )
    )
	(symbol "sa800u-baseboard-hw:Mech_M2_2280_H4mm" (in_bom yes) (on_board yes)
      (property "Reference" "A" (id 0) (at 25.4 0 0)
        (effects (font (size 1.27 1.27) (thickness 0.15)) (justify left bottom))
      )
      (property "Value" "Mech_M2_2280_H4mm" (id 1) (at 25.4 -2.54 0)
        (effects (font (size 1.27 1.27) (thickness 0.15)) (justify left bottom))
      )
      (property "Footprint" "sa800u-baseboard-hw-footprints:Mech_M2_2280_H4mm" (id 2) (at 25.4 -5.08 0)
        (effects (font (size 1.27 1.27) (thickness 0.15)) (justify left bottom) hide)
      )
      (property "Datasheet" "" (id 3) (at 25.4 -7.62 0)
        (effects (font (size 1.27 1.27) (thickness 0.15)) (justify left bottom) hide)
      )
      (property "Manufacturer" "" (id 4) (at 0 0 0)
        (effects (font (size 1.27 1.27)) hide)
      )
      (property "MPN" "" (id 5) (at 0 0 0)
        (effects (font (size 1.27 1.27)) hide)
      )
      (property "Author" "Antmicro" (id 6) (at 25.4 -10.16 0)
        (effects (font (size 1.27 1.27) (thickness 0.15)) (justify left bottom) hide)
      )
      (property "License" "Apache-2.0" (id 7) (at 25.4 -12.7 0)
        (effects (font (size 1.27 1.27) (thickness 0.15)) (justify left bottom) hide)
      )
      (property "ki_description" "M.2 B&M Key  22x80mm 3d model" (id 8) (at 0 0 0)
        (effects (font (size 1.27 1.27)) hide)
      )
      (symbol "Mech_M2_2280_H4mm_1_1"
        (rectangle (start 10.16 -6.35) (end 0 0)
          (stroke (width 0.254) (type default) (color 0 0 0 0))
          (fill (type background))
        )
      )
    )
	(symbol "sa800u-baseboard-hw:NFP0QHB242HS2D" (pin_names hide) (in_bom yes) (on_board yes)
      (property "Reference" "L" (id 0) (at 31.75 -5.08 0)
        (effects (font (size 1.27 1.27) (thickness 0.15)) (justify left bottom))
      )
      (property "Value" "NFP0QHB242HS2D" (id 1) (at 31.75 -7.62 0)
        (effects (font (size 1.27 1.27) (thickness 0.15)) (justify left bottom) hide)
      )
      (property "Footprint" "antmicro-footprints:L_Murata_025020_0605Metric" (id 2) (at 31.75 -10.16 0)
        (effects (font (size 1.27 1.27) (thickness 0.15)) (justify left bottom) hide)
      )
      (property "Datasheet" "https://www.farnell.com/datasheets/2616945.pdf" (id 3) (at 31.75 -12.7 0)
        (effects (font (size 1.27 1.27) (thickness 0.15)) (justify left bottom) hide)
      )
      (property "MPN" "NFP0QHB242HS2D" (id 4) (at 31.75 -15.24 0)
        (effects (font (size 1.27 1.27) (thickness 0.15)) (justify left bottom) hide)
      )
      (property "Manufacturer" "Murata" (id 5) (at 31.75 -17.78 0)
        (effects (font (size 1.27 1.27) (thickness 0.15)) (justify left bottom) hide)
      )
      (property "Author" "Antmicro" (id 6) (at 31.75 -20.32 0)
        (effects (font (size 1.27 1.27) (thickness 0.15)) (justify left bottom) hide)
      )
      (property "License" "Apache-2.0" (id 7) (at 31.75 -22.86 0)
        (effects (font (size 1.27 1.27) (thickness 0.15)) (justify left bottom) hide)
      )
      (property "ki_description" "Common mode filter" (id 8) (at 0 0 0)
        (effects (font (size 1.27 1.27)) hide)
      )
      (symbol "NFP0QHB242HS2D_1_1"
        (polyline
          (pts
            (xy 2.54 -2.921)
            (xy 12.7 -2.921)
          )
          (stroke (width 0.254) (type default) (color 0 0 0 0))
          (fill (type none))
        )
        (polyline
          (pts
            (xy 12.7 -2.032)
            (xy 2.54 -2.032)
          )
          (stroke (width 0.254) (type default) (color 0 0 0 0))
          (fill (type none))
        )
        (circle (center 1.905 -3.429) (radius 0.2032)
          (stroke (width 0.254) (type default) (color 0 0 0 0))
          (fill (type none))
        )
        (circle (center 1.905 -1.651) (radius 0.2032)
          (stroke (width 0.254) (type default) (color 0 0 0 0))
          (fill (type none))
        )
        (arc (start 2.54 0) (mid 3.81 -1.27) (end 5.08 0)
          (stroke (width 0.254) (type default) (color 0 0 0 0))
          (fill (type none))
        )
        (arc (start 5.08 -5.08) (mid 3.81 -3.81) (end 2.54 -5.08)
          (stroke (width 0.254) (type default) (color 0 0 0 0))
          (fill (type none))
        )
        (arc (start 5.08 0) (mid 6.35 -1.27) (end 7.62 0)
          (stroke (width 0.254) (type default) (color 0 0 0 0))
          (fill (type none))
        )
        (arc (start 7.62 -5.08) (mid 6.35 -3.81) (end 5.08 -5.08)
          (stroke (width 0.254) (type default) (color 0 0 0 0))
          (fill (type none))
        )
        (arc (start 7.62 0) (mid 8.89 -1.27) (end 10.16 0)
          (stroke (width 0.254) (type default) (color 0 0 0 0))
          (fill (type none))
        )
        (arc (start 10.16 -5.08) (mid 8.89 -3.81) (end 7.62 -5.08)
          (stroke (width 0.254) (type default) (color 0 0 0 0))
          (fill (type none))
        )
        (arc (start 10.16 0) (mid 11.43 -1.27) (end 12.7 0)
          (stroke (width 0.254) (type default) (color 0 0 0 0))
          (fill (type none))
        )
        (arc (start 12.7 -5.08) (mid 11.43 -3.81) (end 10.16 -5.08)
          (stroke (width 0.254) (type default) (color 0 0 0 0))
          (fill (type none))
        )
        (pin passive line (at 0 0 0) (length 2.54)
          (name "1" (effects (font (size 1.27 1.27))))
          (number "1" (effects (font (size 1.27 1.27))))
        )
        (pin passive line (at 15.24 0 180) (length 2.54)
          (name "2" (effects (font (size 1.27 1.27))))
          (number "2" (effects (font (size 1.27 1.27))))
        )
        (pin passive line (at 15.24 -5.08 180) (length 2.54)
          (name "3" (effects (font (size 1.27 1.27))))
          (number "3" (effects (font (size 1.27 1.27))))
        )
        (pin passive line (at 0 -5.08 0) (length 2.54)
          (name "4" (effects (font (size 1.27 1.27))))
          (number "4" (effects (font (size 1.27 1.27))))
        )
      )
    )
	(symbol "sa800u-baseboard-hw:NTS0102_XSON" (in_bom yes) (on_board yes)
      (property "Reference" "U" (id 0) (at 35.56 -2.54 0)
        (effects (font (size 1.27 1.27) (thickness 0.15)) (justify left bottom))
      )
      (property "Value" "NTS0102_XSON" (id 1) (at 35.56 -5.08 0)
        (effects (font (size 1.27 1.27) (thickness 0.15)) (justify left bottom))
      )
      (property "Footprint" "sa800u-baseboard-hw-footprints:XSON-8_1x1.95mm_P0.5mm" (id 2) (at 35.56 -7.62 0)
        (effects (font (size 1.27 1.27) (thickness 0.15)) (justify left bottom) hide)
      )
      (property "Datasheet" "http://www.farnell.com/datasheets/1760723.pdf" (id 3) (at 35.56 -10.16 0)
        (effects (font (size 1.27 1.27) (thickness 0.15)) (justify left bottom) hide)
      )
      (property "MPN" "NTS0102GT" (id 4) (at 35.56 -12.7 0)
        (effects (font (size 1.27 1.27) (thickness 0.15)) (justify left bottom) hide)
      )
      (property "Manufacturer" "NXP" (id 5) (at 35.56 -15.24 0)
        (effects (font (size 1.27 1.27) (thickness 0.15)) (justify left bottom) hide)
      )
      (property "Author" "Antmicro" (id 6) (at 35.56 -17.78 0)
        (effects (font (size 1.27 1.27) (thickness 0.15)) (justify left bottom) hide)
      )
      (property "License" "Apache-2.0" (id 7) (at 35.56 -20.32 0)
        (effects (font (size 1.27 1.27) (thickness 0.15)) (justify left bottom) hide)
      )
      (symbol "NTS0102_XSON_1_1"
        (rectangle (start 2.54 2.54) (end 17.78 -10.16)
          (stroke (width 0.254) (type default) (color 0 0 0 0))
          (fill (type background))
        )
        (pin bidirectional line (at 20.32 -5.08 180) (length 2.54)
          (name "B_{2}" (effects (font (size 1.27 1.27))))
          (number "1" (effects (font (size 1.27 1.27))))
        )
        (pin power_in line (at 20.32 -7.62 180) (length 2.54)
          (name "GND" (effects (font (size 1.27 1.27))))
          (number "2" (effects (font (size 1.27 1.27))))
        )
        (pin power_in line (at 0 0 0) (length 2.54)
          (name "VCC_{A}" (effects (font (size 1.27 1.27))))
          (number "3" (effects (font (size 1.27 1.27))))
        )
        (pin bidirectional line (at 0 -5.08 0) (length 2.54)
          (name "A_{2}" (effects (font (size 1.27 1.27))))
          (number "4" (effects (font (size 1.27 1.27))))
        )
        (pin bidirectional line (at 0 -2.54 0) (length 2.54)
          (name "A_{1}" (effects (font (size 1.27 1.27))))
          (number "5" (effects (font (size 1.27 1.27))))
        )
        (pin input line (at 0 -7.62 0) (length 2.54)
          (name "OE" (effects (font (size 1.27 1.27))))
          (number "6" (effects (font (size 1.27 1.27))))
        )
        (pin power_in line (at 20.32 0 180) (length 2.54)
          (name "VCC_{B}" (effects (font (size 1.27 1.27))))
          (number "7" (effects (font (size 1.27 1.27))))
        )
        (pin bidirectional line (at 20.32 -2.54 180) (length 2.54)
          (name "B_{1}" (effects (font (size 1.27 1.27))))
          (number "8" (effects (font (size 1.27 1.27))))
        )
      )
    )
	(symbol "sa800u-baseboard-hw:NX3DV42GU" (in_bom yes) (on_board yes)
      (property "Reference" "U" (id 0) (at 30.48 -2.54 0)
        (effects (font (size 1.27 1.27) (thickness 0.15)) (justify left bottom))
      )
      (property "Value" "NX3DV42GU" (id 1) (at 30.48 -7.62 0)
        (effects (font (size 1.27 1.27) (thickness 0.15)) (justify left bottom) hide)
      )
      (property "Footprint" "sa800u-baseboard-hw-footprints:XQFN-10-1.4x1.8mm_P0.4mm" (id 2) (at 30.48 -10.16 0)
        (effects (font (size 1.27 1.27) (thickness 0.15)) (justify left bottom) hide)
      )
      (property "Datasheet" "https://www.nxp.com/docs/en/data-sheet/NX3DV42.pdf" (id 3) (at 30.48 -12.7 0)
        (effects (font (size 1.27 1.27) (thickness 0.15)) (justify left bottom) hide)
      )
      (property "MPN" "NX3DV42GU,115" (id 4) (at 30.48 -5.08 0)
        (effects (font (size 1.27 1.27) (thickness 0.15)) (justify left bottom))
      )
      (property "Manufacturer" "NXP" (id 5) (at 30.48 -15.24 0)
        (effects (font (size 1.27 1.27) (thickness 0.15)) (justify left bottom) hide)
      )
      (property "Author" "Antmicro" (id 6) (at 30.48 -17.78 0)
        (effects (font (size 1.27 1.27) (thickness 0.15)) (justify left bottom) hide)
      )
      (property "License" "Apache-2.0" (id 7) (at 30.48 -20.32 0)
        (effects (font (size 1.27 1.27) (thickness 0.15)) (justify left bottom) hide)
      )
      (property "ki_keywords" "USB 2.0 UART High Speed Switch" (id 8) (at 0 0 0)
        (effects (font (size 1.27 1.27)) hide)
      )
      (property "ki_description" "Low-Power, Two-Port, High-Speed, 950MHz" (id 9) (at 0 0 0)
        (effects (font (size 1.27 1.27)) hide)
      )
      (property "ki_fp_filters" "MSOP*3x3mm*P0.5mm*" (id 10) (at 0 0 0)
        (effects (font (size 1.27 1.27)) hide)
      )
      (symbol "NX3DV42GU_1_1"
        (rectangle (start 2.54 2.54) (end 15.24 -15.24)
          (stroke (width 0.254) (type default) (color 0 0 0 0))
          (fill (type background))
        )
        (pin bidirectional line (at 0 -7.62 0) (length 2.54)
          (name "D+" (effects (font (size 1.27 1.27))))
          (number "1" (effects (font (size 1.27 1.27))))
        )
        (pin input line (at 0 -5.08 0) (length 2.54)
          (name "SEL" (effects (font (size 1.27 1.27))))
          (number "10" (effects (font (size 1.27 1.27))))
        )
        (pin bidirectional line (at 0 -10.16 0) (length 2.54)
          (name "D-" (effects (font (size 1.27 1.27))))
          (number "2" (effects (font (size 1.27 1.27))))
        )
        (pin power_in line (at 0 -12.7 0) (length 2.54)
          (name "GND" (effects (font (size 1.27 1.27))))
          (number "3" (effects (font (size 1.27 1.27))))
        )
        (pin bidirectional line (at 17.78 -10.16 180) (length 2.54)
          (name "HSD1-" (effects (font (size 1.27 1.27))))
          (number "4" (effects (font (size 1.27 1.27))))
        )
        (pin bidirectional line (at 17.78 -7.62 180) (length 2.54)
          (name "HSD1+" (effects (font (size 1.27 1.27))))
          (number "5" (effects (font (size 1.27 1.27))))
        )
        (pin bidirectional line (at 17.78 -5.08 180) (length 2.54)
          (name "HSD2-" (effects (font (size 1.27 1.27))))
          (number "6" (effects (font (size 1.27 1.27))))
        )
        (pin bidirectional line (at 17.78 -2.54 180) (length 2.54)
          (name "HSD2+" (effects (font (size 1.27 1.27))))
          (number "7" (effects (font (size 1.27 1.27))))
        )
        (pin input line (at 0 -2.54 0) (length 2.54)
          (name "~{OE}" (effects (font (size 1.27 1.27))))
          (number "8" (effects (font (size 1.27 1.27))))
        )
        (pin power_in line (at 0 0 0) (length 2.54)
          (name "VCC" (effects (font (size 1.27 1.27))))
          (number "9" (effects (font (size 1.27 1.27))))
        )
      )
    )
	(symbol "sa800u-baseboard-hw:Oscillator_SMD_25MHz_KX-7" (pin_names hide) (in_bom yes) (on_board yes)
      (property "Reference" "Y" (id 0) (at 22.86 -5.08 0)
        (effects (font (size 1.27 1.27) (thickness 0.15)) (justify left bottom))
      )
      (property "Value" "Oscillator_SMD_25MHz_KX-7" (id 1) (at 22.86 -7.62 0)
        (effects (font (size 1.27 1.27) (thickness 0.15)) (justify left bottom))
      )
      (property "Footprint" "sa800u-baseboard-hw-footprints:Oscillator_SMD_Geyer_KX-7-4Pin_3.2x2.5mm" (id 2) (at 22.86 -10.16 0)
        (effects (font (size 1.27 1.27) (thickness 0.15)) (justify left bottom) hide)
      )
      (property "Datasheet" "" (id 3) (at 22.86 -12.7 0)
        (effects (font (size 1.27 1.27) (thickness 0.15)) (justify left bottom) hide)
      )
      (property "MPN" "ABM8G-25.000MHZ-18-D2Y-T" (id 4) (at 22.86 -15.24 0)
        (effects (font (size 1.27 1.27) (thickness 0.15)) (justify left bottom) hide)
      )
      (property "Manufacturer" "Abracon" (id 5) (at 22.86 -17.78 0)
        (effects (font (size 1.27 1.27) (thickness 0.15)) (justify left bottom) hide)
      )
      (property "Val" "25MHz" (id 6) (at 22.86 -20.32 0)
        (effects (font (size 1.27 1.27) (thickness 0.15)) (justify left bottom) hide)
      )
      (property "Author" "Antmicro" (id 7) (at 22.86 -22.86 0)
        (effects (font (size 1.27 1.27) (thickness 0.15)) (justify left bottom) hide)
      )
      (property "License" "Apache-2.0" (id 8) (at 22.86 -25.4 0)
        (effects (font (size 1.27 1.27) (thickness 0.15)) (justify left bottom) hide)
      )
      (property "ki_description" "25 MHz ±20ppm Crystal 18pF 60 Ohms 4-SMD, No Lead" (id 9) (at 0 0 0)
        (effects (font (size 1.27 1.27)) hide)
      )
      (symbol "Oscillator_SMD_25MHz_KX-7_1_1"
        (polyline
          (pts
            (xy 2.54 1.27)
            (xy 2.54 -1.27)
          )
          (stroke (width 0.254) (type default) (color 0 0 0 0))
          (fill (type background))
        )
        (polyline
          (pts
            (xy 5.08 1.27)
            (xy 5.08 -1.27)
          )
          (stroke (width 0.254) (type default) (color 0 0 0 0))
          (fill (type background))
        )
        (polyline
          (pts
            (xy 1.905 -1.905)
            (xy 1.905 -2.54)
            (xy 5.715 -2.54)
            (xy 5.715 -1.905)
          )
          (stroke (width 0.254) (type default) (color 0 0 0 0))
          (fill (type none))
        )
        (polyline
          (pts
            (xy 1.905 1.905)
            (xy 1.905 2.54)
            (xy 5.715 2.54)
            (xy 5.715 1.905)
          )
          (stroke (width 0.254) (type default) (color 0 0 0 0))
          (fill (type none))
        )
        (rectangle (start 3.175 1.905) (end 4.445 -1.905)
          (stroke (width 0.254) (type default) (color 0 0 0 0))
          (fill (type background))
        )
        (pin passive line (at 0 0 0) (length 2.54)
          (name "~" (effects (font (size 1.27 1.27))))
          (number "1" (effects (font (size 1.27 1.27))))
        )
        (pin passive line (at 3.81 -5.08 90) (length 2.54)
          (name "SH" (effects (font (size 1.27 1.27))))
          (number "2" (effects (font (size 1.27 1.27))))
        )
        (pin passive line (at 7.62 0 180) (length 2.54)
          (name "~" (effects (font (size 1.27 1.27))))
          (number "3" (effects (font (size 1.27 1.27))))
        )
        (pin passive line (at 3.81 -5.08 90) (length 2.54) hide
          (name "SH" (effects (font (size 1.27 1.27))))
          (number "4" (effects (font (size 1.27 1.27))))
        )
      )
    )
	(symbol "sa800u-baseboard-hw:PDQE30-Q48-S5-D" (in_bom yes) (on_board yes)
      (property "Reference" "U" (id 0) (at 35.56 -2.54 0)
        (effects (font (size 1.27 1.27) (thickness 0.15)) (justify left bottom))
      )
      (property "Value" "PDQE30-Q48-S5-D" (id 1) (at 35.56 -7.62 0)
        (effects (font (size 1.27 1.27) (thickness 0.15)) (justify left bottom) hide)
      )
      (property "Footprint" "sa800u-baseboard-hw-footprints:CONV_PDQE30-Q48-S5-D" (id 2) (at 35.56 -10.16 0)
        (effects (font (size 1.27 1.27) (thickness 0.15)) (justify left bottom) hide)
      )
      (property "Datasheet" "https://www.cui.com/product/resource/pdqe30-d.pdf" (id 3) (at 35.56 -12.7 0)
        (effects (font (size 1.27 1.27) (thickness 0.15)) (justify left bottom) hide)
      )
      (property "MPN" "PDQE30-Q48-S5-D" (id 4) (at 35.56 -5.08 0)
        (effects (font (size 1.27 1.27) (thickness 0.15)) (justify left bottom))
      )
      (property "Manufacturer" "CUI Inc" (id 5) (at 35.56 -15.24 0)
        (effects (font (size 1.27 1.27) (thickness 0.15)) (justify left bottom) hide)
      )
      (property "Author" "Antmicro" (id 6) (at 35.56 -17.78 0)
        (effects (font (size 1.27 1.27) (thickness 0.15)) (justify left bottom) hide)
      )
      (property "License" "Apache-2.0" (id 7) (at 35.56 -20.32 0)
        (effects (font (size 1.27 1.27) (thickness 0.15)) (justify left bottom) hide)
      )
      (property "ki_keywords" "dc converter step down 5v 48v isolated 30W poe" (id 8) (at 0 0 0)
        (effects (font (size 1.27 1.27)) hide)
      )
      (property "ki_description" "DC-DC CONVERTER, 48VDC input, 5VDC nom isolated output w/ trim option, 30W, 270kHz PWM mode" (id 9) (at 0 0 0)
        (effects (font (size 1.27 1.27)) hide)
      )
      (symbol "PDQE30-Q48-S5-D_1_1"
        (rectangle (start 2.54 2.54) (end 17.78 -17.78)
          (stroke (width 0.254) (type default) (color 0 0 0 0))
          (fill (type background))
        )
        (pin input line (at 0 -7.62 0) (length 2.54)
          (name "CTRL" (effects (font (size 1.27 1.27))))
          (number "1" (effects (font (size 1.27 1.27))))
        )
        (pin power_in line (at 0 -15.24 0) (length 2.54)
          (name "GND" (effects (font (size 1.27 1.27))))
          (number "2" (effects (font (size 1.27 1.27))))
        )
        (pin power_in line (at 0 0 0) (length 2.54)
          (name "V_{IN}" (effects (font (size 1.27 1.27))))
          (number "3" (effects (font (size 1.27 1.27))))
        )
        (pin power_out line (at 20.32 0 180) (length 2.54)
          (name "V_{O}" (effects (font (size 1.27 1.27))))
          (number "4" (effects (font (size 1.27 1.27))))
        )
        (pin passive line (at 20.32 -7.62 180) (length 2.54)
          (name "TRIM" (effects (font (size 1.27 1.27))))
          (number "5" (effects (font (size 1.27 1.27))))
        )
        (pin power_out line (at 20.32 -15.24 180) (length 2.54)
          (name "0V" (effects (font (size 1.27 1.27))))
          (number "6" (effects (font (size 1.27 1.27))))
        )
      )
    )
	(symbol "sa800u-baseboard-hw:PESD18VF1BSFYL" (pin_names hide) (in_bom yes) (on_board yes)
      (property "Reference" "D" (id 0) (at 25.4 -5.08 0)
        (effects (font (size 1.27 1.27) (thickness 0.15)) (justify left bottom))
      )
      (property "Value" "PESD18VF1BSFYL" (id 1) (at 25.4 -7.62 0)
        (effects (font (size 1.27 1.27) (thickness 0.15)) (justify left bottom) hide)
      )
      (property "Footprint" "sa800u-baseboard-hw-footprints:D_0201_0603Metric" (id 2) (at 25.4 -10.16 0)
        (effects (font (size 1.27 1.27) (thickness 0.15)) (justify left bottom) hide)
      )
      (property "Datasheet" "https://www.mouser.pl/datasheet/2/916/PESD18VF1BSF-1599696.pdf" (id 3) (at 25.4 -12.7 0)
        (effects (font (size 1.27 1.27) (thickness 0.15)) (justify left bottom) hide)
      )
      (property "Manufacturer" "Nexperia" (id 4) (at 25.4 -15.24 0)
        (effects (font (size 1.27 1.27) (thickness 0.15)) (justify left bottom) hide)
      )
      (property "MPN" "PESD18VF1BSFYL" (id 5) (at 25.4 -17.78 0)
        (effects (font (size 1.27 1.27) (thickness 0.15)) (justify left bottom))
      )
      (property "Author" "Antmicro" (id 6) (at 25.4 -20.32 0)
        (effects (font (size 1.27 1.27) (thickness 0.15)) (justify left bottom) hide)
      )
      (property "License" "Apache-2.0" (id 7) (at 25.4 -22.86 0)
        (effects (font (size 1.27 1.27) (thickness 0.15)) (justify left bottom) hide)
      )
      (symbol "PESD18VF1BSFYL_1_1"
        (polyline
          (pts
            (xy 2.54 -1.905)
            (xy 2.54 1.905)
          )
          (stroke (width 0.254) (type default) (color 0 0 0 0))
          (fill (type none))
        )
        (polyline
          (pts
            (xy 2.54 -1.905)
            (xy 3.81 -1.905)
          )
          (stroke (width 0.254) (type default) (color 0 0 0 0))
          (fill (type none))
        )
        (polyline
          (pts
            (xy 5.08 0)
            (xy 6.35 0)
          )
          (stroke (width 0.254) (type default) (color 0 0 0 0))
          (fill (type none))
        )
        (polyline
          (pts
            (xy 8.255 0)
            (xy 8.89 0)
          )
          (stroke (width 0.254) (type default) (color 0 0 0 0))
          (fill (type none))
        )
        (polyline
          (pts
            (xy 8.89 -1.905)
            (xy 8.89 1.905)
            (xy 7.62 1.905)
          )
          (stroke (width 0.254) (type default) (color 0 0 0 0))
          (fill (type none))
        )
        (polyline
          (pts
            (xy 2.54 0)
            (xy 5.08 1.905)
            (xy 5.08 -1.905)
            (xy 2.54 0)
          )
          (stroke (width 0.254) (type default) (color 0 0 0 0))
          (fill (type outline))
        )
        (polyline
          (pts
            (xy 6.35 1.905)
            (xy 6.35 -1.905)
            (xy 8.89 0)
            (xy 6.35 1.905)
          )
          (stroke (width 0.254) (type default) (color 0 0 0 0))
          (fill (type outline))
        )
        (pin input line (at 0 0 0) (length 2.54)
          (name "1" (effects (font (size 1.27 1.27))))
          (number "1" (effects (font (size 1.27 1.27))))
        )
        (pin input line (at 11.43 0 180) (length 2.54)
          (name "2" (effects (font (size 1.27 1.27))))
          (number "2" (effects (font (size 1.27 1.27))))
        )
      )
    )
	(symbol "sa800u-baseboard-hw:PESD2V5Y1BSFYL" (pin_names hide) (in_bom yes) (on_board yes)
      (property "Reference" "D" (id 0) (at 25.4 -5.08 0)
        (effects (font (size 1.27 1.27) (thickness 0.15)) (justify left bottom))
      )
      (property "Value" "PESD2V5Y1BSFYL" (id 1) (at 25.4 -7.62 0)
        (effects (font (size 1.27 1.27) (thickness 0.15)) (justify left bottom) hide)
      )
      (property "Footprint" "sa800u-baseboard-hw-footprints:D_0201_0603Metric" (id 2) (at 25.4 -10.16 0)
        (effects (font (size 1.27 1.27) (thickness 0.15)) (justify left bottom) hide)
      )
      (property "Datasheet" "https://assets.nexperia.com/documents/data-sheet/PESD2V5Y1BSF.pdf" (id 3) (at 25.4 -12.7 0)
        (effects (font (size 1.27 1.27) (thickness 0.15)) (justify left bottom) hide)
      )
      (property "Manufacturer" "Nexperia" (id 4) (at 25.4 -15.24 0)
        (effects (font (size 1.27 1.27) (thickness 0.15)) (justify left bottom) hide)
      )
      (property "MPN" "PESD2V5Y1BSFYL" (id 5) (at 25.4 -17.78 0)
        (effects (font (size 1.27 1.27) (thickness 0.15)) (justify left bottom) hide)
      )
      (property "Author" "Antmicro" (id 6) (at 25.4 -20.32 0)
        (effects (font (size 1.27 1.27) (thickness 0.15)) (justify left bottom) hide)
      )
      (property "License" "Apache-2.0" (id 7) (at 25.4 -22.86 0)
        (effects (font (size 1.27 1.27) (thickness 0.15)) (justify left bottom) hide)
      )
      (property "ki_description" "TVS DIODE 2.5V DSN0603-2" (id 8) (at 0 0 0)
        (effects (font (size 1.27 1.27)) hide)
      )
      (symbol "PESD2V5Y1BSFYL_1_1"
        (polyline
          (pts
            (xy 2.54 -1.905)
            (xy 2.54 1.905)
          )
          (stroke (width 0.254) (type default) (color 0 0 0 0))
          (fill (type none))
        )
        (polyline
          (pts
            (xy 2.54 -1.905)
            (xy 3.81 -1.905)
          )
          (stroke (width 0.254) (type default) (color 0 0 0 0))
          (fill (type none))
        )
        (polyline
          (pts
            (xy 5.08 0)
            (xy 6.35 0)
          )
          (stroke (width 0.254) (type default) (color 0 0 0 0))
          (fill (type none))
        )
        (polyline
          (pts
            (xy 8.89 -1.905)
            (xy 8.89 1.905)
            (xy 7.62 1.905)
          )
          (stroke (width 0.254) (type default) (color 0 0 0 0))
          (fill (type none))
        )
        (polyline
          (pts
            (xy 2.54 0)
            (xy 5.08 1.905)
            (xy 5.08 -1.905)
            (xy 2.54 0)
          )
          (stroke (width 0.254) (type default) (color 0 0 0 0))
          (fill (type outline))
        )
        (polyline
          (pts
            (xy 6.35 1.905)
            (xy 6.35 -1.905)
            (xy 8.89 0)
            (xy 6.35 1.905)
          )
          (stroke (width 0.254) (type default) (color 0 0 0 0))
          (fill (type outline))
        )
        (pin input line (at 0 0 0) (length 2.54)
          (name "1" (effects (font (size 1.27 1.27))))
          (number "1" (effects (font (size 1.27 1.27))))
        )
        (pin input line (at 11.43 0 180) (length 2.54)
          (name "2" (effects (font (size 1.27 1.27))))
          (number "2" (effects (font (size 1.27 1.27))))
        )
      )
    )
	(symbol "sa800u-baseboard-hw:PMEG3050EP,115" (pin_names hide) (in_bom yes) (on_board yes)
      (property "Reference" "D" (id 0) (at 21.59 -5.08 0)
        (effects (font (size 1.27 1.27) (thickness 0.15)) (justify left bottom))
      )
      (property "Value" "PMEG3050EP,115" (id 1) (at 21.59 -7.62 0)
        (effects (font (size 1.27 1.27) (thickness 0.15)) (justify left bottom))
      )
      (property "Footprint" "sa800u-baseboard-hw-footprints:Nexperia_SOD128" (id 2) (at 21.59 -10.16 0)
        (effects (font (size 1.27 1.27) (thickness 0.15)) (justify left bottom) hide)
      )
      (property "Datasheet" "https://www.mouser.pl/datasheet/2/916/PMEG3050EP-2938519.pdf" (id 3) (at 21.59 -12.7 0)
        (effects (font (size 1.27 1.27) (thickness 0.15)) (justify left bottom) hide)
      )
      (property "MPN" "PMEG3050EP,115" (id 4) (at 21.59 -15.24 0)
        (effects (font (size 1.27 1.27) (thickness 0.15)) (justify left bottom) hide)
      )
      (property "Manufacturer" "Nexperia" (id 5) (at 21.59 -17.78 0)
        (effects (font (size 1.27 1.27) (thickness 0.15)) (justify left bottom) hide)
      )
      (property "Author" "Antmicro" (id 6) (at 21.59 -20.32 0)
        (effects (font (size 1.27 1.27) (thickness 0.15)) (justify left bottom) hide)
      )
      (property "License" "Apache-2.0" (id 7) (at 21.59 -22.86 0)
        (effects (font (size 1.27 1.27) (thickness 0.15)) (justify left bottom) hide)
      )
      (property "ki_description" "SCHOTTKY RECT 30V 5A, Vf=315 mV" (id 8) (at 0 0 0)
        (effects (font (size 1.27 1.27)) hide)
      )
      (symbol "PMEG3050EP,115_0_1"
        (polyline
          (pts
            (xy 3.302 0)
            (xy 1.778 0)
          )
          (stroke (width 0) (type default) (color 0 0 0 0))
          (fill (type none))
        )
        (polyline
          (pts
            (xy 3.302 1.016)
            (xy 3.302 -1.016)
          )
          (stroke (width 0.254) (type default) (color 0 0 0 0))
          (fill (type none))
        )
        (polyline
          (pts
            (xy 1.778 1.016)
            (xy 3.302 0)
            (xy 1.778 -1.016)
            (xy 1.778 1.016)
          )
          (stroke (width 0.254) (type default) (color 0 0 0 0))
          (fill (type outline))
        )
      )
      (symbol "PMEG3050EP,115_1_1"
        (polyline
          (pts
            (xy 3.302 -1.016)
            (xy 3.302 -1.651)
            (xy 3.937 -1.651)
            (xy 3.937 -1.016)
          )
          (stroke (width 0.254) (type default) (color 0 0 0 0))
          (fill (type none))
        )
        (polyline
          (pts
            (xy 3.302 1.016)
            (xy 3.302 1.651)
            (xy 2.667 1.651)
            (xy 2.667 1.016)
          )
          (stroke (width 0.254) (type default) (color 0 0 0 0))
          (fill (type none))
        )
        (pin passive line (at 5.08 0 180) (length 1.778)
          (name "1" (effects (font (size 1.27 1.27))))
          (number "1" (effects (font (size 1.27 1.27))))
        )
        (pin passive line (at 0 0 0) (length 1.778)
          (name "2" (effects (font (size 1.27 1.27))))
          (number "2" (effects (font (size 1.27 1.27))))
        )
      )
    )
	(symbol "sa800u-baseboard-hw:PMEG6002EJ,115" (pin_numbers hide) (pin_names hide) (in_bom yes) (on_board yes)
      (property "Reference" "D" (id 0) (at 21.59 -5.08 0)
        (effects (font (size 1.27 1.27) (thickness 0.15)) (justify left bottom))
      )
      (property "Value" "PMEG6002EJ,115" (id 1) (at 21.59 -7.62 0)
        (effects (font (size 1.27 1.27) (thickness 0.15)) (justify left bottom))
      )
      (property "Footprint" "sa800u-baseboard-hw-footprints:D_SOD-323F" (id 2) (at 21.59 -10.16 0)
        (effects (font (size 1.27 1.27) (thickness 0.15)) (justify left bottom) hide)
      )
      (property "Datasheet" "https://www.farnell.com/datasheets/1443391.pdf" (id 3) (at 21.59 -12.7 0)
        (effects (font (size 1.27 1.27) (thickness 0.15)) (justify left bottom) hide)
      )
      (property "MPN" "PMEG6002EJ,115" (id 4) (at 21.59 -15.24 0)
        (effects (font (size 1.27 1.27) (thickness 0.15)) (justify left bottom) hide)
      )
      (property "Manufacturer" "Nexperia" (id 5) (at 21.59 -17.78 0)
        (effects (font (size 1.27 1.27) (thickness 0.15)) (justify left bottom) hide)
      )
      (property "Author" "Antmicro" (id 6) (at 21.59 -20.32 0)
        (effects (font (size 1.27 1.27) (thickness 0.15)) (justify left bottom) hide)
      )
      (property "License" "Apache-2.0" (id 7) (at 21.59 -22.86 0)
        (effects (font (size 1.27 1.27) (thickness 0.15)) (justify left bottom) hide)
      )
      (property "ki_description" "200 mA low V F MEGA Schottky barrier rectifier" (id 8) (at 0 0 0)
        (effects (font (size 1.27 1.27)) hide)
      )
      (symbol "PMEG6002EJ,115_1_1"
        (polyline
          (pts
            (xy 4.572 -1.016)
            (xy 4.572 -1.3462)
          )
          (stroke (width 0.254) (type default) (color 0 0 0 0))
          (fill (type none))
        )
        (polyline
          (pts
            (xy 5.588 1.1938)
            (xy 5.588 0.8128)
          )
          (stroke (width 0.254) (type default) (color 0 0 0 0))
          (fill (type none))
        )
        (polyline
          (pts
            (xy 2.54 1.27)
            (xy 2.54 -1.27)
            (xy 5.08 0)
            (xy 2.54 1.27)
          )
          (stroke (width 0.254) (type default) (color 0 0 0 0))
          (fill (type outline))
        )
        (polyline
          (pts
            (xy 5.588 1.1938)
            (xy 5.08 1.1938)
            (xy 5.08 -1.3462)
            (xy 4.572 -1.3462)
          )
          (stroke (width 0.254) (type default) (color 0 0 0 0))
          (fill (type none))
        )
        (pin passive line (at 0 0 0) (length 2.54)
          (name "A" (effects (font (size 1.27 1.27))))
          (number "A" (effects (font (size 1.27 1.27))))
        )
        (pin passive line (at 7.62 0 180) (length 2.54)
          (name "K" (effects (font (size 1.27 1.27))))
          (number "K" (effects (font (size 1.27 1.27))))
        )
      )
    )
	(symbol "sa800u-baseboard-hw:PUSB3F96X_PASS" (in_bom yes) (on_board yes)
      (property "Reference" "D" (id 0) (at 25.4 -2.54 0)
        (effects (font (size 1.27 1.27) (thickness 0.15)) (justify left bottom))
      )
      (property "Value" "PUSB3F96X_PASS" (id 1) (at 25.4 -5.08 0)
        (effects (font (size 1.27 1.27) (thickness 0.15)) (justify left bottom) hide)
      )
      (property "Footprint" "sa800u-baseboard-hw-footprints:Nexperia_DFN-10_2.5x1mm_P0.5mm" (id 2) (at 25.4 -7.62 0)
        (effects (font (size 1.27 1.27) (thickness 0.15)) (justify left bottom) hide)
      )
      (property "Datasheet" "https://pl.mouser.com/datasheet/2/916/PUSB3F96-1600324.pdf" (id 3) (at 25.4 -10.16 0)
        (effects (font (size 1.27 1.27) (thickness 0.15)) (justify left bottom) hide)
      )
      (property "Manufacturer" "Nexperia" (id 4) (at 25.4 -12.7 0)
        (effects (font (size 1.27 1.27) (thickness 0.15)) (justify left bottom) hide)
      )
      (property "MPN" "PUSB3F96X" (id 5) (at 25.4 -15.24 0)
        (effects (font (size 1.27 1.27) (thickness 0.15)) (justify left bottom) hide)
      )
      (property "Author" "Antmicro" (id 6) (at 25.4 -17.78 0)
        (effects (font (size 1.27 1.27) (thickness 0.15)) (justify left bottom) hide)
      )
      (property "License" "Apache-2.0" (id 7) (at 25.4 -20.32 0)
        (effects (font (size 1.27 1.27) (thickness 0.15)) (justify left bottom) hide)
      )
      (symbol "PUSB3F96X_PASS_1_1"
        (polyline
          (pts
            (xy 9.144 -1.524)
            (xy 9.144 -7.112)
          )
          (stroke (width 0.254) (type default) (color 0 0 0 0))
          (fill (type none))
        )
        (polyline
          (pts
            (xy 8.382 -3.81)
            (xy 9.906 -3.81)
            (xy 9.906 -4.064)
          )
          (stroke (width 0.254) (type default) (color 0 0 0 0))
          (fill (type none))
        )
        (polyline
          (pts
            (xy 10.16 -5.334)
            (xy 9.144 -3.81)
            (xy 8.128 -5.334)
            (xy 10.16 -5.334)
          )
          (stroke (width 0.254) (type default) (color 0 0 0 0))
          (fill (type outline))
        )
        (rectangle (start 2.54 -12.7) (end 12.7 2.54)
          (stroke (width 0.254) (type default) (color 0 0 0 0))
          (fill (type background))
        )
        (pin passive line (at 0 0 0) (length 2.54)
          (name "CH1" (effects (font (size 1.27 1.27))))
          (number "1" (effects (font (size 1.27 1.27))))
        )
        (pin passive line (at 0 0 0) (length 2.54) hide
          (name "CH1" (effects (font (size 1.27 1.27))))
          (number "10" (effects (font (size 1.27 1.27))))
        )
        (pin passive line (at 0 -2.54 0) (length 2.54)
          (name "CH2" (effects (font (size 1.27 1.27))))
          (number "2" (effects (font (size 1.27 1.27))))
        )
        (pin passive line (at 0 -10.16 0) (length 2.54)
          (name "GND" (effects (font (size 1.27 1.27))))
          (number "3" (effects (font (size 1.27 1.27))))
        )
        (pin passive line (at 0 -5.08 0) (length 2.54)
          (name "CH3" (effects (font (size 1.27 1.27))))
          (number "4" (effects (font (size 1.27 1.27))))
        )
        (pin passive line (at 0 -7.62 0) (length 2.54)
          (name "CH4" (effects (font (size 1.27 1.27))))
          (number "5" (effects (font (size 1.27 1.27))))
        )
        (pin passive line (at 0 -7.62 0) (length 2.54) hide
          (name "CH4" (effects (font (size 1.27 1.27))))
          (number "6" (effects (font (size 1.27 1.27))))
        )
        (pin passive line (at 0 -5.08 0) (length 2.54) hide
          (name "CH3" (effects (font (size 1.27 1.27))))
          (number "7" (effects (font (size 1.27 1.27))))
        )
        (pin passive line (at 0 -10.16 0) (length 2.54) hide
          (name "GND" (effects (font (size 1.27 1.27))))
          (number "8" (effects (font (size 1.27 1.27))))
        )
        (pin passive line (at 0 -2.54 0) (length 2.54) hide
          (name "CH2" (effects (font (size 1.27 1.27))))
          (number "9" (effects (font (size 1.27 1.27))))
        )
      )
    )
	(symbol "sa800u-baseboard-hw:PWR_FLAG" (power) (pin_numbers hide) (pin_names (offset 0) hide) (in_bom yes) (on_board yes)
      (property "Reference" "#FLG" (id 0) (at 0 1.905 0)
        (effects (font (size 1.27 1.27)) hide)
      )
      (property "Value" "PWR_FLAG" (id 1) (at 0 3.81 0)
        (effects (font (size 1.27 1.27)))
      )
      (property "Footprint" "" (id 2) (at 0 0 0)
        (effects (font (size 1.27 1.27)) hide)
      )
      (property "Datasheet" "" (id 3) (at 0 0 0)
        (effects (font (size 1.27 1.27)) hide)
      )
      (symbol "PWR_FLAG_0_0"
        (pin power_out line (at 0 0 90) (length 0)
          (name "pwr" (effects (font (size 1.27 1.27))))
          (number "1" (effects (font (size 1.27 1.27))))
        )
      )
      (symbol "PWR_FLAG_0_1"
        (polyline
          (pts
            (xy 0 0)
            (xy 0 1.27)
            (xy -1.016 1.905)
            (xy 0 2.54)
            (xy 1.016 1.905)
            (xy 0 1.27)
          )
          (stroke (width 0) (type default) (color 0 0 0 0))
          (fill (type none))
        )
      )
    )
	(symbol "sa800u-baseboard-hw:RTL8111H" (in_bom yes) (on_board yes)
      (property "Reference" "U" (id 0) (at 40.64 -2.54 0)
        (effects (font (size 1.27 1.27) (thickness 0.15)) (justify left bottom))
      )
      (property "Value" "RTL8111H" (id 1) (at 40.64 -7.62 0)
        (effects (font (size 1.27 1.27) (thickness 0.15)) (justify left bottom) hide)
      )
      (property "Footprint" "sa800u-baseboard-hw-footprints:QFN-32-1EP_4x4mm_P0.4mm" (id 2) (at 40.64 -10.16 0)
        (effects (font (size 1.27 1.27) (thickness 0.15)) (justify left bottom) hide)
      )
      (property "Datasheet" "" (id 3) (at 40.64 -12.7 0)
        (effects (font (size 1.27 1.27) (thickness 0.15)) (justify left bottom) hide)
      )
      (property "MPN" "RTL8111H" (id 4) (at 40.64 -5.08 0)
        (effects (font (size 1.27 1.27) (thickness 0.15)) (justify left bottom))
      )
      (property "Manufacturer" "Realtek" (id 5) (at 40.64 -15.24 0)
        (effects (font (size 1.27 1.27) (thickness 0.15)) (justify left bottom) hide)
      )
      (property "Author" "Antmicro" (id 6) (at 40.64 -17.78 0)
        (effects (font (size 1.27 1.27) (thickness 0.15)) (justify left bottom) hide)
      )
      (property "License" "Apache-2.0" (id 7) (at 40.64 -20.32 0)
        (effects (font (size 1.27 1.27) (thickness 0.15)) (justify left bottom) hide)
      )
      (property "ki_description" "INTEGRATED 10/100/1000M ETHERNET CONTROLLER FOR PCI EXPRESS APPLICATIONS" (id 8) (at 0 0 0)
        (effects (font (size 1.27 1.27)) hide)
      )
      (symbol "RTL8111H_1_1"
        (rectangle (start 2.54 2.54) (end 25.4 -50.8)
          (stroke (width 0.254) (type default) (color 0 0 0 0))
          (fill (type background))
        )
        (pin bidirectional line (at 27.94 -21.59 180) (length 2.54)
          (name "MDIP0" (effects (font (size 1.27 1.27))))
          (number "1" (effects (font (size 1.27 1.27))))
        )
        (pin bidirectional line (at 27.94 -34.29 180) (length 2.54)
          (name "MDIN3" (effects (font (size 1.27 1.27))))
          (number "10" (effects (font (size 1.27 1.27))))
        )
        (pin power_in line (at 0 -2.54 0) (length 2.54)
          (name "AVDD33_1" (effects (font (size 1.27 1.27))))
          (number "11" (effects (font (size 1.27 1.27))))
        )
        (pin open_collector line (at 0 -10.16 0) (length 2.54)
          (name "CLKREQB" (effects (font (size 1.27 1.27))))
          (number "12" (effects (font (size 1.27 1.27))))
        )
        (pin input line (at 0 -25.4 0) (length 2.54)
          (name "HSIP" (effects (font (size 1.27 1.27))))
          (number "13" (effects (font (size 1.27 1.27))))
        )
        (pin input line (at 0 -22.86 0) (length 2.54)
          (name "HSIN" (effects (font (size 1.27 1.27))))
          (number "14" (effects (font (size 1.27 1.27))))
        )
        (pin input line (at 0 -17.78 0) (length 2.54)
          (name "REFCLK_P" (effects (font (size 1.27 1.27))))
          (number "15" (effects (font (size 1.27 1.27))))
        )
        (pin input line (at 0 -20.32 0) (length 2.54)
          (name "REFCLK_N" (effects (font (size 1.27 1.27))))
          (number "16" (effects (font (size 1.27 1.27))))
        )
        (pin output line (at 0 -30.48 0) (length 2.54)
          (name "HSOP" (effects (font (size 1.27 1.27))))
          (number "17" (effects (font (size 1.27 1.27))))
        )
        (pin output line (at 0 -27.94 0) (length 2.54)
          (name "HSON" (effects (font (size 1.27 1.27))))
          (number "18" (effects (font (size 1.27 1.27))))
        )
        (pin input line (at 0 -15.24 0) (length 2.54)
          (name "PERSTB" (effects (font (size 1.27 1.27))))
          (number "19" (effects (font (size 1.27 1.27))))
        )
        (pin bidirectional line (at 27.94 -19.05 180) (length 2.54)
          (name "MDIN0" (effects (font (size 1.27 1.27))))
          (number "2" (effects (font (size 1.27 1.27))))
        )
        (pin open_collector line (at 0 -43.18 0) (length 2.54)
          (name "ISOLATEB" (effects (font (size 1.27 1.27))))
          (number "20" (effects (font (size 1.27 1.27))))
        )
        (pin output line (at 0 -12.7 0) (length 2.54)
          (name "LANWAKEB" (effects (font (size 1.27 1.27))))
          (number "21" (effects (font (size 1.27 1.27))))
        )
        (pin power_in line (at 27.94 -5.08 180) (length 2.54)
          (name "DVDD10" (effects (font (size 1.27 1.27))))
          (number "22" (effects (font (size 1.27 1.27))))
        )
        (pin power_in line (at 0 0 0) (length 2.54)
          (name "VDDREG" (effects (font (size 1.27 1.27))))
          (number "23" (effects (font (size 1.27 1.27))))
        )
        (pin output line (at 27.94 0 180) (length 2.54)
          (name "REGOUT" (effects (font (size 1.27 1.27))))
          (number "24" (effects (font (size 1.27 1.27))))
        )
        (pin output line (at 27.94 -48.26 180) (length 2.54)
          (name "LED2" (effects (font (size 1.27 1.27))))
          (number "25" (effects (font (size 1.27 1.27))))
        )
        (pin output line (at 27.94 -45.72 180) (length 2.54)
          (name "LED1/GPO" (effects (font (size 1.27 1.27))))
          (number "26" (effects (font (size 1.27 1.27))))
        )
        (pin output line (at 27.94 -43.18 180) (length 2.54)
          (name "LED0" (effects (font (size 1.27 1.27))))
          (number "27" (effects (font (size 1.27 1.27))))
        )
        (pin input line (at 0 -35.56 0) (length 2.54)
          (name "CKXTAL1" (effects (font (size 1.27 1.27))))
          (number "28" (effects (font (size 1.27 1.27))))
        )
        (pin input line (at 0 -38.1 0) (length 2.54)
          (name "CKXTAL2" (effects (font (size 1.27 1.27))))
          (number "29" (effects (font (size 1.27 1.27))))
        )
        (pin power_in line (at 27.94 -7.62 180) (length 2.54)
          (name "AVDD10" (effects (font (size 1.27 1.27))))
          (number "3" (effects (font (size 1.27 1.27))))
        )
        (pin power_in line (at 27.94 -12.7 180) (length 2.54)
          (name "AVD10_2" (effects (font (size 1.27 1.27))))
          (number "30" (effects (font (size 1.27 1.27))))
        )
        (pin input line (at 0 -45.72 0) (length 2.54)
          (name "RSET" (effects (font (size 1.27 1.27))))
          (number "31" (effects (font (size 1.27 1.27))))
        )
        (pin input line (at 0 -5.08 0) (length 2.54)
          (name "AVDD33_2" (effects (font (size 1.27 1.27))))
          (number "32" (effects (font (size 1.27 1.27))))
        )
        (pin power_in line (at 0 -48.26 0) (length 2.54)
          (name "GND" (effects (font (size 1.27 1.27))))
          (number "33" (effects (font (size 1.27 1.27))))
        )
        (pin bidirectional line (at 27.94 -26.67 180) (length 2.54)
          (name "MDIP1" (effects (font (size 1.27 1.27))))
          (number "4" (effects (font (size 1.27 1.27))))
        )
        (pin bidirectional line (at 27.94 -24.13 180) (length 2.54)
          (name "MDIN1" (effects (font (size 1.27 1.27))))
          (number "5" (effects (font (size 1.27 1.27))))
        )
        (pin bidirectional line (at 27.94 -31.75 180) (length 2.54)
          (name "MDIP2" (effects (font (size 1.27 1.27))))
          (number "6" (effects (font (size 1.27 1.27))))
        )
        (pin bidirectional line (at 27.94 -29.21 180) (length 2.54)
          (name "MDIN2" (effects (font (size 1.27 1.27))))
          (number "7" (effects (font (size 1.27 1.27))))
        )
        (pin power_in line (at 27.94 -10.16 180) (length 2.54)
          (name "AVDD10_1" (effects (font (size 1.27 1.27))))
          (number "8" (effects (font (size 1.27 1.27))))
        )
        (pin bidirectional line (at 27.94 -36.83 180) (length 2.54)
          (name "MDIP3" (effects (font (size 1.27 1.27))))
          (number "9" (effects (font (size 1.27 1.27))))
        )
      )
    )
	(symbol "sa800u-baseboard-hw:R_0R_0402" (pin_numbers hide) (pin_names hide) (in_bom yes) (on_board yes)
      (property "Reference" "R" (id 0) (at 20.32 -5.08 0)
        (effects (font (size 1.27 1.27) (thickness 0.15)) (justify left bottom))
      )
      (property "Value" "R_0R_0402" (id 1) (at 20.32 -12.7 0)
        (effects (font (size 1.27 1.27) (thickness 0.15)) (justify left bottom) hide)
      )
      (property "Footprint" "sa800u-baseboard-hw-footprints:R_0402_1005Metric" (id 2) (at 20.32 -15.24 0)
        (effects (font (size 1.27 1.27) (thickness 0.15)) (justify left bottom) hide)
      )
      (property "Datasheet" "https://industrial.panasonic.com/cdbs/www-data/pdf/RDA0000/AOA0000C301.pdf" (id 3) (at 20.32 -17.78 0)
        (effects (font (size 1.27 1.27) (thickness 0.15)) (justify left bottom) hide)
      )
      (property "MPN" "ERJ2GE0R00X" (id 4) (at 20.32 -20.32 0)
        (effects (font (size 1.27 1.27) (thickness 0.15)) (justify left bottom) hide)
      )
      (property "Manufacturer" "Panasonic" (id 5) (at 20.32 -22.86 0)
        (effects (font (size 1.27 1.27) (thickness 0.15)) (justify left bottom) hide)
      )
      (property "License" "Apache-2.0" (id 6) (at 20.32 -25.4 0)
        (effects (font (size 1.27 1.27) (thickness 0.15)) (justify left bottom) hide)
      )
      (property "Author" "Antmicro" (id 7) (at 20.32 -27.94 0)
        (effects (font (size 1.27 1.27) (thickness 0.15)) (justify left bottom) hide)
      )
      (property "Val" "0R" (id 8) (at 20.32 -7.62 0)
        (effects (font (size 1.27 1.27) (thickness 0.15)) (justify left bottom))
      )
      (property "Tolerance" "~" (id 9) (at 20.32 -10.16 0)
        (effects (font (size 1.27 1.27)) (justify left bottom) hide)
      )
      (property "Current" "1A" (id 10) (at 20.32 -30.48 0)
        (effects (font (size 1.27 1.27) (thickness 0.15)) (justify left bottom) hide)
      )
      (property "ki_description" "0R resistor in 0402 package with unspecified tolerance" (id 11) (at 0 0 0)
        (effects (font (size 1.27 1.27)) hide)
      )
      (symbol "R_0R_0402_0_1"
        (rectangle (start 0.635 0.889) (end 4.445 -0.889)
          (stroke (width 0.254) (type default) (color 0 0 0 0))
          (fill (type none))
        )
      )
      (symbol "R_0R_0402_1_1"
        (pin passive line (at 0 0 0) (length 0.635)
          (name "~" (effects (font (size 1.27 1.27))))
          (number "1" (effects (font (size 1.27 1.27))))
        )
        (pin passive line (at 5.08 0 180) (length 0.635)
          (name "~" (effects (font (size 1.27 1.27))))
          (number "2" (effects (font (size 1.27 1.27))))
        )
      )
    )
	(symbol "sa800u-baseboard-hw:R_0R_0603" (pin_numbers hide) (pin_names hide) (in_bom yes) (on_board yes)
      (property "Reference" "R" (id 0) (at 20.32 -5.08 0)
        (effects (font (size 1.27 1.27) (thickness 0.15)) (justify left bottom))
      )
      (property "Value" "R_0R_0603" (id 1) (at 20.32 -12.7 0)
        (effects (font (size 1.27 1.27) (thickness 0.15)) (justify left bottom) hide)
      )
      (property "Footprint" "sa800u-baseboard-hw-footprints:R_0603_1608Metric" (id 2) (at 20.32 -15.24 0)
        (effects (font (size 1.27 1.27) (thickness 0.15)) (justify left bottom) hide)
      )
      (property "Datasheet" "https://www.bourns.com/docs/product-datasheets/cr.pdf?sfvrsn=574d41f6_14" (id 3) (at 20.32 -17.78 0)
        (effects (font (size 1.27 1.27) (thickness 0.15)) (justify left bottom) hide)
      )
      (property "MPN" "CR0603-J/-000ELF" (id 4) (at 20.32 -20.32 0)
        (effects (font (size 1.27 1.27) (thickness 0.15)) (justify left bottom) hide)
      )
      (property "Manufacturer" "Bourns" (id 5) (at 20.32 -22.86 0)
        (effects (font (size 1.27 1.27) (thickness 0.15)) (justify left bottom) hide)
      )
      (property "License" "Apache-2.0" (id 6) (at 20.32 -25.4 0)
        (effects (font (size 1.27 1.27) (thickness 0.15)) (justify left bottom) hide)
      )
      (property "Author" "Antmicro" (id 7) (at 20.32 -27.94 0)
        (effects (font (size 1.27 1.27) (thickness 0.15)) (justify left bottom) hide)
      )
      (property "Val" "0R" (id 8) (at 20.32 -7.62 0)
        (effects (font (size 1.27 1.27) (thickness 0.15)) (justify left bottom))
      )
      (property "Tolerance" "~" (id 9) (at 20.32 -10.16 0)
        (effects (font (size 1.27 1.27)) (justify left bottom) hide)
      )
      (property "Current" "1A" (id 10) (at 20.32 -30.48 0)
        (effects (font (size 1.27 1.27) (thickness 0.15)) (justify left bottom) hide)
      )
      (property "ki_description" "0R resistor in 0603 package with unspecified tolerance" (id 11) (at 0 0 0)
        (effects (font (size 1.27 1.27)) hide)
      )
      (symbol "R_0R_0603_0_1"
        (rectangle (start 0.635 0.889) (end 4.445 -0.889)
          (stroke (width 0.254) (type default) (color 0 0 0 0))
          (fill (type none))
        )
      )
      (symbol "R_0R_0603_1_1"
        (pin passive line (at 0 0 0) (length 0.635)
          (name "~" (effects (font (size 1.27 1.27))))
          (number "1" (effects (font (size 1.27 1.27))))
        )
        (pin passive line (at 5.08 0 180) (length 0.635)
          (name "~" (effects (font (size 1.27 1.27))))
          (number "2" (effects (font (size 1.27 1.27))))
        )
      )
    )
	(symbol "sa800u-baseboard-hw:R_100R_0402" (pin_numbers hide) (pin_names hide) (in_bom yes) (on_board yes)
      (property "Reference" "R" (id 0) (at 20.32 -5.08 0)
        (effects (font (size 1.27 1.27) (thickness 0.15)) (justify left bottom))
      )
      (property "Value" "R_100R_0402" (id 1) (at 20.32 -12.7 0)
        (effects (font (size 1.27 1.27) (thickness 0.15)) (justify left bottom) hide)
      )
      (property "Footprint" "sa800u-baseboard-hw-footprints:R_0402_1005Metric" (id 2) (at 20.32 -15.24 0)
        (effects (font (size 1.27 1.27) (thickness 0.15)) (justify left bottom) hide)
      )
      (property "Datasheet" "https://www.bourns.com/docs/product-datasheets/cr.pdf" (id 3) (at 20.32 -17.78 0)
        (effects (font (size 1.27 1.27) (thickness 0.15)) (justify left bottom) hide)
      )
      (property "MPN" "CR0402-FX-1000GLF" (id 4) (at 20.32 -20.32 0)
        (effects (font (size 1.27 1.27) (thickness 0.15)) (justify left bottom) hide)
      )
      (property "Manufacturer" "Bourns" (id 5) (at 20.32 -22.86 0)
        (effects (font (size 1.27 1.27) (thickness 0.15)) (justify left bottom) hide)
      )
      (property "License" "Apache-2.0" (id 6) (at 20.32 -25.4 0)
        (effects (font (size 1.27 1.27) (thickness 0.15)) (justify left bottom) hide)
      )
      (property "Author" "Antmicro" (id 7) (at 20.32 -27.94 0)
        (effects (font (size 1.27 1.27) (thickness 0.15)) (justify left bottom) hide)
      )
      (property "Val" "100R" (id 8) (at 20.32 -7.62 0)
        (effects (font (size 1.27 1.27) (thickness 0.15)) (justify left bottom))
      )
      (property "Tolerance" "1%" (id 9) (at 20.32 -10.16 0)
        (effects (font (size 1.27 1.27)) (justify left bottom) hide)
      )
      (property "ki_description" "100R resistor in 0402 package with 1% tolerance" (id 10) (at 0 0 0)
        (effects (font (size 1.27 1.27)) hide)
      )
      (symbol "R_100R_0402_0_1"
        (rectangle (start 0.635 0.889) (end 4.445 -0.889)
          (stroke (width 0.254) (type default) (color 0 0 0 0))
          (fill (type none))
        )
      )
      (symbol "R_100R_0402_1_1"
        (pin passive line (at 0 0 0) (length 0.635)
          (name "~" (effects (font (size 1.27 1.27))))
          (number "1" (effects (font (size 1.27 1.27))))
        )
        (pin passive line (at 5.08 0 180) (length 0.635)
          (name "~" (effects (font (size 1.27 1.27))))
          (number "2" (effects (font (size 1.27 1.27))))
        )
      )
    )
	(symbol "sa800u-baseboard-hw:R_100k_0.5%_0402" (pin_numbers hide) (pin_names hide) (in_bom yes) (on_board yes)
      (property "Reference" "R" (id 0) (at 15.24 -5.08 0)
        (effects (font (size 1.27 1.27) (thickness 0.15)) (justify left bottom))
      )
      (property "Value" "R_100k_0.5%_0402" (id 1) (at 15.24 -10.16 0)
        (effects (font (size 1.27 1.27) (thickness 0.15)) (justify left bottom) hide)
      )
      (property "Footprint" "sa800u-baseboard-hw-footprints:R_0402_1005Metric" (id 2) (at 15.24 -12.7 0)
        (effects (font (size 1.27 1.27) (thickness 0.15)) (justify left bottom) hide)
      )
      (property "Datasheet" "template_datasheet" (id 3) (at 20.32 -17.78 0)
        (effects (font (size 1.27 1.27) (thickness 0.15)) (justify left bottom) hide)
      )
      (property "Val" "100k_0.5%" (id 4) (at 15.24 -7.62 0)
        (effects (font (size 1.27 1.27) (thickness 0.15)) (justify left bottom))
      )
      (property "MPN" "ERA2AED104X" (id 5) (at 15.24 -17.78 0)
        (effects (font (size 1.27 1.27) (thickness 0.15)) (justify left bottom) hide)
      )
      (property "Manufacturer" "Panasonic" (id 6) (at 15.24 -20.32 0)
        (effects (font (size 1.27 1.27) (thickness 0.15)) (justify left bottom) hide)
      )
      (property "Author" "Antmicro" (id 7) (at 15.24 -22.86 0)
        (effects (font (size 1.27 1.27) (thickness 0.15)) (justify left bottom) hide)
      )
      (property "License" "Apache-2.0" (id 8) (at 15.24 -25.4 0)
        (effects (font (size 1.27 1.27) (thickness 0.15)) (justify left bottom) hide)
      )
      (property "Tolerance" "template_tolerance" (id 9) (at 20.32 -10.16 0)
        (effects (font (size 1.27 1.27)) (justify left bottom) hide)
      )
      (property "ki_description" "template_value resistor in 0402 package with template_tolerance tolerance" (id 10) (at 0 0 0)
        (effects (font (size 1.27 1.27)) hide)
      )
      (symbol "R_100k_0.5%_0402_0_1"
        (rectangle (start 0.635 0.889) (end 4.445 -0.889)
          (stroke (width 0.254) (type default) (color 0 0 0 0))
          (fill (type none))
        )
      )
      (symbol "R_100k_0.5%_0402_1_1"
        (pin passive line (at 0 0 0) (length 0.635)
          (name "~" (effects (font (size 1.27 1.27))))
          (number "1" (effects (font (size 1.27 1.27))))
        )
        (pin passive line (at 5.08 0 180) (length 0.635)
          (name "~" (effects (font (size 1.27 1.27))))
          (number "2" (effects (font (size 1.27 1.27))))
        )
      )
    )
	(symbol "sa800u-baseboard-hw:R_100k_0402" (pin_numbers hide) (pin_names hide) (in_bom yes) (on_board yes)
      (property "Reference" "R" (id 0) (at 20.32 -5.08 0)
        (effects (font (size 1.27 1.27) (thickness 0.15)) (justify left bottom))
      )
      (property "Value" "R_100k_0402" (id 1) (at 20.32 -12.7 0)
        (effects (font (size 1.27 1.27) (thickness 0.15)) (justify left bottom) hide)
      )
      (property "Footprint" "sa800u-baseboard-hw-footprints:R_0402_1005Metric" (id 2) (at 20.32 -15.24 0)
        (effects (font (size 1.27 1.27) (thickness 0.15)) (justify left bottom) hide)
      )
      (property "Datasheet" "https://www.bourns.com/docs/product-datasheets/cr.pdf" (id 3) (at 20.32 -17.78 0)
        (effects (font (size 1.27 1.27) (thickness 0.15)) (justify left bottom) hide)
      )
      (property "MPN" "CR0402-FX-1003GLF" (id 4) (at 20.32 -20.32 0)
        (effects (font (size 1.27 1.27) (thickness 0.15)) (justify left bottom) hide)
      )
      (property "Manufacturer" "Bourns" (id 5) (at 20.32 -22.86 0)
        (effects (font (size 1.27 1.27) (thickness 0.15)) (justify left bottom) hide)
      )
      (property "License" "Apache-2.0" (id 6) (at 20.32 -25.4 0)
        (effects (font (size 1.27 1.27) (thickness 0.15)) (justify left bottom) hide)
      )
      (property "Author" "Antmicro" (id 7) (at 20.32 -27.94 0)
        (effects (font (size 1.27 1.27) (thickness 0.15)) (justify left bottom) hide)
      )
      (property "Val" "100k" (id 8) (at 20.32 -7.62 0)
        (effects (font (size 1.27 1.27) (thickness 0.15)) (justify left bottom))
      )
      (property "Tolerance" "1%" (id 9) (at 20.32 -10.16 0)
        (effects (font (size 1.27 1.27)) (justify left bottom) hide)
      )
      (property "ki_description" "100k resistor in 0402 package with 1% tolerance" (id 10) (at 0 0 0)
        (effects (font (size 1.27 1.27)) hide)
      )
      (symbol "R_100k_0402_0_1"
        (rectangle (start 0.635 0.889) (end 4.445 -0.889)
          (stroke (width 0.254) (type default) (color 0 0 0 0))
          (fill (type none))
        )
      )
      (symbol "R_100k_0402_1_1"
        (pin passive line (at 0 0 0) (length 0.635)
          (name "~" (effects (font (size 1.27 1.27))))
          (number "1" (effects (font (size 1.27 1.27))))
        )
        (pin passive line (at 5.08 0 180) (length 0.635)
          (name "~" (effects (font (size 1.27 1.27))))
          (number "2" (effects (font (size 1.27 1.27))))
        )
      )
    )
	(symbol "sa800u-baseboard-hw:R_10k_0402" (pin_numbers hide) (pin_names hide) (in_bom yes) (on_board yes)
      (property "Reference" "R" (id 0) (at 20.32 -5.08 0)
        (effects (font (size 1.27 1.27) (thickness 0.15)) (justify left bottom))
      )
      (property "Value" "R_10k_0402" (id 1) (at 20.32 -12.7 0)
        (effects (font (size 1.27 1.27) (thickness 0.15)) (justify left bottom) hide)
      )
      (property "Footprint" "sa800u-baseboard-hw-footprints:R_0402_1005Metric" (id 2) (at 20.32 -15.24 0)
        (effects (font (size 1.27 1.27) (thickness 0.15)) (justify left bottom) hide)
      )
      (property "Datasheet" "https://www.bourns.com/docs/product-datasheets/cr.pdf" (id 3) (at 20.32 -17.78 0)
        (effects (font (size 1.27 1.27) (thickness 0.15)) (justify left bottom) hide)
      )
      (property "MPN" "CR0402-FX-1002GLF" (id 4) (at 20.32 -20.32 0)
        (effects (font (size 1.27 1.27) (thickness 0.15)) (justify left bottom) hide)
      )
      (property "Manufacturer" "Bourns" (id 5) (at 20.32 -22.86 0)
        (effects (font (size 1.27 1.27) (thickness 0.15)) (justify left bottom) hide)
      )
      (property "License" "Apache-2.0" (id 6) (at 20.32 -25.4 0)
        (effects (font (size 1.27 1.27) (thickness 0.15)) (justify left bottom) hide)
      )
      (property "Author" "Antmicro" (id 7) (at 20.32 -27.94 0)
        (effects (font (size 1.27 1.27) (thickness 0.15)) (justify left bottom) hide)
      )
      (property "Val" "10k" (id 8) (at 20.32 -7.62 0)
        (effects (font (size 1.27 1.27) (thickness 0.15)) (justify left bottom))
      )
      (property "Tolerance" "1%" (id 9) (at 20.32 -10.16 0)
        (effects (font (size 1.27 1.27)) (justify left bottom) hide)
      )
      (property "ki_description" "10k resistor in 0402 package with 1% tolerance" (id 10) (at 0 0 0)
        (effects (font (size 1.27 1.27)) hide)
      )
      (symbol "R_10k_0402_0_1"
        (rectangle (start 0.635 0.889) (end 4.445 -0.889)
          (stroke (width 0.254) (type default) (color 0 0 0 0))
          (fill (type none))
        )
      )
      (symbol "R_10k_0402_1_1"
        (pin passive line (at 0 0 0) (length 0.635)
          (name "~" (effects (font (size 1.27 1.27))))
          (number "1" (effects (font (size 1.27 1.27))))
        )
        (pin passive line (at 5.08 0 180) (length 0.635)
          (name "~" (effects (font (size 1.27 1.27))))
          (number "2" (effects (font (size 1.27 1.27))))
        )
      )
    )
	(symbol "sa800u-baseboard-hw:R_10k_0402_10" (pin_numbers hide) (pin_names hide) (in_bom yes) (on_board yes)
      (property "Reference" "R" (id 0) (at 20.32 -5.08 0)
        (effects (font (size 1.27 1.27) (thickness 0.15)) (justify left bottom))
      )
      (property "Value" "R_10k_0402_10" (id 1) (at 20.32 -12.7 0)
        (effects (font (size 1.27 1.27) (thickness 0.15)) (justify left bottom) hide)
      )
      (property "Footprint" "sa800u-baseboard-hw-footprints:R_0402_1005Metric" (id 2) (at 20.32 -15.24 0)
        (effects (font (size 1.27 1.27) (thickness 0.15)) (justify left bottom) hide)
      )
      (property "Datasheet" "https://www.bourns.com/docs/product-datasheets/cr.pdf" (id 3) (at 20.32 -17.78 0)
        (effects (font (size 1.27 1.27) (thickness 0.15)) (justify left bottom) hide)
      )
      (property "MPN" "CR0402-FX-1002GLF" (id 4) (at 20.32 -20.32 0)
        (effects (font (size 1.27 1.27) (thickness 0.15)) (justify left bottom) hide)
      )
      (property "Manufacturer" "Bourns" (id 5) (at 20.32 -22.86 0)
        (effects (font (size 1.27 1.27) (thickness 0.15)) (justify left bottom) hide)
      )
      (property "License" "Apache-2.0" (id 6) (at 20.32 -25.4 0)
        (effects (font (size 1.27 1.27) (thickness 0.15)) (justify left bottom) hide)
      )
      (property "Author" "Antmicro" (id 7) (at 20.32 -27.94 0)
        (effects (font (size 1.27 1.27) (thickness 0.15)) (justify left bottom) hide)
      )
      (property "Val" "10k" (id 8) (at 20.32 -7.62 0)
        (effects (font (size 1.27 1.27) (thickness 0.15)) (justify left bottom))
      )
      (property "Tolerance" "1%" (id 9) (at 20.32 -10.16 0)
        (effects (font (size 1.27 1.27)) (justify left bottom) hide)
      )
      (property "ki_description" "10k resistor in 0402 package with 1% tolerance" (id 10) (at 0 0 0)
        (effects (font (size 1.27 1.27)) hide)
      )
      (symbol "R_10k_0402_10_0_1"
        (rectangle (start 0.635 0.889) (end 4.445 -0.889)
          (stroke (width 0.254) (type default) (color 0 0 0 0))
          (fill (type none))
        )
      )
      (symbol "R_10k_0402_10_1_1"
        (pin passive line (at 0 0 0) (length 0.635)
          (name "~" (effects (font (size 1.27 1.27))))
          (number "1" (effects (font (size 1.27 1.27))))
        )
        (pin passive line (at 5.08 0 180) (length 0.635)
          (name "~" (effects (font (size 1.27 1.27))))
          (number "2" (effects (font (size 1.27 1.27))))
        )
      )
    )
	(symbol "sa800u-baseboard-hw:R_10k_0402_11" (pin_numbers hide) (pin_names hide) (in_bom yes) (on_board yes)
      (property "Reference" "R" (id 0) (at 20.32 -5.08 0)
        (effects (font (size 1.27 1.27) (thickness 0.15)) (justify left bottom))
      )
      (property "Value" "R_10k_0402_11" (id 1) (at 20.32 -12.7 0)
        (effects (font (size 1.27 1.27) (thickness 0.15)) (justify left bottom) hide)
      )
      (property "Footprint" "sa800u-baseboard-hw-footprints:R_0402_1005Metric" (id 2) (at 20.32 -15.24 0)
        (effects (font (size 1.27 1.27) (thickness 0.15)) (justify left bottom) hide)
      )
      (property "Datasheet" "https://www.bourns.com/docs/product-datasheets/cr.pdf" (id 3) (at 20.32 -17.78 0)
        (effects (font (size 1.27 1.27) (thickness 0.15)) (justify left bottom) hide)
      )
      (property "MPN" "CR0402-FX-1002GLF" (id 4) (at 20.32 -20.32 0)
        (effects (font (size 1.27 1.27) (thickness 0.15)) (justify left bottom) hide)
      )
      (property "Manufacturer" "Bourns" (id 5) (at 20.32 -22.86 0)
        (effects (font (size 1.27 1.27) (thickness 0.15)) (justify left bottom) hide)
      )
      (property "License" "Apache-2.0" (id 6) (at 20.32 -25.4 0)
        (effects (font (size 1.27 1.27) (thickness 0.15)) (justify left bottom) hide)
      )
      (property "Author" "Antmicro" (id 7) (at 20.32 -27.94 0)
        (effects (font (size 1.27 1.27) (thickness 0.15)) (justify left bottom) hide)
      )
      (property "Val" "10k" (id 8) (at 20.32 -7.62 0)
        (effects (font (size 1.27 1.27) (thickness 0.15)) (justify left bottom))
      )
      (property "Tolerance" "1%" (id 9) (at 20.32 -10.16 0)
        (effects (font (size 1.27 1.27)) (justify left bottom) hide)
      )
      (property "ki_description" "10k resistor in 0402 package with 1% tolerance" (id 10) (at 0 0 0)
        (effects (font (size 1.27 1.27)) hide)
      )
      (symbol "R_10k_0402_11_0_1"
        (rectangle (start 0.635 0.889) (end 4.445 -0.889)
          (stroke (width 0.254) (type default) (color 0 0 0 0))
          (fill (type none))
        )
      )
      (symbol "R_10k_0402_11_1_1"
        (pin passive line (at 0 0 0) (length 0.635)
          (name "~" (effects (font (size 1.27 1.27))))
          (number "1" (effects (font (size 1.27 1.27))))
        )
        (pin passive line (at 5.08 0 180) (length 0.635)
          (name "~" (effects (font (size 1.27 1.27))))
          (number "2" (effects (font (size 1.27 1.27))))
        )
      )
    )
	(symbol "sa800u-baseboard-hw:R_10k_0402_12" (pin_numbers hide) (pin_names hide) (in_bom yes) (on_board yes)
      (property "Reference" "R" (id 0) (at 20.32 -5.08 0)
        (effects (font (size 1.27 1.27) (thickness 0.15)) (justify left bottom))
      )
      (property "Value" "R_10k_0402_12" (id 1) (at 20.32 -12.7 0)
        (effects (font (size 1.27 1.27) (thickness 0.15)) (justify left bottom) hide)
      )
      (property "Footprint" "sa800u-baseboard-hw-footprints:R_0402_1005Metric" (id 2) (at 20.32 -15.24 0)
        (effects (font (size 1.27 1.27) (thickness 0.15)) (justify left bottom) hide)
      )
      (property "Datasheet" "https://www.bourns.com/docs/product-datasheets/cr.pdf" (id 3) (at 20.32 -17.78 0)
        (effects (font (size 1.27 1.27) (thickness 0.15)) (justify left bottom) hide)
      )
      (property "MPN" "CR0402-FX-1002GLF" (id 4) (at 20.32 -20.32 0)
        (effects (font (size 1.27 1.27) (thickness 0.15)) (justify left bottom) hide)
      )
      (property "Manufacturer" "Bourns" (id 5) (at 20.32 -22.86 0)
        (effects (font (size 1.27 1.27) (thickness 0.15)) (justify left bottom) hide)
      )
      (property "License" "Apache-2.0" (id 6) (at 20.32 -25.4 0)
        (effects (font (size 1.27 1.27) (thickness 0.15)) (justify left bottom) hide)
      )
      (property "Author" "Antmicro" (id 7) (at 20.32 -27.94 0)
        (effects (font (size 1.27 1.27) (thickness 0.15)) (justify left bottom) hide)
      )
      (property "Val" "10k" (id 8) (at 20.32 -7.62 0)
        (effects (font (size 1.27 1.27) (thickness 0.15)) (justify left bottom))
      )
      (property "Tolerance" "1%" (id 9) (at 20.32 -10.16 0)
        (effects (font (size 1.27 1.27)) (justify left bottom) hide)
      )
      (property "ki_description" "10k resistor in 0402 package with 1% tolerance" (id 10) (at 0 0 0)
        (effects (font (size 1.27 1.27)) hide)
      )
      (symbol "R_10k_0402_12_0_1"
        (rectangle (start 0.635 0.889) (end 4.445 -0.889)
          (stroke (width 0.254) (type default) (color 0 0 0 0))
          (fill (type none))
        )
      )
      (symbol "R_10k_0402_12_1_1"
        (pin passive line (at 0 0 0) (length 0.635)
          (name "~" (effects (font (size 1.27 1.27))))
          (number "1" (effects (font (size 1.27 1.27))))
        )
        (pin passive line (at 5.08 0 180) (length 0.635)
          (name "~" (effects (font (size 1.27 1.27))))
          (number "2" (effects (font (size 1.27 1.27))))
        )
      )
    )
	(symbol "sa800u-baseboard-hw:R_10k_0402_13" (pin_numbers hide) (pin_names hide) (in_bom yes) (on_board yes)
      (property "Reference" "R" (id 0) (at 20.32 -5.08 0)
        (effects (font (size 1.27 1.27) (thickness 0.15)) (justify left bottom))
      )
      (property "Value" "R_10k_0402_13" (id 1) (at 20.32 -12.7 0)
        (effects (font (size 1.27 1.27) (thickness 0.15)) (justify left bottom) hide)
      )
      (property "Footprint" "sa800u-baseboard-hw-footprints:R_0402_1005Metric" (id 2) (at 20.32 -15.24 0)
        (effects (font (size 1.27 1.27) (thickness 0.15)) (justify left bottom) hide)
      )
      (property "Datasheet" "https://www.bourns.com/docs/product-datasheets/cr.pdf" (id 3) (at 20.32 -17.78 0)
        (effects (font (size 1.27 1.27) (thickness 0.15)) (justify left bottom) hide)
      )
      (property "MPN" "CR0402-FX-1002GLF" (id 4) (at 20.32 -20.32 0)
        (effects (font (size 1.27 1.27) (thickness 0.15)) (justify left bottom) hide)
      )
      (property "Manufacturer" "Bourns" (id 5) (at 20.32 -22.86 0)
        (effects (font (size 1.27 1.27) (thickness 0.15)) (justify left bottom) hide)
      )
      (property "License" "Apache-2.0" (id 6) (at 20.32 -25.4 0)
        (effects (font (size 1.27 1.27) (thickness 0.15)) (justify left bottom) hide)
      )
      (property "Author" "Antmicro" (id 7) (at 20.32 -27.94 0)
        (effects (font (size 1.27 1.27) (thickness 0.15)) (justify left bottom) hide)
      )
      (property "Val" "10k" (id 8) (at 20.32 -7.62 0)
        (effects (font (size 1.27 1.27) (thickness 0.15)) (justify left bottom))
      )
      (property "Tolerance" "1%" (id 9) (at 20.32 -10.16 0)
        (effects (font (size 1.27 1.27)) (justify left bottom) hide)
      )
      (property "ki_description" "10k resistor in 0402 package with 1% tolerance" (id 10) (at 0 0 0)
        (effects (font (size 1.27 1.27)) hide)
      )
      (symbol "R_10k_0402_13_0_1"
        (rectangle (start 0.635 0.889) (end 4.445 -0.889)
          (stroke (width 0.254) (type default) (color 0 0 0 0))
          (fill (type none))
        )
      )
      (symbol "R_10k_0402_13_1_1"
        (pin passive line (at 0 0 0) (length 0.635)
          (name "~" (effects (font (size 1.27 1.27))))
          (number "1" (effects (font (size 1.27 1.27))))
        )
        (pin passive line (at 5.08 0 180) (length 0.635)
          (name "~" (effects (font (size 1.27 1.27))))
          (number "2" (effects (font (size 1.27 1.27))))
        )
      )
    )
	(symbol "sa800u-baseboard-hw:R_10k_0402_14" (pin_numbers hide) (pin_names hide) (in_bom yes) (on_board yes)
      (property "Reference" "R" (id 0) (at 20.32 -5.08 0)
        (effects (font (size 1.27 1.27) (thickness 0.15)) (justify left bottom))
      )
      (property "Value" "R_10k_0402_14" (id 1) (at 20.32 -12.7 0)
        (effects (font (size 1.27 1.27) (thickness 0.15)) (justify left bottom) hide)
      )
      (property "Footprint" "sa800u-baseboard-hw-footprints:R_0402_1005Metric" (id 2) (at 20.32 -15.24 0)
        (effects (font (size 1.27 1.27) (thickness 0.15)) (justify left bottom) hide)
      )
      (property "Datasheet" "https://www.bourns.com/docs/product-datasheets/cr.pdf" (id 3) (at 20.32 -17.78 0)
        (effects (font (size 1.27 1.27) (thickness 0.15)) (justify left bottom) hide)
      )
      (property "MPN" "CR0402-FX-1002GLF" (id 4) (at 20.32 -20.32 0)
        (effects (font (size 1.27 1.27) (thickness 0.15)) (justify left bottom) hide)
      )
      (property "Manufacturer" "Bourns" (id 5) (at 20.32 -22.86 0)
        (effects (font (size 1.27 1.27) (thickness 0.15)) (justify left bottom) hide)
      )
      (property "License" "Apache-2.0" (id 6) (at 20.32 -25.4 0)
        (effects (font (size 1.27 1.27) (thickness 0.15)) (justify left bottom) hide)
      )
      (property "Author" "Antmicro" (id 7) (at 20.32 -27.94 0)
        (effects (font (size 1.27 1.27) (thickness 0.15)) (justify left bottom) hide)
      )
      (property "Val" "10k" (id 8) (at 20.32 -7.62 0)
        (effects (font (size 1.27 1.27) (thickness 0.15)) (justify left bottom))
      )
      (property "Tolerance" "1%" (id 9) (at 20.32 -10.16 0)
        (effects (font (size 1.27 1.27)) (justify left bottom) hide)
      )
      (property "ki_description" "10k resistor in 0402 package with 1% tolerance" (id 10) (at 0 0 0)
        (effects (font (size 1.27 1.27)) hide)
      )
      (symbol "R_10k_0402_14_0_1"
        (rectangle (start 0.635 0.889) (end 4.445 -0.889)
          (stroke (width 0.254) (type default) (color 0 0 0 0))
          (fill (type none))
        )
      )
      (symbol "R_10k_0402_14_1_1"
        (pin passive line (at 0 0 0) (length 0.635)
          (name "~" (effects (font (size 1.27 1.27))))
          (number "1" (effects (font (size 1.27 1.27))))
        )
        (pin passive line (at 5.08 0 180) (length 0.635)
          (name "~" (effects (font (size 1.27 1.27))))
          (number "2" (effects (font (size 1.27 1.27))))
        )
      )
    )
	(symbol "sa800u-baseboard-hw:R_10k_0603" (pin_numbers hide) (pin_names hide) (in_bom yes) (on_board yes)
      (property "Reference" "R" (id 0) (at 20.32 -5.08 0)
        (effects (font (size 1.27 1.27) (thickness 0.15)) (justify left bottom))
      )
      (property "Value" "R_10k_0603" (id 1) (at 20.32 -12.7 0)
        (effects (font (size 1.27 1.27) (thickness 0.15)) (justify left bottom) hide)
      )
      (property "Footprint" "sa800u-baseboard-hw-footprints:R_0603_1608Metric" (id 2) (at 20.32 -15.24 0)
        (effects (font (size 1.27 1.27) (thickness 0.15)) (justify left bottom) hide)
      )
      (property "Datasheet" "https://www.bourns.com/docs/product-datasheets/cr.pdf" (id 3) (at 20.32 -17.78 0)
        (effects (font (size 1.27 1.27) (thickness 0.15)) (justify left bottom) hide)
      )
      (property "MPN" "CR0603-FX-1002ELF" (id 4) (at 20.32 -20.32 0)
        (effects (font (size 1.27 1.27) (thickness 0.15)) (justify left bottom) hide)
      )
      (property "Manufacturer" "Bourns" (id 5) (at 20.32 -22.86 0)
        (effects (font (size 1.27 1.27) (thickness 0.15)) (justify left bottom) hide)
      )
      (property "License" "Apache-2.0" (id 6) (at 20.32 -25.4 0)
        (effects (font (size 1.27 1.27) (thickness 0.15)) (justify left bottom) hide)
      )
      (property "Author" "Antmicro" (id 7) (at 20.32 -27.94 0)
        (effects (font (size 1.27 1.27) (thickness 0.15)) (justify left bottom) hide)
      )
      (property "Val" "10k" (id 8) (at 20.32 -7.62 0)
        (effects (font (size 1.27 1.27) (thickness 0.15)) (justify left bottom))
      )
      (property "Tolerance" "1%" (id 9) (at 20.32 -10.16 0)
        (effects (font (size 1.27 1.27)) (justify left bottom) hide)
      )
      (property "ki_description" "10k resistor in 0603 package with 1% tolerance" (id 10) (at 0 0 0)
        (effects (font (size 1.27 1.27)) hide)
      )
      (symbol "R_10k_0603_0_1"
        (rectangle (start 0.635 0.889) (end 4.445 -0.889)
          (stroke (width 0.254) (type default) (color 0 0 0 0))
          (fill (type none))
        )
      )
      (symbol "R_10k_0603_1_1"
        (pin passive line (at 0 0 0) (length 0.635)
          (name "~" (effects (font (size 1.27 1.27))))
          (number "1" (effects (font (size 1.27 1.27))))
        )
        (pin passive line (at 5.08 0 180) (length 0.635)
          (name "~" (effects (font (size 1.27 1.27))))
          (number "2" (effects (font (size 1.27 1.27))))
        )
      )
    )
	(symbol "sa800u-baseboard-hw:R_13k7_0402" (pin_numbers hide) (pin_names hide) (in_bom yes) (on_board yes)
      (property "Reference" "R" (id 0) (at 20.32 -5.08 0)
        (effects (font (size 1.27 1.27) (thickness 0.15)) (justify left bottom))
      )
      (property "Value" "R_13k7_0402" (id 1) (at 20.32 -12.7 0)
        (effects (font (size 1.27 1.27) (thickness 0.15)) (justify left bottom) hide)
      )
      (property "Footprint" "sa800u-baseboard-hw-footprints:R_0402_1005Metric" (id 2) (at 20.32 -15.24 0)
        (effects (font (size 1.27 1.27) (thickness 0.15)) (justify left bottom) hide)
      )
      (property "Datasheet" "https://www.bourns.com/docs/product-datasheets/cr.pdf" (id 3) (at 20.32 -17.78 0)
        (effects (font (size 1.27 1.27) (thickness 0.15)) (justify left bottom) hide)
      )
      (property "MPN" "CR0402-FX-1372GLF" (id 4) (at 20.32 -20.32 0)
        (effects (font (size 1.27 1.27) (thickness 0.15)) (justify left bottom) hide)
      )
      (property "Manufacturer" "Bourns" (id 5) (at 20.32 -22.86 0)
        (effects (font (size 1.27 1.27) (thickness 0.15)) (justify left bottom) hide)
      )
      (property "License" "Apache-2.0" (id 6) (at 20.32 -25.4 0)
        (effects (font (size 1.27 1.27) (thickness 0.15)) (justify left bottom) hide)
      )
      (property "Author" "Antmicro" (id 7) (at 20.32 -27.94 0)
        (effects (font (size 1.27 1.27) (thickness 0.15)) (justify left bottom) hide)
      )
      (property "Val" "13k7" (id 8) (at 20.32 -7.62 0)
        (effects (font (size 1.27 1.27) (thickness 0.15)) (justify left bottom))
      )
      (property "Tolerance" "1%" (id 9) (at 20.32 -10.16 0)
        (effects (font (size 1.27 1.27)) (justify left bottom) hide)
      )
      (property "ki_description" "13k7 resistor in 0402 package with 1% tolerance" (id 10) (at 0 0 0)
        (effects (font (size 1.27 1.27)) hide)
      )
      (symbol "R_13k7_0402_0_1"
        (rectangle (start 0.635 0.889) (end 4.445 -0.889)
          (stroke (width 0.254) (type default) (color 0 0 0 0))
          (fill (type none))
        )
      )
      (symbol "R_13k7_0402_1_1"
        (pin passive line (at 0 0 0) (length 0.635)
          (name "~" (effects (font (size 1.27 1.27))))
          (number "1" (effects (font (size 1.27 1.27))))
        )
        (pin passive line (at 5.08 0 180) (length 0.635)
          (name "~" (effects (font (size 1.27 1.27))))
          (number "2" (effects (font (size 1.27 1.27))))
        )
      )
    )
	(symbol "sa800u-baseboard-hw:R_15k_0603" (pin_numbers hide) (pin_names hide) (in_bom yes) (on_board yes)
      (property "Reference" "R" (id 0) (at 20.32 -5.08 0)
        (effects (font (size 1.27 1.27) (thickness 0.15)) (justify left bottom))
      )
      (property "Value" "R_15k_0603" (id 1) (at 20.32 -12.7 0)
        (effects (font (size 1.27 1.27) (thickness 0.15)) (justify left bottom) hide)
      )
      (property "Footprint" "sa800u-baseboard-hw-footprints:R_0603_1608Metric" (id 2) (at 20.32 -15.24 0)
        (effects (font (size 1.27 1.27) (thickness 0.15)) (justify left bottom) hide)
      )
      (property "Datasheet" "https://www.bourns.com/docs/product-datasheets/cr.pdf" (id 3) (at 20.32 -17.78 0)
        (effects (font (size 1.27 1.27) (thickness 0.15)) (justify left bottom) hide)
      )
      (property "MPN" "CR0603-FX-1502ELF" (id 4) (at 20.32 -20.32 0)
        (effects (font (size 1.27 1.27) (thickness 0.15)) (justify left bottom) hide)
      )
      (property "Manufacturer" "Bourns" (id 5) (at 20.32 -22.86 0)
        (effects (font (size 1.27 1.27) (thickness 0.15)) (justify left bottom) hide)
      )
      (property "License" "Apache-2.0" (id 6) (at 20.32 -25.4 0)
        (effects (font (size 1.27 1.27) (thickness 0.15)) (justify left bottom) hide)
      )
      (property "Author" "Antmicro" (id 7) (at 20.32 -27.94 0)
        (effects (font (size 1.27 1.27) (thickness 0.15)) (justify left bottom) hide)
      )
      (property "Val" "15k" (id 8) (at 20.32 -7.62 0)
        (effects (font (size 1.27 1.27) (thickness 0.15)) (justify left bottom))
      )
      (property "Tolerance" "1%" (id 9) (at 20.32 -10.16 0)
        (effects (font (size 1.27 1.27)) (justify left bottom) hide)
      )
      (property "ki_description" "15k resistor in 0603 package with 1% tolerance" (id 10) (at 0 0 0)
        (effects (font (size 1.27 1.27)) hide)
      )
      (symbol "R_15k_0603_0_1"
        (rectangle (start 0.635 0.889) (end 4.445 -0.889)
          (stroke (width 0.254) (type default) (color 0 0 0 0))
          (fill (type none))
        )
      )
      (symbol "R_15k_0603_1_1"
        (pin passive line (at 0 0 0) (length 0.635)
          (name "~" (effects (font (size 1.27 1.27))))
          (number "1" (effects (font (size 1.27 1.27))))
        )
        (pin passive line (at 5.08 0 180) (length 0.635)
          (name "~" (effects (font (size 1.27 1.27))))
          (number "2" (effects (font (size 1.27 1.27))))
        )
      )
    )
	(symbol "sa800u-baseboard-hw:R_1M_0402" (pin_numbers hide) (pin_names hide) (in_bom yes) (on_board yes)
      (property "Reference" "R" (id 0) (at 20.32 -5.08 0)
        (effects (font (size 1.27 1.27) (thickness 0.15)) (justify left bottom))
      )
      (property "Value" "R_1M_0402" (id 1) (at 20.32 -12.7 0)
        (effects (font (size 1.27 1.27) (thickness 0.15)) (justify left bottom) hide)
      )
      (property "Footprint" "sa800u-baseboard-hw-footprints:R_0402_1005Metric" (id 2) (at 20.32 -15.24 0)
        (effects (font (size 1.27 1.27) (thickness 0.15)) (justify left bottom) hide)
      )
      (property "Datasheet" "https://www.bourns.com/docs/product-datasheets/cr.pdf" (id 3) (at 20.32 -17.78 0)
        (effects (font (size 1.27 1.27) (thickness 0.15)) (justify left bottom) hide)
      )
      (property "MPN" "CR0402-FX-1004GLF" (id 4) (at 20.32 -20.32 0)
        (effects (font (size 1.27 1.27) (thickness 0.15)) (justify left bottom) hide)
      )
      (property "Manufacturer" "Bourns" (id 5) (at 20.32 -22.86 0)
        (effects (font (size 1.27 1.27) (thickness 0.15)) (justify left bottom) hide)
      )
      (property "License" "Apache-2.0" (id 6) (at 20.32 -25.4 0)
        (effects (font (size 1.27 1.27) (thickness 0.15)) (justify left bottom) hide)
      )
      (property "Author" "Antmicro" (id 7) (at 20.32 -27.94 0)
        (effects (font (size 1.27 1.27) (thickness 0.15)) (justify left bottom) hide)
      )
      (property "Val" "1M" (id 8) (at 20.32 -7.62 0)
        (effects (font (size 1.27 1.27) (thickness 0.15)) (justify left bottom))
      )
      (property "Tolerance" "1%" (id 9) (at 20.32 -10.16 0)
        (effects (font (size 1.27 1.27)) (justify left bottom) hide)
      )
      (property "ki_description" "1M resistor in 0402 package with 1% tolerance" (id 10) (at 0 0 0)
        (effects (font (size 1.27 1.27)) hide)
      )
      (symbol "R_1M_0402_0_1"
        (rectangle (start 0.635 0.889) (end 4.445 -0.889)
          (stroke (width 0.254) (type default) (color 0 0 0 0))
          (fill (type none))
        )
      )
      (symbol "R_1M_0402_1_1"
        (pin passive line (at 0 0 0) (length 0.635)
          (name "~" (effects (font (size 1.27 1.27))))
          (number "1" (effects (font (size 1.27 1.27))))
        )
        (pin passive line (at 5.08 0 180) (length 0.635)
          (name "~" (effects (font (size 1.27 1.27))))
          (number "2" (effects (font (size 1.27 1.27))))
        )
      )
    )
	(symbol "sa800u-baseboard-hw:R_1k1_0402" (pin_numbers hide) (pin_names hide) (in_bom yes) (on_board yes)
      (property "Reference" "R" (id 0) (at 20.32 -5.08 0)
        (effects (font (size 1.27 1.27) (thickness 0.15)) (justify left bottom))
      )
      (property "Value" "R_1k1_0402" (id 1) (at 20.32 -12.7 0)
        (effects (font (size 1.27 1.27) (thickness 0.15)) (justify left bottom) hide)
      )
      (property "Footprint" "sa800u-baseboard-hw-footprints:R_0402_1005Metric" (id 2) (at 20.32 -15.24 0)
        (effects (font (size 1.27 1.27) (thickness 0.15)) (justify left bottom) hide)
      )
      (property "Datasheet" "https://www.bourns.com/docs/product-datasheets/cr.pdf" (id 3) (at 20.32 -17.78 0)
        (effects (font (size 1.27 1.27) (thickness 0.15)) (justify left bottom) hide)
      )
      (property "MPN" "CR0402-FX-1101GLF" (id 4) (at 20.32 -20.32 0)
        (effects (font (size 1.27 1.27) (thickness 0.15)) (justify left bottom) hide)
      )
      (property "Manufacturer" "Bourns" (id 5) (at 20.32 -22.86 0)
        (effects (font (size 1.27 1.27) (thickness 0.15)) (justify left bottom) hide)
      )
      (property "License" "Apache-2.0" (id 6) (at 20.32 -25.4 0)
        (effects (font (size 1.27 1.27) (thickness 0.15)) (justify left bottom) hide)
      )
      (property "Author" "Antmicro" (id 7) (at 20.32 -27.94 0)
        (effects (font (size 1.27 1.27) (thickness 0.15)) (justify left bottom) hide)
      )
      (property "Val" "1k1" (id 8) (at 20.32 -7.62 0)
        (effects (font (size 1.27 1.27) (thickness 0.15)) (justify left bottom))
      )
      (property "Tolerance" "1%" (id 9) (at 20.32 -10.16 0)
        (effects (font (size 1.27 1.27)) (justify left bottom) hide)
      )
      (property "ki_description" "1k1 resistor in 0402 package with 1% tolerance" (id 10) (at 0 0 0)
        (effects (font (size 1.27 1.27)) hide)
      )
      (symbol "R_1k1_0402_0_1"
        (rectangle (start 0.635 0.889) (end 4.445 -0.889)
          (stroke (width 0.254) (type default) (color 0 0 0 0))
          (fill (type none))
        )
      )
      (symbol "R_1k1_0402_1_1"
        (pin passive line (at 0 0 0) (length 0.635)
          (name "~" (effects (font (size 1.27 1.27))))
          (number "1" (effects (font (size 1.27 1.27))))
        )
        (pin passive line (at 5.08 0 180) (length 0.635)
          (name "~" (effects (font (size 1.27 1.27))))
          (number "2" (effects (font (size 1.27 1.27))))
        )
      )
    )
	(symbol "sa800u-baseboard-hw:R_1k_0402" (pin_numbers hide) (pin_names hide) (in_bom yes) (on_board yes)
      (property "Reference" "R" (id 0) (at 20.32 -5.08 0)
        (effects (font (size 1.27 1.27) (thickness 0.15)) (justify left bottom))
      )
      (property "Value" "R_1k_0402" (id 1) (at 20.32 -12.7 0)
        (effects (font (size 1.27 1.27) (thickness 0.15)) (justify left bottom) hide)
      )
      (property "Footprint" "sa800u-baseboard-hw-footprints:R_0402_1005Metric" (id 2) (at 20.32 -15.24 0)
        (effects (font (size 1.27 1.27) (thickness 0.15)) (justify left bottom) hide)
      )
      (property "Datasheet" "https://www.bourns.com/docs/product-datasheets/cr.pdf" (id 3) (at 20.32 -17.78 0)
        (effects (font (size 1.27 1.27) (thickness 0.15)) (justify left bottom) hide)
      )
      (property "MPN" "CR0402-FX-1001GLF" (id 4) (at 20.32 -20.32 0)
        (effects (font (size 1.27 1.27) (thickness 0.15)) (justify left bottom) hide)
      )
      (property "Manufacturer" "Bourns" (id 5) (at 20.32 -22.86 0)
        (effects (font (size 1.27 1.27) (thickness 0.15)) (justify left bottom) hide)
      )
      (property "License" "Apache-2.0" (id 6) (at 20.32 -25.4 0)
        (effects (font (size 1.27 1.27) (thickness 0.15)) (justify left bottom) hide)
      )
      (property "Author" "Antmicro" (id 7) (at 20.32 -27.94 0)
        (effects (font (size 1.27 1.27) (thickness 0.15)) (justify left bottom) hide)
      )
      (property "Val" "1k" (id 8) (at 20.32 -7.62 0)
        (effects (font (size 1.27 1.27) (thickness 0.15)) (justify left bottom))
      )
      (property "Tolerance" "1%" (id 9) (at 20.32 -10.16 0)
        (effects (font (size 1.27 1.27)) (justify left bottom) hide)
      )
      (property "ki_description" "1k resistor in 0402 package with 1% tolerance" (id 10) (at 0 0 0)
        (effects (font (size 1.27 1.27)) hide)
      )
      (symbol "R_1k_0402_0_1"
        (rectangle (start 0.635 0.889) (end 4.445 -0.889)
          (stroke (width 0.254) (type default) (color 0 0 0 0))
          (fill (type none))
        )
      )
      (symbol "R_1k_0402_1_1"
        (pin passive line (at 0 0 0) (length 0.635)
          (name "~" (effects (font (size 1.27 1.27))))
          (number "1" (effects (font (size 1.27 1.27))))
        )
        (pin passive line (at 5.08 0 180) (length 0.635)
          (name "~" (effects (font (size 1.27 1.27))))
          (number "2" (effects (font (size 1.27 1.27))))
        )
      )
    )
	(symbol "sa800u-baseboard-hw:R_200k_0402" (pin_numbers hide) (pin_names hide) (in_bom yes) (on_board yes)
      (property "Reference" "R" (id 0) (at 20.32 -5.08 0)
        (effects (font (size 1.27 1.27) (thickness 0.15)) (justify left bottom))
      )
      (property "Value" "R_200k_0402" (id 1) (at 20.32 -12.7 0)
        (effects (font (size 1.27 1.27) (thickness 0.15)) (justify left bottom) hide)
      )
      (property "Footprint" "sa800u-baseboard-hw-footprints:R_0402_1005Metric" (id 2) (at 20.32 -15.24 0)
        (effects (font (size 1.27 1.27) (thickness 0.15)) (justify left bottom) hide)
      )
      (property "Datasheet" "https://www.bourns.com/docs/product-datasheets/cr.pdf" (id 3) (at 20.32 -17.78 0)
        (effects (font (size 1.27 1.27) (thickness 0.15)) (justify left bottom) hide)
      )
      (property "MPN" "CR0402-FX-2003GLF" (id 4) (at 20.32 -20.32 0)
        (effects (font (size 1.27 1.27) (thickness 0.15)) (justify left bottom) hide)
      )
      (property "Manufacturer" "Bourns" (id 5) (at 20.32 -22.86 0)
        (effects (font (size 1.27 1.27) (thickness 0.15)) (justify left bottom) hide)
      )
      (property "License" "Apache-2.0" (id 6) (at 20.32 -25.4 0)
        (effects (font (size 1.27 1.27) (thickness 0.15)) (justify left bottom) hide)
      )
      (property "Author" "Antmicro" (id 7) (at 20.32 -27.94 0)
        (effects (font (size 1.27 1.27) (thickness 0.15)) (justify left bottom) hide)
      )
      (property "Val" "200k" (id 8) (at 20.32 -7.62 0)
        (effects (font (size 1.27 1.27) (thickness 0.15)) (justify left bottom))
      )
      (property "Tolerance" "1%" (id 9) (at 20.32 -10.16 0)
        (effects (font (size 1.27 1.27)) (justify left bottom) hide)
      )
      (property "ki_description" "200k resistor in 0402 package with 1% tolerance" (id 10) (at 0 0 0)
        (effects (font (size 1.27 1.27)) hide)
      )
      (symbol "R_200k_0402_0_1"
        (rectangle (start 0.635 0.889) (end 4.445 -0.889)
          (stroke (width 0.254) (type default) (color 0 0 0 0))
          (fill (type none))
        )
      )
      (symbol "R_200k_0402_1_1"
        (pin passive line (at 0 0 0) (length 0.635)
          (name "~" (effects (font (size 1.27 1.27))))
          (number "1" (effects (font (size 1.27 1.27))))
        )
        (pin passive line (at 5.08 0 180) (length 0.635)
          (name "~" (effects (font (size 1.27 1.27))))
          (number "2" (effects (font (size 1.27 1.27))))
        )
      )
    )
	(symbol "sa800u-baseboard-hw:R_20k_0402" (pin_numbers hide) (pin_names hide) (in_bom yes) (on_board yes)
      (property "Reference" "R" (id 0) (at 20.32 -5.08 0)
        (effects (font (size 1.27 1.27) (thickness 0.15)) (justify left bottom))
      )
      (property "Value" "R_20k_0402" (id 1) (at 20.32 -12.7 0)
        (effects (font (size 1.27 1.27) (thickness 0.15)) (justify left bottom) hide)
      )
      (property "Footprint" "sa800u-baseboard-hw-footprints:R_0402_1005Metric" (id 2) (at 20.32 -15.24 0)
        (effects (font (size 1.27 1.27) (thickness 0.15)) (justify left bottom) hide)
      )
      (property "Datasheet" "https://www.bourns.com/docs/product-datasheets/cr.pdf" (id 3) (at 20.32 -17.78 0)
        (effects (font (size 1.27 1.27) (thickness 0.15)) (justify left bottom) hide)
      )
      (property "MPN" "CR0402-FX-2002GLF" (id 4) (at 20.32 -20.32 0)
        (effects (font (size 1.27 1.27) (thickness 0.15)) (justify left bottom) hide)
      )
      (property "Manufacturer" "Bourns" (id 5) (at 20.32 -22.86 0)
        (effects (font (size 1.27 1.27) (thickness 0.15)) (justify left bottom) hide)
      )
      (property "License" "Apache-2.0" (id 6) (at 20.32 -25.4 0)
        (effects (font (size 1.27 1.27) (thickness 0.15)) (justify left bottom) hide)
      )
      (property "Author" "Antmicro" (id 7) (at 20.32 -27.94 0)
        (effects (font (size 1.27 1.27) (thickness 0.15)) (justify left bottom) hide)
      )
      (property "Val" "20k" (id 8) (at 20.32 -7.62 0)
        (effects (font (size 1.27 1.27) (thickness 0.15)) (justify left bottom))
      )
      (property "Tolerance" "1%" (id 9) (at 20.32 -10.16 0)
        (effects (font (size 1.27 1.27)) (justify left bottom) hide)
      )
      (property "ki_description" "20k resistor in 0402 package with 1% tolerance" (id 10) (at 0 0 0)
        (effects (font (size 1.27 1.27)) hide)
      )
      (symbol "R_20k_0402_0_1"
        (rectangle (start 0.635 0.889) (end 4.445 -0.889)
          (stroke (width 0.254) (type default) (color 0 0 0 0))
          (fill (type none))
        )
      )
      (symbol "R_20k_0402_1_1"
        (pin passive line (at 0 0 0) (length 0.635)
          (name "~" (effects (font (size 1.27 1.27))))
          (number "1" (effects (font (size 1.27 1.27))))
        )
        (pin passive line (at 5.08 0 180) (length 0.635)
          (name "~" (effects (font (size 1.27 1.27))))
          (number "2" (effects (font (size 1.27 1.27))))
        )
      )
    )
	(symbol "sa800u-baseboard-hw:R_20k_0603" (pin_numbers hide) (pin_names hide) (in_bom yes) (on_board yes)
      (property "Reference" "R" (id 0) (at 20.32 -5.08 0)
        (effects (font (size 1.27 1.27) (thickness 0.15)) (justify left bottom))
      )
      (property "Value" "R_20k_0603" (id 1) (at 20.32 -12.7 0)
        (effects (font (size 1.27 1.27) (thickness 0.15)) (justify left bottom) hide)
      )
      (property "Footprint" "sa800u-baseboard-hw-footprints:R_0603_1608Metric" (id 2) (at 20.32 -15.24 0)
        (effects (font (size 1.27 1.27) (thickness 0.15)) (justify left bottom) hide)
      )
      (property "Datasheet" "https://www.bourns.com/docs/product-datasheets/cr.pdf" (id 3) (at 20.32 -17.78 0)
        (effects (font (size 1.27 1.27) (thickness 0.15)) (justify left bottom) hide)
      )
      (property "MPN" "CR0603-FX-2002ELF" (id 4) (at 20.32 -20.32 0)
        (effects (font (size 1.27 1.27) (thickness 0.15)) (justify left bottom) hide)
      )
      (property "Manufacturer" "Bourns" (id 5) (at 20.32 -22.86 0)
        (effects (font (size 1.27 1.27) (thickness 0.15)) (justify left bottom) hide)
      )
      (property "License" "Apache-2.0" (id 6) (at 20.32 -25.4 0)
        (effects (font (size 1.27 1.27) (thickness 0.15)) (justify left bottom) hide)
      )
      (property "Author" "Antmicro" (id 7) (at 20.32 -27.94 0)
        (effects (font (size 1.27 1.27) (thickness 0.15)) (justify left bottom) hide)
      )
      (property "Val" "20k" (id 8) (at 20.32 -7.62 0)
        (effects (font (size 1.27 1.27) (thickness 0.15)) (justify left bottom))
      )
      (property "Tolerance" "1%" (id 9) (at 20.32 -10.16 0)
        (effects (font (size 1.27 1.27)) (justify left bottom) hide)
      )
      (property "ki_description" "20k resistor in 0603 package with 1% tolerance" (id 10) (at 0 0 0)
        (effects (font (size 1.27 1.27)) hide)
      )
      (symbol "R_20k_0603_0_1"
        (rectangle (start 0.635 0.889) (end 4.445 -0.889)
          (stroke (width 0.254) (type default) (color 0 0 0 0))
          (fill (type none))
        )
      )
      (symbol "R_20k_0603_1_1"
        (pin passive line (at 0 0 0) (length 0.635)
          (name "~" (effects (font (size 1.27 1.27))))
          (number "1" (effects (font (size 1.27 1.27))))
        )
        (pin passive line (at 5.08 0 180) (length 0.635)
          (name "~" (effects (font (size 1.27 1.27))))
          (number "2" (effects (font (size 1.27 1.27))))
        )
      )
    )
	(symbol "sa800u-baseboard-hw:R_220R_0402" (pin_numbers hide) (pin_names hide) (in_bom yes) (on_board yes)
      (property "Reference" "R" (id 0) (at 20.32 -5.08 0)
        (effects (font (size 1.27 1.27) (thickness 0.15)) (justify left bottom))
      )
      (property "Value" "R_220R_0402" (id 1) (at 20.32 -12.7 0)
        (effects (font (size 1.27 1.27) (thickness 0.15)) (justify left bottom) hide)
      )
      (property "Footprint" "sa800u-baseboard-hw-footprints:R_0402_1005Metric" (id 2) (at 20.32 -15.24 0)
        (effects (font (size 1.27 1.27) (thickness 0.15)) (justify left bottom) hide)
      )
      (property "Datasheet" "https://www.bourns.com/docs/product-datasheets/cr.pdf" (id 3) (at 20.32 -17.78 0)
        (effects (font (size 1.27 1.27) (thickness 0.15)) (justify left bottom) hide)
      )
      (property "MPN" "CR0402-FX-2200GLF" (id 4) (at 20.32 -20.32 0)
        (effects (font (size 1.27 1.27) (thickness 0.15)) (justify left bottom) hide)
      )
      (property "Manufacturer" "Bourns" (id 5) (at 20.32 -22.86 0)
        (effects (font (size 1.27 1.27) (thickness 0.15)) (justify left bottom) hide)
      )
      (property "License" "Apache-2.0" (id 6) (at 20.32 -25.4 0)
        (effects (font (size 1.27 1.27) (thickness 0.15)) (justify left bottom) hide)
      )
      (property "Author" "Antmicro" (id 7) (at 20.32 -27.94 0)
        (effects (font (size 1.27 1.27) (thickness 0.15)) (justify left bottom) hide)
      )
      (property "Val" "220R" (id 8) (at 20.32 -7.62 0)
        (effects (font (size 1.27 1.27) (thickness 0.15)) (justify left bottom))
      )
      (property "Tolerance" "1%" (id 9) (at 20.32 -10.16 0)
        (effects (font (size 1.27 1.27)) (justify left bottom) hide)
      )
      (property "ki_description" "220R resistor in 0402 package with 1% tolerance" (id 10) (at 0 0 0)
        (effects (font (size 1.27 1.27)) hide)
      )
      (symbol "R_220R_0402_0_1"
        (rectangle (start 0.635 0.889) (end 4.445 -0.889)
          (stroke (width 0.254) (type default) (color 0 0 0 0))
          (fill (type none))
        )
      )
      (symbol "R_220R_0402_1_1"
        (pin passive line (at 0 0 0) (length 0.635)
          (name "~" (effects (font (size 1.27 1.27))))
          (number "1" (effects (font (size 1.27 1.27))))
        )
        (pin passive line (at 5.08 0 180) (length 0.635)
          (name "~" (effects (font (size 1.27 1.27))))
          (number "2" (effects (font (size 1.27 1.27))))
        )
      )
    )
	(symbol "sa800u-baseboard-hw:R_22k_0402" (pin_numbers hide) (pin_names hide) (in_bom yes) (on_board yes)
      (property "Reference" "R" (id 0) (at 20.32 -5.08 0)
        (effects (font (size 1.27 1.27) (thickness 0.15)) (justify left bottom))
      )
      (property "Value" "R_22k_0402" (id 1) (at 20.32 -12.7 0)
        (effects (font (size 1.27 1.27) (thickness 0.15)) (justify left bottom) hide)
      )
      (property "Footprint" "sa800u-baseboard-hw-footprints:R_0402_1005Metric" (id 2) (at 20.32 -15.24 0)
        (effects (font (size 1.27 1.27) (thickness 0.15)) (justify left bottom) hide)
      )
      (property "Datasheet" "https://www.bourns.com/docs/product-datasheets/cr.pdf" (id 3) (at 20.32 -17.78 0)
        (effects (font (size 1.27 1.27) (thickness 0.15)) (justify left bottom) hide)
      )
      (property "MPN" "CR0402-FX-2202GLF" (id 4) (at 20.32 -20.32 0)
        (effects (font (size 1.27 1.27) (thickness 0.15)) (justify left bottom) hide)
      )
      (property "Manufacturer" "Bourns" (id 5) (at 20.32 -22.86 0)
        (effects (font (size 1.27 1.27) (thickness 0.15)) (justify left bottom) hide)
      )
      (property "License" "Apache-2.0" (id 6) (at 20.32 -25.4 0)
        (effects (font (size 1.27 1.27) (thickness 0.15)) (justify left bottom) hide)
      )
      (property "Author" "Antmicro" (id 7) (at 20.32 -27.94 0)
        (effects (font (size 1.27 1.27) (thickness 0.15)) (justify left bottom) hide)
      )
      (property "Val" "22k" (id 8) (at 20.32 -7.62 0)
        (effects (font (size 1.27 1.27) (thickness 0.15)) (justify left bottom))
      )
      (property "Tolerance" "1%" (id 9) (at 20.32 -10.16 0)
        (effects (font (size 1.27 1.27)) (justify left bottom) hide)
      )
      (property "ki_description" "22k resistor in 0402 package with 1% tolerance" (id 10) (at 0 0 0)
        (effects (font (size 1.27 1.27)) hide)
      )
      (symbol "R_22k_0402_0_1"
        (rectangle (start 0.635 0.889) (end 4.445 -0.889)
          (stroke (width 0.254) (type default) (color 0 0 0 0))
          (fill (type none))
        )
      )
      (symbol "R_22k_0402_1_1"
        (pin passive line (at 0 0 0) (length 0.635)
          (name "~" (effects (font (size 1.27 1.27))))
          (number "1" (effects (font (size 1.27 1.27))))
        )
        (pin passive line (at 5.08 0 180) (length 0.635)
          (name "~" (effects (font (size 1.27 1.27))))
          (number "2" (effects (font (size 1.27 1.27))))
        )
      )
    )
	(symbol "sa800u-baseboard-hw:R_24k9_0402" (pin_numbers hide) (pin_names hide) (in_bom yes) (on_board yes)
      (property "Reference" "R" (id 0) (at 20.32 -5.08 0)
        (effects (font (size 1.27 1.27) (thickness 0.15)) (justify left bottom))
      )
      (property "Value" "R_24k9_0402" (id 1) (at 20.32 -12.7 0)
        (effects (font (size 1.27 1.27) (thickness 0.15)) (justify left bottom) hide)
      )
      (property "Footprint" "sa800u-baseboard-hw-footprints:R_0402_1005Metric" (id 2) (at 20.32 -15.24 0)
        (effects (font (size 1.27 1.27) (thickness 0.15)) (justify left bottom) hide)
      )
      (property "Datasheet" "https://www.bourns.com/docs/product-datasheets/cr.pdf" (id 3) (at 20.32 -17.78 0)
        (effects (font (size 1.27 1.27) (thickness 0.15)) (justify left bottom) hide)
      )
      (property "MPN" "CR0402-FX-2492GLF" (id 4) (at 20.32 -20.32 0)
        (effects (font (size 1.27 1.27) (thickness 0.15)) (justify left bottom) hide)
      )
      (property "Manufacturer" "Bourns" (id 5) (at 20.32 -22.86 0)
        (effects (font (size 1.27 1.27) (thickness 0.15)) (justify left bottom) hide)
      )
      (property "License" "Apache-2.0" (id 6) (at 20.32 -25.4 0)
        (effects (font (size 1.27 1.27) (thickness 0.15)) (justify left bottom) hide)
      )
      (property "Author" "Antmicro" (id 7) (at 20.32 -27.94 0)
        (effects (font (size 1.27 1.27) (thickness 0.15)) (justify left bottom) hide)
      )
      (property "Val" "24k9" (id 8) (at 20.32 -7.62 0)
        (effects (font (size 1.27 1.27) (thickness 0.15)) (justify left bottom))
      )
      (property "Tolerance" "1%" (id 9) (at 20.32 -10.16 0)
        (effects (font (size 1.27 1.27)) (justify left bottom) hide)
      )
      (property "ki_description" "24k9 resistor in 0402 package with 1% tolerance" (id 10) (at 0 0 0)
        (effects (font (size 1.27 1.27)) hide)
      )
      (symbol "R_24k9_0402_0_1"
        (rectangle (start 0.635 0.889) (end 4.445 -0.889)
          (stroke (width 0.254) (type default) (color 0 0 0 0))
          (fill (type none))
        )
      )
      (symbol "R_24k9_0402_1_1"
        (pin passive line (at 0 0 0) (length 0.635)
          (name "~" (effects (font (size 1.27 1.27))))
          (number "1" (effects (font (size 1.27 1.27))))
        )
        (pin passive line (at 5.08 0 180) (length 0.635)
          (name "~" (effects (font (size 1.27 1.27))))
          (number "2" (effects (font (size 1.27 1.27))))
        )
      )
    )
	(symbol "sa800u-baseboard-hw:R_255k_0402" (pin_numbers hide) (pin_names hide) (in_bom yes) (on_board yes)
      (property "Reference" "R" (id 0) (at 20.32 -5.08 0)
        (effects (font (size 1.27 1.27) (thickness 0.15)) (justify left bottom))
      )
      (property "Value" "R_255k_0402" (id 1) (at 20.32 -12.7 0)
        (effects (font (size 1.27 1.27) (thickness 0.15)) (justify left bottom) hide)
      )
      (property "Footprint" "sa800u-baseboard-hw-footprints:R_0402_1005Metric" (id 2) (at 20.32 -15.24 0)
        (effects (font (size 1.27 1.27) (thickness 0.15)) (justify left bottom) hide)
      )
      (property "Datasheet" "https://www.bourns.com/docs/product-datasheets/cr.pdf" (id 3) (at 20.32 -17.78 0)
        (effects (font (size 1.27 1.27) (thickness 0.15)) (justify left bottom) hide)
      )
      (property "MPN" "CR0402-FX-2553GLF" (id 4) (at 20.32 -20.32 0)
        (effects (font (size 1.27 1.27) (thickness 0.15)) (justify left bottom) hide)
      )
      (property "Manufacturer" "Bourns" (id 5) (at 20.32 -22.86 0)
        (effects (font (size 1.27 1.27) (thickness 0.15)) (justify left bottom) hide)
      )
      (property "License" "Apache-2.0" (id 6) (at 20.32 -25.4 0)
        (effects (font (size 1.27 1.27) (thickness 0.15)) (justify left bottom) hide)
      )
      (property "Author" "Antmicro" (id 7) (at 20.32 -27.94 0)
        (effects (font (size 1.27 1.27) (thickness 0.15)) (justify left bottom) hide)
      )
      (property "Val" "255k" (id 8) (at 20.32 -7.62 0)
        (effects (font (size 1.27 1.27) (thickness 0.15)) (justify left bottom))
      )
      (property "Tolerance" "1%" (id 9) (at 20.32 -10.16 0)
        (effects (font (size 1.27 1.27)) (justify left bottom) hide)
      )
      (property "ki_description" "255k resistor in 0402 package with 1% tolerance" (id 10) (at 0 0 0)
        (effects (font (size 1.27 1.27)) hide)
      )
      (symbol "R_255k_0402_0_1"
        (rectangle (start 0.635 0.889) (end 4.445 -0.889)
          (stroke (width 0.254) (type default) (color 0 0 0 0))
          (fill (type none))
        )
      )
      (symbol "R_255k_0402_1_1"
        (pin passive line (at 0 0 0) (length 0.635)
          (name "~" (effects (font (size 1.27 1.27))))
          (number "1" (effects (font (size 1.27 1.27))))
        )
        (pin passive line (at 5.08 0 180) (length 0.635)
          (name "~" (effects (font (size 1.27 1.27))))
          (number "2" (effects (font (size 1.27 1.27))))
        )
      )
    )
	(symbol "sa800u-baseboard-hw:R_25k5_0402" (pin_numbers hide) (pin_names hide) (in_bom yes) (on_board yes)
      (property "Reference" "R" (id 0) (at 20.32 -5.08 0)
        (effects (font (size 1.27 1.27) (thickness 0.15)) (justify left bottom))
      )
      (property "Value" "R_25k5_0402" (id 1) (at 20.32 -12.7 0)
        (effects (font (size 1.27 1.27) (thickness 0.15)) (justify left bottom) hide)
      )
      (property "Footprint" "sa800u-baseboard-hw-footprints:R_0402_1005Metric" (id 2) (at 20.32 -15.24 0)
        (effects (font (size 1.27 1.27) (thickness 0.15)) (justify left bottom) hide)
      )
      (property "Datasheet" "https://www.bourns.com/docs/product-datasheets/cr.pdf" (id 3) (at 20.32 -17.78 0)
        (effects (font (size 1.27 1.27) (thickness 0.15)) (justify left bottom) hide)
      )
      (property "MPN" "CR0402-FX-2552GLF" (id 4) (at 20.32 -20.32 0)
        (effects (font (size 1.27 1.27) (thickness 0.15)) (justify left bottom) hide)
      )
      (property "Manufacturer" "Bourns" (id 5) (at 20.32 -22.86 0)
        (effects (font (size 1.27 1.27) (thickness 0.15)) (justify left bottom) hide)
      )
      (property "License" "Apache-2.0" (id 6) (at 20.32 -25.4 0)
        (effects (font (size 1.27 1.27) (thickness 0.15)) (justify left bottom) hide)
      )
      (property "Author" "Antmicro" (id 7) (at 20.32 -27.94 0)
        (effects (font (size 1.27 1.27) (thickness 0.15)) (justify left bottom) hide)
      )
      (property "Val" "25k5" (id 8) (at 20.32 -7.62 0)
        (effects (font (size 1.27 1.27) (thickness 0.15)) (justify left bottom))
      )
      (property "Tolerance" "1%" (id 9) (at 20.32 -10.16 0)
        (effects (font (size 1.27 1.27)) (justify left bottom) hide)
      )
      (property "ki_description" "25k5 resistor in 0402 package with 1% tolerance" (id 10) (at 0 0 0)
        (effects (font (size 1.27 1.27)) hide)
      )
      (symbol "R_25k5_0402_0_1"
        (rectangle (start 0.635 0.889) (end 4.445 -0.889)
          (stroke (width 0.254) (type default) (color 0 0 0 0))
          (fill (type none))
        )
      )
      (symbol "R_25k5_0402_1_1"
        (pin passive line (at 0 0 0) (length 0.635)
          (name "~" (effects (font (size 1.27 1.27))))
          (number "1" (effects (font (size 1.27 1.27))))
        )
        (pin passive line (at 5.08 0 180) (length 0.635)
          (name "~" (effects (font (size 1.27 1.27))))
          (number "2" (effects (font (size 1.27 1.27))))
        )
      )
    )
	(symbol "sa800u-baseboard-hw:R_27k_0402" (pin_numbers hide) (pin_names hide) (in_bom yes) (on_board yes)
      (property "Reference" "R" (id 0) (at 20.32 -5.08 0)
        (effects (font (size 1.27 1.27) (thickness 0.15)) (justify left bottom))
      )
      (property "Value" "R_27k_0402" (id 1) (at 20.32 -12.7 0)
        (effects (font (size 1.27 1.27) (thickness 0.15)) (justify left bottom) hide)
      )
      (property "Footprint" "sa800u-baseboard-hw-footprints:R_0402_1005Metric" (id 2) (at 20.32 -15.24 0)
        (effects (font (size 1.27 1.27) (thickness 0.15)) (justify left bottom) hide)
      )
      (property "Datasheet" "https://www.bourns.com/docs/product-datasheets/cr.pdf" (id 3) (at 20.32 -17.78 0)
        (effects (font (size 1.27 1.27) (thickness 0.15)) (justify left bottom) hide)
      )
      (property "MPN" "CR0402-FX-2702GLF" (id 4) (at 20.32 -20.32 0)
        (effects (font (size 1.27 1.27) (thickness 0.15)) (justify left bottom) hide)
      )
      (property "Manufacturer" "Bourns" (id 5) (at 20.32 -22.86 0)
        (effects (font (size 1.27 1.27) (thickness 0.15)) (justify left bottom) hide)
      )
      (property "License" "Apache-2.0" (id 6) (at 20.32 -25.4 0)
        (effects (font (size 1.27 1.27) (thickness 0.15)) (justify left bottom) hide)
      )
      (property "Author" "Antmicro" (id 7) (at 20.32 -27.94 0)
        (effects (font (size 1.27 1.27) (thickness 0.15)) (justify left bottom) hide)
      )
      (property "Val" "27k" (id 8) (at 20.32 -7.62 0)
        (effects (font (size 1.27 1.27) (thickness 0.15)) (justify left bottom))
      )
      (property "Tolerance" "1%" (id 9) (at 20.32 -10.16 0)
        (effects (font (size 1.27 1.27)) (justify left bottom) hide)
      )
      (property "ki_description" "27k resistor in 0402 package with 1% tolerance" (id 10) (at 0 0 0)
        (effects (font (size 1.27 1.27)) hide)
      )
      (symbol "R_27k_0402_0_1"
        (rectangle (start 0.635 0.889) (end 4.445 -0.889)
          (stroke (width 0.254) (type default) (color 0 0 0 0))
          (fill (type none))
        )
      )
      (symbol "R_27k_0402_1_1"
        (pin passive line (at 0 0 0) (length 0.635)
          (name "~" (effects (font (size 1.27 1.27))))
          (number "1" (effects (font (size 1.27 1.27))))
        )
        (pin passive line (at 5.08 0 180) (length 0.635)
          (name "~" (effects (font (size 1.27 1.27))))
          (number "2" (effects (font (size 1.27 1.27))))
        )
      )
    )
	(symbol "sa800u-baseboard-hw:R_2k2_0402" (pin_numbers hide) (pin_names hide) (in_bom yes) (on_board yes)
      (property "Reference" "R" (id 0) (at 20.32 -5.08 0)
        (effects (font (size 1.27 1.27) (thickness 0.15)) (justify left bottom))
      )
      (property "Value" "R_2k2_0402" (id 1) (at 20.32 -12.7 0)
        (effects (font (size 1.27 1.27) (thickness 0.15)) (justify left bottom) hide)
      )
      (property "Footprint" "sa800u-baseboard-hw-footprints:R_0402_1005Metric" (id 2) (at 20.32 -15.24 0)
        (effects (font (size 1.27 1.27) (thickness 0.15)) (justify left bottom) hide)
      )
      (property "Datasheet" "https://www.bourns.com/docs/product-datasheets/cr.pdf" (id 3) (at 20.32 -17.78 0)
        (effects (font (size 1.27 1.27) (thickness 0.15)) (justify left bottom) hide)
      )
      (property "MPN" "CR0402-FX-2201GLF" (id 4) (at 20.32 -20.32 0)
        (effects (font (size 1.27 1.27) (thickness 0.15)) (justify left bottom) hide)
      )
      (property "Manufacturer" "Bourns" (id 5) (at 20.32 -22.86 0)
        (effects (font (size 1.27 1.27) (thickness 0.15)) (justify left bottom) hide)
      )
      (property "License" "Apache-2.0" (id 6) (at 20.32 -25.4 0)
        (effects (font (size 1.27 1.27) (thickness 0.15)) (justify left bottom) hide)
      )
      (property "Author" "Antmicro" (id 7) (at 20.32 -27.94 0)
        (effects (font (size 1.27 1.27) (thickness 0.15)) (justify left bottom) hide)
      )
      (property "Val" "2k2" (id 8) (at 20.32 -7.62 0)
        (effects (font (size 1.27 1.27) (thickness 0.15)) (justify left bottom))
      )
      (property "Tolerance" "1%" (id 9) (at 20.32 -10.16 0)
        (effects (font (size 1.27 1.27)) (justify left bottom) hide)
      )
      (property "ki_description" "2k2 resistor in 0402 package with 1% tolerance" (id 10) (at 0 0 0)
        (effects (font (size 1.27 1.27)) hide)
      )
      (symbol "R_2k2_0402_0_1"
        (rectangle (start 0.635 0.889) (end 4.445 -0.889)
          (stroke (width 0.254) (type default) (color 0 0 0 0))
          (fill (type none))
        )
      )
      (symbol "R_2k2_0402_1_1"
        (pin passive line (at 0 0 0) (length 0.635)
          (name "~" (effects (font (size 1.27 1.27))))
          (number "1" (effects (font (size 1.27 1.27))))
        )
        (pin passive line (at 5.08 0 180) (length 0.635)
          (name "~" (effects (font (size 1.27 1.27))))
          (number "2" (effects (font (size 1.27 1.27))))
        )
      )
    )
	(symbol "sa800u-baseboard-hw:R_2k49_0402" (pin_numbers hide) (pin_names hide) (in_bom yes) (on_board yes)
      (property "Reference" "R" (id 0) (at 20.32 -5.08 0)
        (effects (font (size 1.27 1.27) (thickness 0.15)) (justify left bottom))
      )
      (property "Value" "R_2k49_0402" (id 1) (at 20.32 -12.7 0)
        (effects (font (size 1.27 1.27) (thickness 0.15)) (justify left bottom) hide)
      )
      (property "Footprint" "sa800u-baseboard-hw-footprints:R_0402_1005Metric" (id 2) (at 20.32 -15.24 0)
        (effects (font (size 1.27 1.27) (thickness 0.15)) (justify left bottom) hide)
      )
      (property "Datasheet" "https://www.bourns.com/docs/product-datasheets/cr.pdf" (id 3) (at 20.32 -17.78 0)
        (effects (font (size 1.27 1.27) (thickness 0.15)) (justify left bottom) hide)
      )
      (property "MPN" "CR0402-FX-2491GLF" (id 4) (at 20.32 -20.32 0)
        (effects (font (size 1.27 1.27) (thickness 0.15)) (justify left bottom) hide)
      )
      (property "Manufacturer" "Bourns" (id 5) (at 20.32 -22.86 0)
        (effects (font (size 1.27 1.27) (thickness 0.15)) (justify left bottom) hide)
      )
      (property "License" "Apache-2.0" (id 6) (at 20.32 -25.4 0)
        (effects (font (size 1.27 1.27) (thickness 0.15)) (justify left bottom) hide)
      )
      (property "Author" "Antmicro" (id 7) (at 20.32 -27.94 0)
        (effects (font (size 1.27 1.27) (thickness 0.15)) (justify left bottom) hide)
      )
      (property "Val" "2k49" (id 8) (at 20.32 -7.62 0)
        (effects (font (size 1.27 1.27) (thickness 0.15)) (justify left bottom))
      )
      (property "Tolerance" "1%" (id 9) (at 20.32 -10.16 0)
        (effects (font (size 1.27 1.27)) (justify left bottom) hide)
      )
      (property "ki_description" "2k49 resistor in 0402 package with 1% tolerance" (id 10) (at 0 0 0)
        (effects (font (size 1.27 1.27)) hide)
      )
      (symbol "R_2k49_0402_0_1"
        (rectangle (start 0.635 0.889) (end 4.445 -0.889)
          (stroke (width 0.254) (type default) (color 0 0 0 0))
          (fill (type none))
        )
      )
      (symbol "R_2k49_0402_1_1"
        (pin passive line (at 0 0 0) (length 0.635)
          (name "~" (effects (font (size 1.27 1.27))))
          (number "1" (effects (font (size 1.27 1.27))))
        )
        (pin passive line (at 5.08 0 180) (length 0.635)
          (name "~" (effects (font (size 1.27 1.27))))
          (number "2" (effects (font (size 1.27 1.27))))
        )
      )
    )
	(symbol "sa800u-baseboard-hw:R_2k7_0402" (pin_numbers hide) (pin_names hide) (in_bom yes) (on_board yes)
      (property "Reference" "R" (id 0) (at 20.32 -5.08 0)
        (effects (font (size 1.27 1.27) (thickness 0.15)) (justify left bottom))
      )
      (property "Value" "R_2k7_0402" (id 1) (at 20.32 -12.7 0)
        (effects (font (size 1.27 1.27) (thickness 0.15)) (justify left bottom) hide)
      )
      (property "Footprint" "sa800u-baseboard-hw-footprints:R_0402_1005Metric" (id 2) (at 20.32 -15.24 0)
        (effects (font (size 1.27 1.27) (thickness 0.15)) (justify left bottom) hide)
      )
      (property "Datasheet" "https://www.bourns.com/docs/product-datasheets/cr.pdf" (id 3) (at 20.32 -17.78 0)
        (effects (font (size 1.27 1.27) (thickness 0.15)) (justify left bottom) hide)
      )
      (property "MPN" "CR0402-FX-2701GLF" (id 4) (at 20.32 -20.32 0)
        (effects (font (size 1.27 1.27) (thickness 0.15)) (justify left bottom) hide)
      )
      (property "Manufacturer" "Bourns" (id 5) (at 20.32 -22.86 0)
        (effects (font (size 1.27 1.27) (thickness 0.15)) (justify left bottom) hide)
      )
      (property "License" "Apache-2.0" (id 6) (at 20.32 -25.4 0)
        (effects (font (size 1.27 1.27) (thickness 0.15)) (justify left bottom) hide)
      )
      (property "Author" "Antmicro" (id 7) (at 20.32 -27.94 0)
        (effects (font (size 1.27 1.27) (thickness 0.15)) (justify left bottom) hide)
      )
      (property "Val" "2k7" (id 8) (at 20.32 -7.62 0)
        (effects (font (size 1.27 1.27) (thickness 0.15)) (justify left bottom))
      )
      (property "Tolerance" "1%" (id 9) (at 20.32 -10.16 0)
        (effects (font (size 1.27 1.27)) (justify left bottom) hide)
      )
      (property "ki_description" "2k7 resistor in 0402 package with 1% tolerance" (id 10) (at 0 0 0)
        (effects (font (size 1.27 1.27)) hide)
      )
      (symbol "R_2k7_0402_0_1"
        (rectangle (start 0.635 0.889) (end 4.445 -0.889)
          (stroke (width 0.254) (type default) (color 0 0 0 0))
          (fill (type none))
        )
      )
      (symbol "R_2k7_0402_1_1"
        (pin passive line (at 0 0 0) (length 0.635)
          (name "~" (effects (font (size 1.27 1.27))))
          (number "1" (effects (font (size 1.27 1.27))))
        )
        (pin passive line (at 5.08 0 180) (length 0.635)
          (name "~" (effects (font (size 1.27 1.27))))
          (number "2" (effects (font (size 1.27 1.27))))
        )
      )
    )
	(symbol "sa800u-baseboard-hw:R_2k_0402" (pin_numbers hide) (pin_names hide) (in_bom yes) (on_board yes)
      (property "Reference" "R" (id 0) (at 20.32 -5.08 0)
        (effects (font (size 1.27 1.27) (thickness 0.15)) (justify left bottom))
      )
      (property "Value" "R_2k_0402" (id 1) (at 20.32 -12.7 0)
        (effects (font (size 1.27 1.27) (thickness 0.15)) (justify left bottom) hide)
      )
      (property "Footprint" "sa800u-baseboard-hw-footprints:R_0402_1005Metric" (id 2) (at 20.32 -15.24 0)
        (effects (font (size 1.27 1.27) (thickness 0.15)) (justify left bottom) hide)
      )
      (property "Datasheet" "https://www.bourns.com/docs/product-datasheets/cr.pdf" (id 3) (at 20.32 -17.78 0)
        (effects (font (size 1.27 1.27) (thickness 0.15)) (justify left bottom) hide)
      )
      (property "MPN" "CR0402-FX-2001GLF" (id 4) (at 20.32 -20.32 0)
        (effects (font (size 1.27 1.27) (thickness 0.15)) (justify left bottom) hide)
      )
      (property "Manufacturer" "Bourns" (id 5) (at 20.32 -22.86 0)
        (effects (font (size 1.27 1.27) (thickness 0.15)) (justify left bottom) hide)
      )
      (property "License" "Apache-2.0" (id 6) (at 20.32 -25.4 0)
        (effects (font (size 1.27 1.27) (thickness 0.15)) (justify left bottom) hide)
      )
      (property "Author" "Antmicro" (id 7) (at 20.32 -27.94 0)
        (effects (font (size 1.27 1.27) (thickness 0.15)) (justify left bottom) hide)
      )
      (property "Val" "2k" (id 8) (at 20.32 -7.62 0)
        (effects (font (size 1.27 1.27) (thickness 0.15)) (justify left bottom))
      )
      (property "Tolerance" "1%" (id 9) (at 20.32 -10.16 0)
        (effects (font (size 1.27 1.27)) (justify left bottom) hide)
      )
      (property "ki_description" "2k resistor in 0402 package with 1% tolerance" (id 10) (at 0 0 0)
        (effects (font (size 1.27 1.27)) hide)
      )
      (symbol "R_2k_0402_0_1"
        (rectangle (start 0.635 0.889) (end 4.445 -0.889)
          (stroke (width 0.254) (type default) (color 0 0 0 0))
          (fill (type none))
        )
      )
      (symbol "R_2k_0402_1_1"
        (pin passive line (at 0 0 0) (length 0.635)
          (name "~" (effects (font (size 1.27 1.27))))
          (number "1" (effects (font (size 1.27 1.27))))
        )
        (pin passive line (at 5.08 0 180) (length 0.635)
          (name "~" (effects (font (size 1.27 1.27))))
          (number "2" (effects (font (size 1.27 1.27))))
        )
      )
    )
	(symbol "sa800u-baseboard-hw:R_31k6_0402" (pin_numbers hide) (pin_names hide) (in_bom yes) (on_board yes)
      (property "Reference" "R" (id 0) (at 20.32 -5.08 0)
        (effects (font (size 1.27 1.27) (thickness 0.15)) (justify left bottom))
      )
      (property "Value" "R_31k6_0402" (id 1) (at 20.32 -12.7 0)
        (effects (font (size 1.27 1.27) (thickness 0.15)) (justify left bottom) hide)
      )
      (property "Footprint" "sa800u-baseboard-hw-footprints:R_0402_1005Metric" (id 2) (at 20.32 -15.24 0)
        (effects (font (size 1.27 1.27) (thickness 0.15)) (justify left bottom) hide)
      )
      (property "Datasheet" "https://www.bourns.com/docs/product-datasheets/cr.pdf" (id 3) (at 20.32 -17.78 0)
        (effects (font (size 1.27 1.27) (thickness 0.15)) (justify left bottom) hide)
      )
      (property "MPN" "CR0402-FX-3162GLF" (id 4) (at 20.32 -20.32 0)
        (effects (font (size 1.27 1.27) (thickness 0.15)) (justify left bottom) hide)
      )
      (property "Manufacturer" "Bourns" (id 5) (at 20.32 -22.86 0)
        (effects (font (size 1.27 1.27) (thickness 0.15)) (justify left bottom) hide)
      )
      (property "License" "Apache-2.0" (id 6) (at 20.32 -25.4 0)
        (effects (font (size 1.27 1.27) (thickness 0.15)) (justify left bottom) hide)
      )
      (property "Author" "Antmicro" (id 7) (at 20.32 -27.94 0)
        (effects (font (size 1.27 1.27) (thickness 0.15)) (justify left bottom) hide)
      )
      (property "Val" "31k6" (id 8) (at 20.32 -7.62 0)
        (effects (font (size 1.27 1.27) (thickness 0.15)) (justify left bottom))
      )
      (property "Tolerance" "1%" (id 9) (at 20.32 -10.16 0)
        (effects (font (size 1.27 1.27)) (justify left bottom) hide)
      )
      (property "ki_description" "31k6 resistor in 0402 package with 1% tolerance" (id 10) (at 0 0 0)
        (effects (font (size 1.27 1.27)) hide)
      )
      (symbol "R_31k6_0402_0_1"
        (rectangle (start 0.635 0.889) (end 4.445 -0.889)
          (stroke (width 0.254) (type default) (color 0 0 0 0))
          (fill (type none))
        )
      )
      (symbol "R_31k6_0402_1_1"
        (pin passive line (at 0 0 0) (length 0.635)
          (name "~" (effects (font (size 1.27 1.27))))
          (number "1" (effects (font (size 1.27 1.27))))
        )
        (pin passive line (at 5.08 0 180) (length 0.635)
          (name "~" (effects (font (size 1.27 1.27))))
          (number "2" (effects (font (size 1.27 1.27))))
        )
      )
    )
	(symbol "sa800u-baseboard-hw:R_33R_0402" (pin_numbers hide) (pin_names hide) (in_bom yes) (on_board yes)
      (property "Reference" "R" (id 0) (at 20.32 -5.08 0)
        (effects (font (size 1.27 1.27) (thickness 0.15)) (justify left bottom))
      )
      (property "Value" "R_33R_0402" (id 1) (at 20.32 -12.7 0)
        (effects (font (size 1.27 1.27) (thickness 0.15)) (justify left bottom) hide)
      )
      (property "Footprint" "sa800u-baseboard-hw-footprints:R_0402_1005Metric" (id 2) (at 20.32 -15.24 0)
        (effects (font (size 1.27 1.27) (thickness 0.15)) (justify left bottom) hide)
      )
      (property "Datasheet" "https://www.bourns.com/docs/product-datasheets/cr.pdf" (id 3) (at 20.32 -17.78 0)
        (effects (font (size 1.27 1.27) (thickness 0.15)) (justify left bottom) hide)
      )
      (property "MPN" "CR0402-FX-33R0GLF" (id 4) (at 20.32 -20.32 0)
        (effects (font (size 1.27 1.27) (thickness 0.15)) (justify left bottom) hide)
      )
      (property "Manufacturer" "Bourns" (id 5) (at 20.32 -22.86 0)
        (effects (font (size 1.27 1.27) (thickness 0.15)) (justify left bottom) hide)
      )
      (property "License" "Apache-2.0" (id 6) (at 20.32 -25.4 0)
        (effects (font (size 1.27 1.27) (thickness 0.15)) (justify left bottom) hide)
      )
      (property "Author" "Antmicro" (id 7) (at 20.32 -27.94 0)
        (effects (font (size 1.27 1.27) (thickness 0.15)) (justify left bottom) hide)
      )
      (property "Val" "33R" (id 8) (at 20.32 -7.62 0)
        (effects (font (size 1.27 1.27) (thickness 0.15)) (justify left bottom))
      )
      (property "Tolerance" "1%" (id 9) (at 20.32 -10.16 0)
        (effects (font (size 1.27 1.27)) (justify left bottom) hide)
      )
      (property "ki_description" "33R resistor in 0402 package with 1% tolerance" (id 10) (at 0 0 0)
        (effects (font (size 1.27 1.27)) hide)
      )
      (symbol "R_33R_0402_0_1"
        (rectangle (start 0.635 0.889) (end 4.445 -0.889)
          (stroke (width 0.254) (type default) (color 0 0 0 0))
          (fill (type none))
        )
      )
      (symbol "R_33R_0402_1_1"
        (pin passive line (at 0 0 0) (length 0.635)
          (name "~" (effects (font (size 1.27 1.27))))
          (number "1" (effects (font (size 1.27 1.27))))
        )
        (pin passive line (at 5.08 0 180) (length 0.635)
          (name "~" (effects (font (size 1.27 1.27))))
          (number "2" (effects (font (size 1.27 1.27))))
        )
      )
    )
	(symbol "sa800u-baseboard-hw:R_39k_0402" (pin_numbers hide) (pin_names hide) (in_bom yes) (on_board yes)
      (property "Reference" "R" (id 0) (at 20.32 -5.08 0)
        (effects (font (size 1.27 1.27) (thickness 0.15)) (justify left bottom))
      )
      (property "Value" "R_39k_0402" (id 1) (at 20.32 -12.7 0)
        (effects (font (size 1.27 1.27) (thickness 0.15)) (justify left bottom) hide)
      )
      (property "Footprint" "sa800u-baseboard-hw-footprints:R_0402_1005Metric" (id 2) (at 20.32 -15.24 0)
        (effects (font (size 1.27 1.27) (thickness 0.15)) (justify left bottom) hide)
      )
      (property "Datasheet" "https://www.bourns.com/docs/product-datasheets/cr.pdf" (id 3) (at 20.32 -17.78 0)
        (effects (font (size 1.27 1.27) (thickness 0.15)) (justify left bottom) hide)
      )
      (property "MPN" "CR0402-FX-3902GLF" (id 4) (at 20.32 -20.32 0)
        (effects (font (size 1.27 1.27) (thickness 0.15)) (justify left bottom) hide)
      )
      (property "Manufacturer" "Bourns" (id 5) (at 20.32 -22.86 0)
        (effects (font (size 1.27 1.27) (thickness 0.15)) (justify left bottom) hide)
      )
      (property "License" "Apache-2.0" (id 6) (at 20.32 -25.4 0)
        (effects (font (size 1.27 1.27) (thickness 0.15)) (justify left bottom) hide)
      )
      (property "Author" "Antmicro" (id 7) (at 20.32 -27.94 0)
        (effects (font (size 1.27 1.27) (thickness 0.15)) (justify left bottom) hide)
      )
      (property "Val" "39k" (id 8) (at 20.32 -7.62 0)
        (effects (font (size 1.27 1.27) (thickness 0.15)) (justify left bottom))
      )
      (property "Tolerance" "1%" (id 9) (at 20.32 -10.16 0)
        (effects (font (size 1.27 1.27)) (justify left bottom) hide)
      )
      (property "ki_description" "39k resistor in 0402 package with 1% tolerance" (id 10) (at 0 0 0)
        (effects (font (size 1.27 1.27)) hide)
      )
      (symbol "R_39k_0402_0_1"
        (rectangle (start 0.635 0.889) (end 4.445 -0.889)
          (stroke (width 0.254) (type default) (color 0 0 0 0))
          (fill (type none))
        )
      )
      (symbol "R_39k_0402_1_1"
        (pin passive line (at 0 0 0) (length 0.635)
          (name "~" (effects (font (size 1.27 1.27))))
          (number "1" (effects (font (size 1.27 1.27))))
        )
        (pin passive line (at 5.08 0 180) (length 0.635)
          (name "~" (effects (font (size 1.27 1.27))))
          (number "2" (effects (font (size 1.27 1.27))))
        )
      )
    )
	(symbol "sa800u-baseboard-hw:R_470R_0402" (pin_numbers hide) (pin_names hide) (in_bom yes) (on_board yes)
      (property "Reference" "R" (id 0) (at 20.32 -5.08 0)
        (effects (font (size 1.27 1.27) (thickness 0.15)) (justify left bottom))
      )
      (property "Value" "R_470R_0402" (id 1) (at 20.32 -12.7 0)
        (effects (font (size 1.27 1.27) (thickness 0.15)) (justify left bottom) hide)
      )
      (property "Footprint" "sa800u-baseboard-hw-footprints:R_0402_1005Metric" (id 2) (at 20.32 -15.24 0)
        (effects (font (size 1.27 1.27) (thickness 0.15)) (justify left bottom) hide)
      )
      (property "Datasheet" "https://www.bourns.com/docs/product-datasheets/cr.pdf" (id 3) (at 20.32 -17.78 0)
        (effects (font (size 1.27 1.27) (thickness 0.15)) (justify left bottom) hide)
      )
      (property "MPN" "CR0402-FX-4700GLF" (id 4) (at 20.32 -20.32 0)
        (effects (font (size 1.27 1.27) (thickness 0.15)) (justify left bottom) hide)
      )
      (property "Manufacturer" "Bourns" (id 5) (at 20.32 -22.86 0)
        (effects (font (size 1.27 1.27) (thickness 0.15)) (justify left bottom) hide)
      )
      (property "License" "Apache-2.0" (id 6) (at 20.32 -25.4 0)
        (effects (font (size 1.27 1.27) (thickness 0.15)) (justify left bottom) hide)
      )
      (property "Author" "Antmicro" (id 7) (at 20.32 -27.94 0)
        (effects (font (size 1.27 1.27) (thickness 0.15)) (justify left bottom) hide)
      )
      (property "Val" "470R" (id 8) (at 20.32 -7.62 0)
        (effects (font (size 1.27 1.27) (thickness 0.15)) (justify left bottom))
      )
      (property "Tolerance" "1%" (id 9) (at 20.32 -10.16 0)
        (effects (font (size 1.27 1.27)) (justify left bottom) hide)
      )
      (property "ki_description" "470R resistor in 0402 package with 1% tolerance" (id 10) (at 0 0 0)
        (effects (font (size 1.27 1.27)) hide)
      )
      (symbol "R_470R_0402_0_1"
        (rectangle (start 0.635 0.889) (end 4.445 -0.889)
          (stroke (width 0.254) (type default) (color 0 0 0 0))
          (fill (type none))
        )
      )
      (symbol "R_470R_0402_1_1"
        (pin passive line (at 0 0 0) (length 0.635)
          (name "~" (effects (font (size 1.27 1.27))))
          (number "1" (effects (font (size 1.27 1.27))))
        )
        (pin passive line (at 5.08 0 180) (length 0.635)
          (name "~" (effects (font (size 1.27 1.27))))
          (number "2" (effects (font (size 1.27 1.27))))
        )
      )
    )
	(symbol "sa800u-baseboard-hw:R_47k_0402" (pin_numbers hide) (pin_names hide) (in_bom yes) (on_board yes)
      (property "Reference" "R" (id 0) (at 20.32 -5.08 0)
        (effects (font (size 1.27 1.27) (thickness 0.15)) (justify left bottom))
      )
      (property "Value" "R_47k_0402" (id 1) (at 20.32 -12.7 0)
        (effects (font (size 1.27 1.27) (thickness 0.15)) (justify left bottom) hide)
      )
      (property "Footprint" "sa800u-baseboard-hw-footprints:R_0402_1005Metric" (id 2) (at 20.32 -15.24 0)
        (effects (font (size 1.27 1.27) (thickness 0.15)) (justify left bottom) hide)
      )
      (property "Datasheet" "https://www.bourns.com/docs/product-datasheets/cr.pdf" (id 3) (at 20.32 -17.78 0)
        (effects (font (size 1.27 1.27) (thickness 0.15)) (justify left bottom) hide)
      )
      (property "MPN" "CR0402-FX-4702GLF" (id 4) (at 20.32 -20.32 0)
        (effects (font (size 1.27 1.27) (thickness 0.15)) (justify left bottom) hide)
      )
      (property "Manufacturer" "Bourns" (id 5) (at 20.32 -22.86 0)
        (effects (font (size 1.27 1.27) (thickness 0.15)) (justify left bottom) hide)
      )
      (property "License" "Apache-2.0" (id 6) (at 20.32 -25.4 0)
        (effects (font (size 1.27 1.27) (thickness 0.15)) (justify left bottom) hide)
      )
      (property "Author" "Antmicro" (id 7) (at 20.32 -27.94 0)
        (effects (font (size 1.27 1.27) (thickness 0.15)) (justify left bottom) hide)
      )
      (property "Val" "47k" (id 8) (at 20.32 -7.62 0)
        (effects (font (size 1.27 1.27) (thickness 0.15)) (justify left bottom))
      )
      (property "Tolerance" "1%" (id 9) (at 20.32 -10.16 0)
        (effects (font (size 1.27 1.27)) (justify left bottom) hide)
      )
      (property "ki_description" "47k resistor in 0402 package with 1% tolerance" (id 10) (at 0 0 0)
        (effects (font (size 1.27 1.27)) hide)
      )
      (symbol "R_47k_0402_0_1"
        (rectangle (start 0.635 0.889) (end 4.445 -0.889)
          (stroke (width 0.254) (type default) (color 0 0 0 0))
          (fill (type none))
        )
      )
      (symbol "R_47k_0402_1_1"
        (pin passive line (at 0 0 0) (length 0.635)
          (name "~" (effects (font (size 1.27 1.27))))
          (number "1" (effects (font (size 1.27 1.27))))
        )
        (pin passive line (at 5.08 0 180) (length 0.635)
          (name "~" (effects (font (size 1.27 1.27))))
          (number "2" (effects (font (size 1.27 1.27))))
        )
      )
    )
	(symbol "sa800u-baseboard-hw:R_4k7_0402" (pin_numbers hide) (pin_names hide) (in_bom yes) (on_board yes)
      (property "Reference" "R" (id 0) (at 20.32 -5.08 0)
        (effects (font (size 1.27 1.27) (thickness 0.15)) (justify left bottom))
      )
      (property "Value" "R_4k7_0402" (id 1) (at 20.32 -12.7 0)
        (effects (font (size 1.27 1.27) (thickness 0.15)) (justify left bottom) hide)
      )
      (property "Footprint" "sa800u-baseboard-hw-footprints:R_0402_1005Metric" (id 2) (at 20.32 -15.24 0)
        (effects (font (size 1.27 1.27) (thickness 0.15)) (justify left bottom) hide)
      )
      (property "Datasheet" "https://www.bourns.com/docs/product-datasheets/cr.pdf" (id 3) (at 20.32 -17.78 0)
        (effects (font (size 1.27 1.27) (thickness 0.15)) (justify left bottom) hide)
      )
      (property "MPN" "CR0402-FX-4701GLF" (id 4) (at 20.32 -20.32 0)
        (effects (font (size 1.27 1.27) (thickness 0.15)) (justify left bottom) hide)
      )
      (property "Manufacturer" "Bourns" (id 5) (at 20.32 -22.86 0)
        (effects (font (size 1.27 1.27) (thickness 0.15)) (justify left bottom) hide)
      )
      (property "License" "Apache-2.0" (id 6) (at 20.32 -25.4 0)
        (effects (font (size 1.27 1.27) (thickness 0.15)) (justify left bottom) hide)
      )
      (property "Author" "Antmicro" (id 7) (at 20.32 -27.94 0)
        (effects (font (size 1.27 1.27) (thickness 0.15)) (justify left bottom) hide)
      )
      (property "Val" "4k7" (id 8) (at 20.32 -7.62 0)
        (effects (font (size 1.27 1.27) (thickness 0.15)) (justify left bottom))
      )
      (property "Tolerance" "1%" (id 9) (at 20.32 -10.16 0)
        (effects (font (size 1.27 1.27)) (justify left bottom) hide)
      )
      (property "ki_description" "4k7 resistor in 0402 package with 1% tolerance" (id 10) (at 0 0 0)
        (effects (font (size 1.27 1.27)) hide)
      )
      (symbol "R_4k7_0402_0_1"
        (rectangle (start 0.635 0.889) (end 4.445 -0.889)
          (stroke (width 0.254) (type default) (color 0 0 0 0))
          (fill (type none))
        )
      )
      (symbol "R_4k7_0402_1_1"
        (pin passive line (at 0 0 0) (length 0.635)
          (name "~" (effects (font (size 1.27 1.27))))
          (number "1" (effects (font (size 1.27 1.27))))
        )
        (pin passive line (at 5.08 0 180) (length 0.635)
          (name "~" (effects (font (size 1.27 1.27))))
          (number "2" (effects (font (size 1.27 1.27))))
        )
      )
    )
	(symbol "sa800u-baseboard-hw:R_50R_0402" (pin_numbers hide) (pin_names hide) (in_bom yes) (on_board yes)
      (property "Reference" "R" (id 0) (at 20.32 -5.08 0)
        (effects (font (size 1.27 1.27) (thickness 0.15)) (justify left bottom))
      )
      (property "Value" "R_50R_0402" (id 1) (at 20.32 -12.7 0)
        (effects (font (size 1.27 1.27) (thickness 0.15)) (justify left bottom) hide)
      )
      (property "Footprint" "sa800u-baseboard-hw-footprints:R_0402_1005Metric" (id 2) (at 20.32 -15.24 0)
        (effects (font (size 1.27 1.27) (thickness 0.15)) (justify left bottom) hide)
      )
      (property "Datasheet" "https://www.bourns.com/docs/product-datasheets/cr.pdf" (id 3) (at 20.32 -17.78 0)
        (effects (font (size 1.27 1.27) (thickness 0.15)) (justify left bottom) hide)
      )
      (property "MPN" "CR0402-FX-50R0GLF" (id 4) (at 20.32 -20.32 0)
        (effects (font (size 1.27 1.27) (thickness 0.15)) (justify left bottom) hide)
      )
      (property "Manufacturer" "Bourns" (id 5) (at 20.32 -22.86 0)
        (effects (font (size 1.27 1.27) (thickness 0.15)) (justify left bottom) hide)
      )
      (property "License" "Apache-2.0" (id 6) (at 20.32 -25.4 0)
        (effects (font (size 1.27 1.27) (thickness 0.15)) (justify left bottom) hide)
      )
      (property "Author" "Antmicro" (id 7) (at 20.32 -27.94 0)
        (effects (font (size 1.27 1.27) (thickness 0.15)) (justify left bottom) hide)
      )
      (property "Val" "50R" (id 8) (at 20.32 -7.62 0)
        (effects (font (size 1.27 1.27) (thickness 0.15)) (justify left bottom))
      )
      (property "Tolerance" "1%" (id 9) (at 20.32 -10.16 0)
        (effects (font (size 1.27 1.27)) (justify left bottom) hide)
      )
      (property "ki_description" "50R resistor in 0402 package with 1% tolerance" (id 10) (at 0 0 0)
        (effects (font (size 1.27 1.27)) hide)
      )
      (symbol "R_50R_0402_0_1"
        (rectangle (start 0.635 0.889) (end 4.445 -0.889)
          (stroke (width 0.254) (type default) (color 0 0 0 0))
          (fill (type none))
        )
      )
      (symbol "R_50R_0402_1_1"
        (pin passive line (at 0 0 0) (length 0.635)
          (name "~" (effects (font (size 1.27 1.27))))
          (number "1" (effects (font (size 1.27 1.27))))
        )
        (pin passive line (at 5.08 0 180) (length 0.635)
          (name "~" (effects (font (size 1.27 1.27))))
          (number "2" (effects (font (size 1.27 1.27))))
        )
      )
    )
	(symbol "sa800u-baseboard-hw:R_510R_0402" (pin_numbers hide) (pin_names hide) (in_bom yes) (on_board yes)
      (property "Reference" "R" (id 0) (at 20.32 -5.08 0)
        (effects (font (size 1.27 1.27) (thickness 0.15)) (justify left bottom))
      )
      (property "Value" "R_510R_0402" (id 1) (at 20.32 -12.7 0)
        (effects (font (size 1.27 1.27) (thickness 0.15)) (justify left bottom) hide)
      )
      (property "Footprint" "sa800u-baseboard-hw-footprints:R_0402_1005Metric" (id 2) (at 20.32 -15.24 0)
        (effects (font (size 1.27 1.27) (thickness 0.15)) (justify left bottom) hide)
      )
      (property "Datasheet" "https://www.bourns.com/docs/product-datasheets/cr.pdf" (id 3) (at 20.32 -17.78 0)
        (effects (font (size 1.27 1.27) (thickness 0.15)) (justify left bottom) hide)
      )
      (property "MPN" "CR0402-FX-5100GLF" (id 4) (at 20.32 -20.32 0)
        (effects (font (size 1.27 1.27) (thickness 0.15)) (justify left bottom) hide)
      )
      (property "Manufacturer" "Bourns" (id 5) (at 20.32 -22.86 0)
        (effects (font (size 1.27 1.27) (thickness 0.15)) (justify left bottom) hide)
      )
      (property "License" "Apache-2.0" (id 6) (at 20.32 -25.4 0)
        (effects (font (size 1.27 1.27) (thickness 0.15)) (justify left bottom) hide)
      )
      (property "Author" "Antmicro" (id 7) (at 20.32 -27.94 0)
        (effects (font (size 1.27 1.27) (thickness 0.15)) (justify left bottom) hide)
      )
      (property "Val" "510R" (id 8) (at 20.32 -7.62 0)
        (effects (font (size 1.27 1.27) (thickness 0.15)) (justify left bottom))
      )
      (property "Tolerance" "1%" (id 9) (at 20.32 -10.16 0)
        (effects (font (size 1.27 1.27)) (justify left bottom) hide)
      )
      (property "ki_description" "510R resistor in 0402 package with 1% tolerance" (id 10) (at 0 0 0)
        (effects (font (size 1.27 1.27)) hide)
      )
      (symbol "R_510R_0402_0_1"
        (rectangle (start 0.635 0.889) (end 4.445 -0.889)
          (stroke (width 0.254) (type default) (color 0 0 0 0))
          (fill (type none))
        )
      )
      (symbol "R_510R_0402_1_1"
        (pin passive line (at 0 0 0) (length 0.635)
          (name "~" (effects (font (size 1.27 1.27))))
          (number "1" (effects (font (size 1.27 1.27))))
        )
        (pin passive line (at 5.08 0 180) (length 0.635)
          (name "~" (effects (font (size 1.27 1.27))))
          (number "2" (effects (font (size 1.27 1.27))))
        )
      )
    )
	(symbol "sa800u-baseboard-hw:R_52k3_0402" (pin_numbers hide) (pin_names hide) (in_bom yes) (on_board yes)
      (property "Reference" "R" (id 0) (at 20.32 -5.08 0)
        (effects (font (size 1.27 1.27) (thickness 0.15)) (justify left bottom))
      )
      (property "Value" "R_52k3_0402" (id 1) (at 20.32 -12.7 0)
        (effects (font (size 1.27 1.27) (thickness 0.15)) (justify left bottom) hide)
      )
      (property "Footprint" "sa800u-baseboard-hw-footprints:R_0402_1005Metric" (id 2) (at 20.32 -15.24 0)
        (effects (font (size 1.27 1.27) (thickness 0.15)) (justify left bottom) hide)
      )
      (property "Datasheet" "https://www.bourns.com/docs/product-datasheets/cr.pdf" (id 3) (at 20.32 -17.78 0)
        (effects (font (size 1.27 1.27) (thickness 0.15)) (justify left bottom) hide)
      )
      (property "MPN" "CR0402-FX-5232GLF" (id 4) (at 20.32 -20.32 0)
        (effects (font (size 1.27 1.27) (thickness 0.15)) (justify left bottom) hide)
      )
      (property "Manufacturer" "Bourns" (id 5) (at 20.32 -22.86 0)
        (effects (font (size 1.27 1.27) (thickness 0.15)) (justify left bottom) hide)
      )
      (property "License" "Apache-2.0" (id 6) (at 20.32 -25.4 0)
        (effects (font (size 1.27 1.27) (thickness 0.15)) (justify left bottom) hide)
      )
      (property "Author" "Antmicro" (id 7) (at 20.32 -27.94 0)
        (effects (font (size 1.27 1.27) (thickness 0.15)) (justify left bottom) hide)
      )
      (property "Val" "52k3" (id 8) (at 20.32 -7.62 0)
        (effects (font (size 1.27 1.27) (thickness 0.15)) (justify left bottom))
      )
      (property "Tolerance" "1%" (id 9) (at 20.32 -10.16 0)
        (effects (font (size 1.27 1.27)) (justify left bottom) hide)
      )
      (property "ki_description" "52k3 resistor in 0402 package with 1% tolerance" (id 10) (at 0 0 0)
        (effects (font (size 1.27 1.27)) hide)
      )
      (symbol "R_52k3_0402_0_1"
        (rectangle (start 0.635 0.889) (end 4.445 -0.889)
          (stroke (width 0.254) (type default) (color 0 0 0 0))
          (fill (type none))
        )
      )
      (symbol "R_52k3_0402_1_1"
        (pin passive line (at 0 0 0) (length 0.635)
          (name "~" (effects (font (size 1.27 1.27))))
          (number "1" (effects (font (size 1.27 1.27))))
        )
        (pin passive line (at 5.08 0 180) (length 0.635)
          (name "~" (effects (font (size 1.27 1.27))))
          (number "2" (effects (font (size 1.27 1.27))))
        )
      )
    )
	(symbol "sa800u-baseboard-hw:R_63R4_0402" (pin_numbers hide) (pin_names hide) (in_bom yes) (on_board yes)
      (property "Reference" "R" (id 0) (at 20.32 -5.08 0)
        (effects (font (size 1.27 1.27) (thickness 0.15)) (justify left bottom))
      )
      (property "Value" "R_63R4_0402" (id 1) (at 20.32 -12.7 0)
        (effects (font (size 1.27 1.27) (thickness 0.15)) (justify left bottom) hide)
      )
      (property "Footprint" "sa800u-baseboard-hw-footprints:R_0402_1005Metric" (id 2) (at 20.32 -15.24 0)
        (effects (font (size 1.27 1.27) (thickness 0.15)) (justify left bottom) hide)
      )
      (property "Datasheet" "https://www.bourns.com/docs/product-datasheets/cr.pdf" (id 3) (at 20.32 -17.78 0)
        (effects (font (size 1.27 1.27) (thickness 0.15)) (justify left bottom) hide)
      )
      (property "MPN" "CR0402-FX-63R4GLF" (id 4) (at 20.32 -20.32 0)
        (effects (font (size 1.27 1.27) (thickness 0.15)) (justify left bottom) hide)
      )
      (property "Manufacturer" "Bourns" (id 5) (at 20.32 -22.86 0)
        (effects (font (size 1.27 1.27) (thickness 0.15)) (justify left bottom) hide)
      )
      (property "License" "Apache-2.0" (id 6) (at 20.32 -25.4 0)
        (effects (font (size 1.27 1.27) (thickness 0.15)) (justify left bottom) hide)
      )
      (property "Author" "Antmicro" (id 7) (at 20.32 -27.94 0)
        (effects (font (size 1.27 1.27) (thickness 0.15)) (justify left bottom) hide)
      )
      (property "Val" "63R4" (id 8) (at 20.32 -7.62 0)
        (effects (font (size 1.27 1.27) (thickness 0.15)) (justify left bottom))
      )
      (property "Tolerance" "1%" (id 9) (at 20.32 -10.16 0)
        (effects (font (size 1.27 1.27)) (justify left bottom) hide)
      )
      (property "ki_description" "63R4 resistor in 0402 package with 1% tolerance" (id 10) (at 0 0 0)
        (effects (font (size 1.27 1.27)) hide)
      )
      (symbol "R_63R4_0402_0_1"
        (rectangle (start 0.635 0.889) (end 4.445 -0.889)
          (stroke (width 0.254) (type default) (color 0 0 0 0))
          (fill (type none))
        )
      )
      (symbol "R_63R4_0402_1_1"
        (pin passive line (at 0 0 0) (length 0.635)
          (name "~" (effects (font (size 1.27 1.27))))
          (number "1" (effects (font (size 1.27 1.27))))
        )
        (pin passive line (at 5.08 0 180) (length 0.635)
          (name "~" (effects (font (size 1.27 1.27))))
          (number "2" (effects (font (size 1.27 1.27))))
        )
      )
    )
	(symbol "sa800u-baseboard-hw:R_750R_0402" (pin_numbers hide) (pin_names hide) (in_bom yes) (on_board yes)
      (property "Reference" "R" (id 0) (at 20.32 -5.08 0)
        (effects (font (size 1.27 1.27) (thickness 0.15)) (justify left bottom))
      )
      (property "Value" "R_750R_0402" (id 1) (at 20.32 -12.7 0)
        (effects (font (size 1.27 1.27) (thickness 0.15)) (justify left bottom) hide)
      )
      (property "Footprint" "sa800u-baseboard-hw-footprints:R_0402_1005Metric" (id 2) (at 20.32 -15.24 0)
        (effects (font (size 1.27 1.27) (thickness 0.15)) (justify left bottom) hide)
      )
      (property "Datasheet" "https://www.bourns.com/docs/product-datasheets/cr.pdf" (id 3) (at 20.32 -17.78 0)
        (effects (font (size 1.27 1.27) (thickness 0.15)) (justify left bottom) hide)
      )
      (property "MPN" "CR0402-FX-7500GLF" (id 4) (at 20.32 -20.32 0)
        (effects (font (size 1.27 1.27) (thickness 0.15)) (justify left bottom) hide)
      )
      (property "Manufacturer" "Bourns" (id 5) (at 20.32 -22.86 0)
        (effects (font (size 1.27 1.27) (thickness 0.15)) (justify left bottom) hide)
      )
      (property "License" "Apache-2.0" (id 6) (at 20.32 -25.4 0)
        (effects (font (size 1.27 1.27) (thickness 0.15)) (justify left bottom) hide)
      )
      (property "Author" "Antmicro" (id 7) (at 20.32 -27.94 0)
        (effects (font (size 1.27 1.27) (thickness 0.15)) (justify left bottom) hide)
      )
      (property "Val" "750R" (id 8) (at 20.32 -7.62 0)
        (effects (font (size 1.27 1.27) (thickness 0.15)) (justify left bottom))
      )
      (property "Tolerance" "1%" (id 9) (at 20.32 -10.16 0)
        (effects (font (size 1.27 1.27)) (justify left bottom) hide)
      )
      (property "ki_description" "750R resistor in 0402 package with 1% tolerance" (id 10) (at 0 0 0)
        (effects (font (size 1.27 1.27)) hide)
      )
      (symbol "R_750R_0402_0_1"
        (rectangle (start 0.635 0.889) (end 4.445 -0.889)
          (stroke (width 0.254) (type default) (color 0 0 0 0))
          (fill (type none))
        )
      )
      (symbol "R_750R_0402_1_1"
        (pin passive line (at 0 0 0) (length 0.635)
          (name "~" (effects (font (size 1.27 1.27))))
          (number "1" (effects (font (size 1.27 1.27))))
        )
        (pin passive line (at 5.08 0 180) (length 0.635)
          (name "~" (effects (font (size 1.27 1.27))))
          (number "2" (effects (font (size 1.27 1.27))))
        )
      )
    )
	(symbol "sa800u-baseboard-hw:R_75k_0402" (pin_numbers hide) (pin_names hide) (in_bom yes) (on_board yes)
      (property "Reference" "R" (id 0) (at 20.32 -5.08 0)
        (effects (font (size 1.27 1.27) (thickness 0.15)) (justify left bottom))
      )
      (property "Value" "R_75k_0402" (id 1) (at 20.32 -12.7 0)
        (effects (font (size 1.27 1.27) (thickness 0.15)) (justify left bottom) hide)
      )
      (property "Footprint" "sa800u-baseboard-hw-footprints:R_0402_1005Metric" (id 2) (at 20.32 -15.24 0)
        (effects (font (size 1.27 1.27) (thickness 0.15)) (justify left bottom) hide)
      )
      (property "Datasheet" "https://www.bourns.com/docs/product-datasheets/cr.pdf" (id 3) (at 20.32 -17.78 0)
        (effects (font (size 1.27 1.27) (thickness 0.15)) (justify left bottom) hide)
      )
      (property "MPN" "CR0402-FX-7502GLF" (id 4) (at 20.32 -20.32 0)
        (effects (font (size 1.27 1.27) (thickness 0.15)) (justify left bottom) hide)
      )
      (property "Manufacturer" "Bourns" (id 5) (at 20.32 -22.86 0)
        (effects (font (size 1.27 1.27) (thickness 0.15)) (justify left bottom) hide)
      )
      (property "License" "Apache-2.0" (id 6) (at 20.32 -25.4 0)
        (effects (font (size 1.27 1.27) (thickness 0.15)) (justify left bottom) hide)
      )
      (property "Author" "Antmicro" (id 7) (at 20.32 -27.94 0)
        (effects (font (size 1.27 1.27) (thickness 0.15)) (justify left bottom) hide)
      )
      (property "Val" "75k" (id 8) (at 20.32 -7.62 0)
        (effects (font (size 1.27 1.27) (thickness 0.15)) (justify left bottom))
      )
      (property "Tolerance" "1%" (id 9) (at 20.32 -10.16 0)
        (effects (font (size 1.27 1.27)) (justify left bottom) hide)
      )
      (property "ki_description" "75k resistor in 0402 package with 1% tolerance" (id 10) (at 0 0 0)
        (effects (font (size 1.27 1.27)) hide)
      )
      (symbol "R_75k_0402_0_1"
        (rectangle (start 0.635 0.889) (end 4.445 -0.889)
          (stroke (width 0.254) (type default) (color 0 0 0 0))
          (fill (type none))
        )
      )
      (symbol "R_75k_0402_1_1"
        (pin passive line (at 0 0 0) (length 0.635)
          (name "~" (effects (font (size 1.27 1.27))))
          (number "1" (effects (font (size 1.27 1.27))))
        )
        (pin passive line (at 5.08 0 180) (length 0.635)
          (name "~" (effects (font (size 1.27 1.27))))
          (number "2" (effects (font (size 1.27 1.27))))
        )
      )
    )
	(symbol "sa800u-baseboard-hw:R_7k5_0402" (pin_numbers hide) (pin_names hide) (in_bom yes) (on_board yes)
      (property "Reference" "R" (id 0) (at 20.32 -5.08 0)
        (effects (font (size 1.27 1.27) (thickness 0.15)) (justify left bottom))
      )
      (property "Value" "R_7k5_0402" (id 1) (at 20.32 -12.7 0)
        (effects (font (size 1.27 1.27) (thickness 0.15)) (justify left bottom) hide)
      )
      (property "Footprint" "sa800u-baseboard-hw-footprints:R_0402_1005Metric" (id 2) (at 20.32 -15.24 0)
        (effects (font (size 1.27 1.27) (thickness 0.15)) (justify left bottom) hide)
      )
      (property "Datasheet" "https://www.bourns.com/docs/product-datasheets/cr.pdf" (id 3) (at 20.32 -17.78 0)
        (effects (font (size 1.27 1.27) (thickness 0.15)) (justify left bottom) hide)
      )
      (property "MPN" "CR0402-FX-7501GLF" (id 4) (at 20.32 -20.32 0)
        (effects (font (size 1.27 1.27) (thickness 0.15)) (justify left bottom) hide)
      )
      (property "Manufacturer" "Bourns" (id 5) (at 20.32 -22.86 0)
        (effects (font (size 1.27 1.27) (thickness 0.15)) (justify left bottom) hide)
      )
      (property "License" "Apache-2.0" (id 6) (at 20.32 -25.4 0)
        (effects (font (size 1.27 1.27) (thickness 0.15)) (justify left bottom) hide)
      )
      (property "Author" "Antmicro" (id 7) (at 20.32 -27.94 0)
        (effects (font (size 1.27 1.27) (thickness 0.15)) (justify left bottom) hide)
      )
      (property "Val" "7k5" (id 8) (at 20.32 -7.62 0)
        (effects (font (size 1.27 1.27) (thickness 0.15)) (justify left bottom))
      )
      (property "Tolerance" "1%" (id 9) (at 20.32 -10.16 0)
        (effects (font (size 1.27 1.27)) (justify left bottom) hide)
      )
      (property "ki_description" "7k5 resistor in 0402 package with 1% tolerance" (id 10) (at 0 0 0)
        (effects (font (size 1.27 1.27)) hide)
      )
      (symbol "R_7k5_0402_0_1"
        (rectangle (start 0.635 0.889) (end 4.445 -0.889)
          (stroke (width 0.254) (type default) (color 0 0 0 0))
          (fill (type none))
        )
      )
      (symbol "R_7k5_0402_1_1"
        (pin passive line (at 0 0 0) (length 0.635)
          (name "~" (effects (font (size 1.27 1.27))))
          (number "1" (effects (font (size 1.27 1.27))))
        )
        (pin passive line (at 5.08 0 180) (length 0.635)
          (name "~" (effects (font (size 1.27 1.27))))
          (number "2" (effects (font (size 1.27 1.27))))
        )
      )
    )
	(symbol "sa800u-baseboard-hw:R_7k68_0402" (pin_numbers hide) (pin_names hide) (in_bom yes) (on_board yes)
      (property "Reference" "R" (id 0) (at 20.32 -5.08 0)
        (effects (font (size 1.27 1.27) (thickness 0.15)) (justify left bottom))
      )
      (property "Value" "R_7k68_0402" (id 1) (at 20.32 -12.7 0)
        (effects (font (size 1.27 1.27) (thickness 0.15)) (justify left bottom) hide)
      )
      (property "Footprint" "sa800u-baseboard-hw-footprints:R_0402_1005Metric" (id 2) (at 20.32 -15.24 0)
        (effects (font (size 1.27 1.27) (thickness 0.15)) (justify left bottom) hide)
      )
      (property "Datasheet" "https://www.bourns.com/docs/product-datasheets/cr.pdf" (id 3) (at 20.32 -17.78 0)
        (effects (font (size 1.27 1.27) (thickness 0.15)) (justify left bottom) hide)
      )
      (property "MPN" "CR0402-FX-7681GLF" (id 4) (at 20.32 -20.32 0)
        (effects (font (size 1.27 1.27) (thickness 0.15)) (justify left bottom) hide)
      )
      (property "Manufacturer" "Bourns" (id 5) (at 20.32 -22.86 0)
        (effects (font (size 1.27 1.27) (thickness 0.15)) (justify left bottom) hide)
      )
      (property "License" "Apache-2.0" (id 6) (at 20.32 -25.4 0)
        (effects (font (size 1.27 1.27) (thickness 0.15)) (justify left bottom) hide)
      )
      (property "Author" "Antmicro" (id 7) (at 20.32 -27.94 0)
        (effects (font (size 1.27 1.27) (thickness 0.15)) (justify left bottom) hide)
      )
      (property "Val" "7k68" (id 8) (at 20.32 -7.62 0)
        (effects (font (size 1.27 1.27) (thickness 0.15)) (justify left bottom))
      )
      (property "Tolerance" "1%" (id 9) (at 20.32 -10.16 0)
        (effects (font (size 1.27 1.27)) (justify left bottom) hide)
      )
      (property "ki_description" "7k68 resistor in 0402 package with 1% tolerance" (id 10) (at 0 0 0)
        (effects (font (size 1.27 1.27)) hide)
      )
      (symbol "R_7k68_0402_0_1"
        (rectangle (start 0.635 0.889) (end 4.445 -0.889)
          (stroke (width 0.254) (type default) (color 0 0 0 0))
          (fill (type none))
        )
      )
      (symbol "R_7k68_0402_1_1"
        (pin passive line (at 0 0 0) (length 0.635)
          (name "~" (effects (font (size 1.27 1.27))))
          (number "1" (effects (font (size 1.27 1.27))))
        )
        (pin passive line (at 5.08 0 180) (length 0.635)
          (name "~" (effects (font (size 1.27 1.27))))
          (number "2" (effects (font (size 1.27 1.27))))
        )
      )
    )
	(symbol "sa800u-baseboard-hw:Receptacle_SA800U-WF" (in_bom yes) (on_board yes)
      (property "Reference" "A" (id 0) (at 63.5 -5.08 0)
        (effects (font (size 1.27 1.27) (thickness 0.15)) (justify left bottom))
      )
      (property "Value" "Receptacle_SA800U-WF" (id 1) (at 63.5 -10.16 0)
        (effects (font (size 1.27 1.27) (thickness 0.15)) (justify left bottom) hide)
      )
      (property "Footprint" "sa800u-baseboard-hw-footprints:Receptacle_SA800U-WF" (id 2) (at 63.5 -12.7 0)
        (effects (font (size 1.27 1.27) (thickness 0.15)) (justify left bottom) hide)
      )
      (property "Datasheet" "https://www.farnell.com/datasheets/2691101.pdf" (id 3) (at 63.5 -15.24 0)
        (effects (font (size 1.27 1.27) (thickness 0.15)) (justify left bottom) hide)
      )
      (property "MPN" "FX10A-168S-SV" (id 4) (at 63.5 -7.62 0)
        (effects (font (size 1.27 1.27) (thickness 0.15)) (justify left bottom))
      )
      (property "Manufacturer" "Hirose Electric" (id 5) (at 63.5 -17.78 0)
        (effects (font (size 1.27 1.27) (thickness 0.15)) (justify left bottom) hide)
      )
      (property "Author" "Antmicro" (id 6) (at 63.5 -20.32 0)
        (effects (font (size 1.27 1.27) (thickness 0.15)) (justify left bottom) hide)
      )
      (property "License" "Apache-2.0" (id 7) (at 63.5 -22.86 0)
        (effects (font (size 1.27 1.27) (thickness 0.15)) (justify left bottom) hide)
      )
      (property "ki_locked" "" (id 8) (at 0 0 0)
        (effects (font (size 1.27 1.27)))
      )
      (property "ki_keywords" "CONNECTOR, B2B" (id 9) (at 0 0 0)
        (effects (font (size 1.27 1.27)) hide)
      )
      (property "ki_description" "Connectors for SA800U-WF module, MPN: 2x FX10A-168S-SV" (id 10) (at 0 0 0)
        (effects (font (size 1.27 1.27)) hide)
      )
      (symbol "Receptacle_SA800U-WF_1_1"
        (rectangle (start 6.35 2.54) (end 43.18 -162.56)
          (stroke (width 0.254) (type default) (color 0 0 0 0))
          (fill (type background))
        )
        (pin output line (at 49.53 0 180) (length 6.35)
          (name "PCIE0_RST_N" (effects (font (size 1.27 1.27))))
          (number "1_1" (effects (font (size 1.27 1.27))))
        )
        (pin input line (at 0 -7.62 0) (length 6.35)
          (name "CSI0_LN2_N" (effects (font (size 1.27 1.27))))
          (number "1_10" (effects (font (size 1.27 1.27))))
        )
        (pin output line (at 0 -86.36 0) (length 6.35)
          (name "CAM0_RST" (effects (font (size 1.27 1.27))))
          (number "1_100" (effects (font (size 1.27 1.27))))
        )
        (pin power_in line (at 0 -160.02 0) (length 6.35)
          (name "GND" (effects (font (size 1.27 1.27))))
          (number "1_101" (effects (font (size 1.27 1.27))))
        )
        (pin output line (at 0 -88.9 0) (length 6.35)
          (name "CAM0_AVDD_EN" (effects (font (size 1.27 1.27))))
          (number "1_102" (effects (font (size 1.27 1.27))))
        )
        (pin output line (at 49.53 -88.9 180) (length 6.35)
          (name "CAM3_MCLK" (effects (font (size 1.27 1.27))))
          (number "1_103" (effects (font (size 1.27 1.27))))
        )
        (pin output line (at 0 -91.44 0) (length 6.35)
          (name "CAM2_AVDD_EN" (effects (font (size 1.27 1.27))))
          (number "1_104" (effects (font (size 1.27 1.27))))
        )
        (pin passive line (at 0 -160.02 0) (length 6.35) hide
          (name "GND" (effects (font (size 1.27 1.27))))
          (number "1_105" (effects (font (size 1.27 1.27))))
        )
        (pin output line (at 0 -93.98 0) (length 6.35)
          (name "CAM2_PWDN" (effects (font (size 1.27 1.27))))
          (number "1_106" (effects (font (size 1.27 1.27))))
        )
        (pin output line (at 49.53 -91.44 180) (length 6.35)
          (name "PCIE1_RST_N" (effects (font (size 1.27 1.27))))
          (number "1_107" (effects (font (size 1.27 1.27))))
        )
        (pin output line (at 0 -96.52 0) (length 6.35)
          (name "CAM3_AVDD_EN" (effects (font (size 1.27 1.27))))
          (number "1_108" (effects (font (size 1.27 1.27))))
        )
        (pin input line (at 49.53 -93.98 180) (length 6.35)
          (name "PCIE1_CLKREQ_N" (effects (font (size 1.27 1.27))))
          (number "1_109" (effects (font (size 1.27 1.27))))
        )
        (pin output line (at 49.53 -10.16 180) (length 6.35)
          (name "PCIE0_TX_P" (effects (font (size 1.27 1.27))))
          (number "1_11" (effects (font (size 1.27 1.27))))
        )
        (pin output line (at 0 -99.06 0) (length 6.35)
          (name "CAM2_DVDD_EN" (effects (font (size 1.27 1.27))))
          (number "1_110" (effects (font (size 1.27 1.27))))
        )
        (pin input line (at 49.53 -96.52 180) (length 6.35)
          (name "PCIE1_WAKE_N" (effects (font (size 1.27 1.27))))
          (number "1_111" (effects (font (size 1.27 1.27))))
        )
        (pin output line (at 0 -101.6 0) (length 6.35)
          (name "CAM3_PWDN" (effects (font (size 1.27 1.27))))
          (number "1_112" (effects (font (size 1.27 1.27))))
        )
        (pin passive line (at 0 -160.02 0) (length 6.35) hide
          (name "GND" (effects (font (size 1.27 1.27))))
          (number "1_113" (effects (font (size 1.27 1.27))))
        )
        (pin output line (at 0 -104.14 0) (length 6.35)
          (name "CAM0_PWDN" (effects (font (size 1.27 1.27))))
          (number "1_114" (effects (font (size 1.27 1.27))))
        )
        (pin input line (at 49.53 -99.06 180) (length 6.35)
          (name "PCIE1_RX_P" (effects (font (size 1.27 1.27))))
          (number "1_115" (effects (font (size 1.27 1.27))))
        )
        (pin output line (at 0 -106.68 0) (length 6.35)
          (name "CAM1_STROBE" (effects (font (size 1.27 1.27))))
          (number "1_116" (effects (font (size 1.27 1.27))))
        )
        (pin input line (at 49.53 -101.6 180) (length 6.35)
          (name "PCIE1_RX_M" (effects (font (size 1.27 1.27))))
          (number "1_117" (effects (font (size 1.27 1.27))))
        )
        (pin input line (at 0 -109.22 0) (length 6.35)
          (name "CAM2_STROBE" (effects (font (size 1.27 1.27))))
          (number "1_118" (effects (font (size 1.27 1.27))))
        )
        (pin passive line (at 0 -160.02 0) (length 6.35) hide
          (name "GND" (effects (font (size 1.27 1.27))))
          (number "1_119" (effects (font (size 1.27 1.27))))
        )
        (pin input line (at 0 -5.08 0) (length 6.35)
          (name "CSI0_LN2_P" (effects (font (size 1.27 1.27))))
          (number "1_12" (effects (font (size 1.27 1.27))))
        )
        (pin output line (at 0 -111.76 0) (length 6.35)
          (name "CAM1_PWDN" (effects (font (size 1.27 1.27))))
          (number "1_120" (effects (font (size 1.27 1.27))))
        )
        (pin output line (at 49.53 -104.14 180) (length 6.35)
          (name "PCIE1_REFCLK_P" (effects (font (size 1.27 1.27))))
          (number "1_121" (effects (font (size 1.27 1.27))))
        )
        (pin output line (at 0 -114.3 0) (length 6.35)
          (name "CAM0_STROBE" (effects (font (size 1.27 1.27))))
          (number "1_122" (effects (font (size 1.27 1.27))))
        )
        (pin output line (at 49.53 -106.68 180) (length 6.35)
          (name "PCIE1_REFCLK_M" (effects (font (size 1.27 1.27))))
          (number "1_123" (effects (font (size 1.27 1.27))))
        )
        (pin output line (at 0 -116.84 0) (length 6.35)
          (name "CAM2_RST" (effects (font (size 1.27 1.27))))
          (number "1_124" (effects (font (size 1.27 1.27))))
        )
        (pin passive line (at 0 -160.02 0) (length 6.35) hide
          (name "GND" (effects (font (size 1.27 1.27))))
          (number "1_125" (effects (font (size 1.27 1.27))))
        )
        (pin output line (at 0 -119.38 0) (length 6.35)
          (name "CAM3_RST" (effects (font (size 1.27 1.27))))
          (number "1_126" (effects (font (size 1.27 1.27))))
        )
        (pin output line (at 49.53 -109.22 180) (length 6.35)
          (name "PCIE1_TX_M" (effects (font (size 1.27 1.27))))
          (number "1_127" (effects (font (size 1.27 1.27))))
        )
        (pin output line (at 0 -121.92 0) (length 6.35)
          (name "CAM3_DVDD_EN" (effects (font (size 1.27 1.27))))
          (number "1_128" (effects (font (size 1.27 1.27))))
        )
        (pin output line (at 49.53 -111.76 180) (length 6.35)
          (name "PCIE1_TX_P" (effects (font (size 1.27 1.27))))
          (number "1_129" (effects (font (size 1.27 1.27))))
        )
        (pin passive line (at 0 -160.02 0) (length 6.35) hide
          (name "GND" (effects (font (size 1.27 1.27))))
          (number "1_13" (effects (font (size 1.27 1.27))))
        )
        (pin output line (at 0 -124.46 0) (length 6.35)
          (name "CAM1_DVDD_EN" (effects (font (size 1.27 1.27))))
          (number "1_130" (effects (font (size 1.27 1.27))))
        )
        (pin passive line (at 0 -160.02 0) (length 6.35) hide
          (name "GND" (effects (font (size 1.27 1.27))))
          (number "1_131" (effects (font (size 1.27 1.27))))
        )
        (pin output line (at 0 -127 0) (length 6.35)
          (name "CAM0_DVDD_EN" (effects (font (size 1.27 1.27))))
          (number "1_132" (effects (font (size 1.27 1.27))))
        )
        (pin input line (at 49.53 -114.3 180) (length 6.35)
          (name "MAG_INT" (effects (font (size 1.27 1.27))))
          (number "1_133" (effects (font (size 1.27 1.27))))
        )
        (pin input line (at 0 -129.54 0) (length 6.35)
          (name "CBL_PWR_N" (effects (font (size 1.27 1.27))))
          (number "1_134" (effects (font (size 1.27 1.27))))
        )
        (pin input line (at 49.53 -116.84 180) (length 6.35)
          (name "MAG_DRDY_INT" (effects (font (size 1.27 1.27))))
          (number "1_135" (effects (font (size 1.27 1.27))))
        )
        (pin output line (at 0 -132.08 0) (length 6.35)
          (name "SSC_SPI1_CS0" (effects (font (size 1.27 1.27))))
          (number "1_136" (effects (font (size 1.27 1.27))))
        )
        (pin input line (at 49.53 -119.38 180) (length 6.35)
          (name "GYRO_INT" (effects (font (size 1.27 1.27))))
          (number "1_137" (effects (font (size 1.27 1.27))))
        )
        (pin output line (at 0 -134.62 0) (length 6.35)
          (name "SSC_SPI1_CS1" (effects (font (size 1.27 1.27))))
          (number "1_138" (effects (font (size 1.27 1.27))))
        )
        (pin input line (at 49.53 -121.92 180) (length 6.35)
          (name "ACCEL_INT" (effects (font (size 1.27 1.27))))
          (number "1_139" (effects (font (size 1.27 1.27))))
        )
        (pin passive line (at 0 -160.02 0) (length 6.35) hide
          (name "GND" (effects (font (size 1.27 1.27))))
          (number "1_14" (effects (font (size 1.27 1.27))))
        )
        (pin output line (at 0 -137.16 0) (length 6.35)
          (name "SSC_SPI1_CS2" (effects (font (size 1.27 1.27))))
          (number "1_140" (effects (font (size 1.27 1.27))))
        )
        (pin output line (at 49.53 -124.46 180) (length 6.35)
          (name "SSC_SPI2_CS" (effects (font (size 1.27 1.27))))
          (number "1_141" (effects (font (size 1.27 1.27))))
        )
        (pin output line (at 0 -139.7 0) (length 6.35)
          (name "CCI0_I2C_SCL" (effects (font (size 1.27 1.27))))
          (number "1_142" (effects (font (size 1.27 1.27))))
        )
        (pin output line (at 49.53 -127 180) (length 6.35)
          (name "SSC_SPI2_MOSI" (effects (font (size 1.27 1.27))))
          (number "1_143" (effects (font (size 1.27 1.27))))
        )
        (pin bidirectional line (at 0 -142.24 0) (length 6.35)
          (name "CCI0_I2C_SDA" (effects (font (size 1.27 1.27))))
          (number "1_144" (effects (font (size 1.27 1.27))))
        )
        (pin output line (at 49.53 -129.54 180) (length 6.35)
          (name "SSC_SPI2_CLK" (effects (font (size 1.27 1.27))))
          (number "1_145" (effects (font (size 1.27 1.27))))
        )
        (pin bidirectional line (at 0 -144.78 0) (length 6.35)
          (name "CCI1_I2C_SDA" (effects (font (size 1.27 1.27))))
          (number "1_146" (effects (font (size 1.27 1.27))))
        )
        (pin input line (at 49.53 -132.08 180) (length 6.35)
          (name "SSC_SPI2_MISO" (effects (font (size 1.27 1.27))))
          (number "1_147" (effects (font (size 1.27 1.27))))
        )
        (pin output line (at 0 -147.32 0) (length 6.35)
          (name "CCI1_I2C_SCL" (effects (font (size 1.27 1.27))))
          (number "1_148" (effects (font (size 1.27 1.27))))
        )
        (pin power_in line (at 49.53 -134.62 180) (length 6.35)
          (name "LVS1A_1V8" (effects (font (size 1.27 1.27))))
          (number "1_149" (effects (font (size 1.27 1.27))))
        )
        (pin output line (at 49.53 -12.7 180) (length 6.35)
          (name "PCIE0_REFCLK_P" (effects (font (size 1.27 1.27))))
          (number "1_15" (effects (font (size 1.27 1.27))))
        )
        (pin input line (at 0 -149.86 0) (length 6.35)
          (name "SSC_SPI1_MISO" (effects (font (size 1.27 1.27))))
          (number "1_150" (effects (font (size 1.27 1.27))))
        )
        (pin power_in line (at 49.53 -137.16 180) (length 6.35)
          (name "SD_LDO21A" (effects (font (size 1.27 1.27))))
          (number "1_151" (effects (font (size 1.27 1.27))))
        )
        (pin output line (at 0 -152.4 0) (length 6.35)
          (name "SSC_SPI1_MOSI" (effects (font (size 1.27 1.27))))
          (number "1_152" (effects (font (size 1.27 1.27))))
        )
        (pin passive line (at 49.53 -137.16 180) (length 6.35) hide
          (name "SD_LDO21A" (effects (font (size 1.27 1.27))))
          (number "1_153" (effects (font (size 1.27 1.27))))
        )
        (pin output line (at 0 -154.94 0) (length 6.35)
          (name "SSC_SPI1_CLK" (effects (font (size 1.27 1.27))))
          (number "1_154" (effects (font (size 1.27 1.27))))
        )
        (pin passive line (at 49.53 -137.16 180) (length 6.35) hide
          (name "SD_LDO21A" (effects (font (size 1.27 1.27))))
          (number "1_155" (effects (font (size 1.27 1.27))))
        )
        (pin passive line (at 0 -160.02 0) (length 6.35) hide
          (name "GND" (effects (font (size 1.27 1.27))))
          (number "1_156" (effects (font (size 1.27 1.27))))
        )
        (pin passive line (at 0 -160.02 0) (length 6.35) hide
          (name "GND" (effects (font (size 1.27 1.27))))
          (number "1_157" (effects (font (size 1.27 1.27))))
        )
        (pin passive line (at 0 -160.02 0) (length 6.35) hide
          (name "GND" (effects (font (size 1.27 1.27))))
          (number "1_158" (effects (font (size 1.27 1.27))))
        )
        (pin power_in line (at 0 -157.48 0) (length 6.35)
          (name "VBAT" (effects (font (size 1.27 1.27))))
          (number "1_159" (effects (font (size 1.27 1.27))))
        )
        (pin input line (at 0 -12.7 0) (length 6.35)
          (name "CSI0_LN1_N" (effects (font (size 1.27 1.27))))
          (number "1_16" (effects (font (size 1.27 1.27))))
        )
        (pin passive line (at 0 -157.48 0) (length 6.35) hide
          (name "VBAT" (effects (font (size 1.27 1.27))))
          (number "1_160" (effects (font (size 1.27 1.27))))
        )
        (pin passive line (at 0 -157.48 0) (length 6.35) hide
          (name "VBAT" (effects (font (size 1.27 1.27))))
          (number "1_161" (effects (font (size 1.27 1.27))))
        )
        (pin passive line (at 0 -157.48 0) (length 6.35) hide
          (name "VBAT" (effects (font (size 1.27 1.27))))
          (number "1_162" (effects (font (size 1.27 1.27))))
        )
        (pin passive line (at 0 -157.48 0) (length 6.35) hide
          (name "VBAT" (effects (font (size 1.27 1.27))))
          (number "1_163" (effects (font (size 1.27 1.27))))
        )
        (pin passive line (at 0 -157.48 0) (length 6.35) hide
          (name "VBAT" (effects (font (size 1.27 1.27))))
          (number "1_164" (effects (font (size 1.27 1.27))))
        )
        (pin passive line (at 0 -157.48 0) (length 6.35) hide
          (name "VBAT" (effects (font (size 1.27 1.27))))
          (number "1_165" (effects (font (size 1.27 1.27))))
        )
        (pin passive line (at 0 -157.48 0) (length 6.35) hide
          (name "VBAT" (effects (font (size 1.27 1.27))))
          (number "1_166" (effects (font (size 1.27 1.27))))
        )
        (pin passive line (at 0 -157.48 0) (length 6.35) hide
          (name "VBAT" (effects (font (size 1.27 1.27))))
          (number "1_167" (effects (font (size 1.27 1.27))))
        )
        (pin passive line (at 0 -157.48 0) (length 6.35) hide
          (name "VBAT" (effects (font (size 1.27 1.27))))
          (number "1_168" (effects (font (size 1.27 1.27))))
        )
        (pin output line (at 49.53 -15.24 180) (length 6.35)
          (name "PCIE0_REFCLK_M" (effects (font (size 1.27 1.27))))
          (number "1_17" (effects (font (size 1.27 1.27))))
        )
        (pin no_connect line (at 43.18 -139.7 180) (length 6.35) hide
          (name "NC" (effects (font (size 1.27 1.27))))
          (number "1_171" (effects (font (size 1.27 1.27))))
        )
        (pin no_connect line (at 43.18 -142.24 180) (length 6.35) hide
          (name "NC" (effects (font (size 1.27 1.27))))
          (number "1_172" (effects (font (size 1.27 1.27))))
        )
        (pin input line (at 0 -10.16 0) (length 6.35)
          (name "CSI0_LN1_P" (effects (font (size 1.27 1.27))))
          (number "1_18" (effects (font (size 1.27 1.27))))
        )
        (pin passive line (at 0 -160.02 0) (length 6.35) hide
          (name "GND" (effects (font (size 1.27 1.27))))
          (number "1_19" (effects (font (size 1.27 1.27))))
        )
        (pin passive line (at 0 -160.02 0) (length 6.35) hide
          (name "GND" (effects (font (size 1.27 1.27))))
          (number "1_2" (effects (font (size 1.27 1.27))))
        )
        (pin passive line (at 0 -160.02 0) (length 6.35) hide
          (name "GND" (effects (font (size 1.27 1.27))))
          (number "1_20" (effects (font (size 1.27 1.27))))
        )
        (pin input line (at 49.53 -17.78 180) (length 6.35)
          (name "PCIE0_RX_P" (effects (font (size 1.27 1.27))))
          (number "1_21" (effects (font (size 1.27 1.27))))
        )
        (pin input line (at 0 -17.78 0) (length 6.35)
          (name "CSI0_LN0_N" (effects (font (size 1.27 1.27))))
          (number "1_22" (effects (font (size 1.27 1.27))))
        )
        (pin input line (at 49.53 -20.32 180) (length 6.35)
          (name "PCIE0_RX_M" (effects (font (size 1.27 1.27))))
          (number "1_23" (effects (font (size 1.27 1.27))))
        )
        (pin input line (at 0 -15.24 0) (length 6.35)
          (name "CSI0_LN0_P" (effects (font (size 1.27 1.27))))
          (number "1_24" (effects (font (size 1.27 1.27))))
        )
        (pin passive line (at 0 -160.02 0) (length 6.35) hide
          (name "GND" (effects (font (size 1.27 1.27))))
          (number "1_25" (effects (font (size 1.27 1.27))))
        )
        (pin passive line (at 0 -160.02 0) (length 6.35) hide
          (name "GND" (effects (font (size 1.27 1.27))))
          (number "1_26" (effects (font (size 1.27 1.27))))
        )
        (pin input line (at 49.53 -22.86 180) (length 6.35)
          (name "UFS_RX_M" (effects (font (size 1.27 1.27))))
          (number "1_27" (effects (font (size 1.27 1.27))))
        )
        (pin input line (at 0 -20.32 0) (length 6.35)
          (name "CSI0_CLK_P" (effects (font (size 1.27 1.27))))
          (number "1_28" (effects (font (size 1.27 1.27))))
        )
        (pin input line (at 49.53 -25.4 180) (length 6.35)
          (name "UFS_RX_P" (effects (font (size 1.27 1.27))))
          (number "1_29" (effects (font (size 1.27 1.27))))
        )
        (pin input line (at 49.53 -2.54 180) (length 6.35)
          (name "PCIE0_WAKE_N" (effects (font (size 1.27 1.27))))
          (number "1_3" (effects (font (size 1.27 1.27))))
        )
        (pin input line (at 0 -22.86 0) (length 6.35)
          (name "CSI0_CLK_N" (effects (font (size 1.27 1.27))))
          (number "1_30" (effects (font (size 1.27 1.27))))
        )
        (pin passive line (at 0 -160.02 0) (length 6.35) hide
          (name "GND" (effects (font (size 1.27 1.27))))
          (number "1_31" (effects (font (size 1.27 1.27))))
        )
        (pin passive line (at 0 -160.02 0) (length 6.35) hide
          (name "GND" (effects (font (size 1.27 1.27))))
          (number "1_32" (effects (font (size 1.27 1.27))))
        )
        (pin output line (at 49.53 -27.94 180) (length 6.35)
          (name "UFS_TX_P" (effects (font (size 1.27 1.27))))
          (number "1_33" (effects (font (size 1.27 1.27))))
        )
        (pin input line (at 0 -27.94 0) (length 6.35)
          (name "CSI1_LN3_N" (effects (font (size 1.27 1.27))))
          (number "1_34" (effects (font (size 1.27 1.27))))
        )
        (pin output line (at 49.53 -30.48 180) (length 6.35)
          (name "UFS_TX_M" (effects (font (size 1.27 1.27))))
          (number "1_35" (effects (font (size 1.27 1.27))))
        )
        (pin input line (at 0 -25.4 0) (length 6.35)
          (name "CSI1_LN3_P" (effects (font (size 1.27 1.27))))
          (number "1_36" (effects (font (size 1.27 1.27))))
        )
        (pin passive line (at 0 -160.02 0) (length 6.35) hide
          (name "GND" (effects (font (size 1.27 1.27))))
          (number "1_37" (effects (font (size 1.27 1.27))))
        )
        (pin passive line (at 0 -160.02 0) (length 6.35) hide
          (name "GND" (effects (font (size 1.27 1.27))))
          (number "1_38" (effects (font (size 1.27 1.27))))
        )
        (pin output line (at 49.53 -33.02 180) (length 6.35)
          (name "UFS_CLK" (effects (font (size 1.27 1.27))))
          (number "1_39" (effects (font (size 1.27 1.27))))
        )
        (pin input line (at 0 0 0) (length 6.35)
          (name "CSI0_LN3_P" (effects (font (size 1.27 1.27))))
          (number "1_4" (effects (font (size 1.27 1.27))))
        )
        (pin input line (at 0 -30.48 0) (length 6.35)
          (name "CSI1_LN2_P" (effects (font (size 1.27 1.27))))
          (number "1_40" (effects (font (size 1.27 1.27))))
        )
        (pin passive line (at 0 -160.02 0) (length 6.35) hide
          (name "GND" (effects (font (size 1.27 1.27))))
          (number "1_41" (effects (font (size 1.27 1.27))))
        )
        (pin input line (at 0 -33.02 0) (length 6.35)
          (name "CSI1_LN2_N" (effects (font (size 1.27 1.27))))
          (number "1_42" (effects (font (size 1.27 1.27))))
        )
        (pin output line (at 49.53 -35.56 180) (length 6.35)
          (name "UFS_DET" (effects (font (size 1.27 1.27))))
          (number "1_43" (effects (font (size 1.27 1.27))))
        )
        (pin passive line (at 0 -160.02 0) (length 6.35) hide
          (name "GND" (effects (font (size 1.27 1.27))))
          (number "1_44" (effects (font (size 1.27 1.27))))
        )
        (pin output line (at 49.53 -38.1 180) (length 6.35)
          (name "SD_CLK" (effects (font (size 1.27 1.27))))
          (number "1_45" (effects (font (size 1.27 1.27))))
        )
        (pin input line (at 0 -38.1 0) (length 6.35)
          (name "CSI1_LN1_N" (effects (font (size 1.27 1.27))))
          (number "1_46" (effects (font (size 1.27 1.27))))
        )
        (pin output line (at 49.53 -40.64 180) (length 6.35)
          (name "SD_CMD" (effects (font (size 1.27 1.27))))
          (number "1_47" (effects (font (size 1.27 1.27))))
        )
        (pin input line (at 0 -35.56 0) (length 6.35)
          (name "CSI1_LN1_P" (effects (font (size 1.27 1.27))))
          (number "1_48" (effects (font (size 1.27 1.27))))
        )
        (pin input line (at 49.53 -43.18 180) (length 6.35)
          (name "SD_DET" (effects (font (size 1.27 1.27))))
          (number "1_49" (effects (font (size 1.27 1.27))))
        )
        (pin input line (at 49.53 -5.08 180) (length 6.35)
          (name "PCIE0_CLKREQ_N" (effects (font (size 1.27 1.27))))
          (number "1_5" (effects (font (size 1.27 1.27))))
        )
        (pin passive line (at 0 -160.02 0) (length 6.35) hide
          (name "GND" (effects (font (size 1.27 1.27))))
          (number "1_50" (effects (font (size 1.27 1.27))))
        )
        (pin bidirectional line (at 49.53 -45.72 180) (length 6.35)
          (name "SD_DATA0" (effects (font (size 1.27 1.27))))
          (number "1_51" (effects (font (size 1.27 1.27))))
        )
        (pin input line (at 0 -43.18 0) (length 6.35)
          (name "CSI1_LN0_N" (effects (font (size 1.27 1.27))))
          (number "1_52" (effects (font (size 1.27 1.27))))
        )
        (pin bidirectional line (at 49.53 -48.26 180) (length 6.35)
          (name "SD_DATA1" (effects (font (size 1.27 1.27))))
          (number "1_53" (effects (font (size 1.27 1.27))))
        )
        (pin input line (at 0 -40.64 0) (length 6.35)
          (name "CSI1_LN0_P" (effects (font (size 1.27 1.27))))
          (number "1_54" (effects (font (size 1.27 1.27))))
        )
        (pin bidirectional line (at 49.53 -50.8 180) (length 6.35)
          (name "SD_DATA3" (effects (font (size 1.27 1.27))))
          (number "1_55" (effects (font (size 1.27 1.27))))
        )
        (pin passive line (at 0 -160.02 0) (length 6.35) hide
          (name "GND" (effects (font (size 1.27 1.27))))
          (number "1_56" (effects (font (size 1.27 1.27))))
        )
        (pin bidirectional line (at 49.53 -53.34 180) (length 6.35)
          (name "SD_DATA2" (effects (font (size 1.27 1.27))))
          (number "1_57" (effects (font (size 1.27 1.27))))
        )
        (pin input line (at 0 -48.26 0) (length 6.35)
          (name "CSI1_CLK_N" (effects (font (size 1.27 1.27))))
          (number "1_58" (effects (font (size 1.27 1.27))))
        )
        (pin passive line (at 0 -160.02 0) (length 6.35) hide
          (name "GND" (effects (font (size 1.27 1.27))))
          (number "1_59" (effects (font (size 1.27 1.27))))
        )
        (pin input line (at 0 -2.54 0) (length 6.35)
          (name "CSI0_LN3_N" (effects (font (size 1.27 1.27))))
          (number "1_6" (effects (font (size 1.27 1.27))))
        )
        (pin input line (at 0 -45.72 0) (length 6.35)
          (name "CSI1_CLK_P" (effects (font (size 1.27 1.27))))
          (number "1_60" (effects (font (size 1.27 1.27))))
        )
        (pin input line (at 49.53 -55.88 180) (length 6.35)
          (name "CSI2_CLK_P" (effects (font (size 1.27 1.27))))
          (number "1_61" (effects (font (size 1.27 1.27))))
        )
        (pin passive line (at 0 -160.02 0) (length 6.35) hide
          (name "GND" (effects (font (size 1.27 1.27))))
          (number "1_62" (effects (font (size 1.27 1.27))))
        )
        (pin input line (at 49.53 -58.42 180) (length 6.35)
          (name "CSI2_CLK_N" (effects (font (size 1.27 1.27))))
          (number "1_63" (effects (font (size 1.27 1.27))))
        )
        (pin input line (at 0 -50.8 0) (length 6.35)
          (name "CSI2_LN1_P" (effects (font (size 1.27 1.27))))
          (number "1_64" (effects (font (size 1.27 1.27))))
        )
        (pin passive line (at 0 -160.02 0) (length 6.35) hide
          (name "GND" (effects (font (size 1.27 1.27))))
          (number "1_65" (effects (font (size 1.27 1.27))))
        )
        (pin input line (at 0 -53.34 0) (length 6.35)
          (name "CSI2_LN1_N" (effects (font (size 1.27 1.27))))
          (number "1_66" (effects (font (size 1.27 1.27))))
        )
        (pin input line (at 49.53 -63.5 180) (length 6.35)
          (name "CSI2_LN0_N" (effects (font (size 1.27 1.27))))
          (number "1_67" (effects (font (size 1.27 1.27))))
        )
        (pin passive line (at 0 -160.02 0) (length 6.35) hide
          (name "GND" (effects (font (size 1.27 1.27))))
          (number "1_68" (effects (font (size 1.27 1.27))))
        )
        (pin input line (at 49.53 -60.96 180) (length 6.35)
          (name "CSI2_LN0_P" (effects (font (size 1.27 1.27))))
          (number "1_69" (effects (font (size 1.27 1.27))))
        )
        (pin passive line (at 0 -160.02 0) (length 6.35) hide
          (name "GND" (effects (font (size 1.27 1.27))))
          (number "1_7" (effects (font (size 1.27 1.27))))
        )
        (pin input line (at 0 -55.88 0) (length 6.35)
          (name "CSI2_LN2_P" (effects (font (size 1.27 1.27))))
          (number "1_70" (effects (font (size 1.27 1.27))))
        )
        (pin passive line (at 0 -160.02 0) (length 6.35) hide
          (name "GND" (effects (font (size 1.27 1.27))))
          (number "1_71" (effects (font (size 1.27 1.27))))
        )
        (pin input line (at 0 -58.42 0) (length 6.35)
          (name "CSI2_LN2_N" (effects (font (size 1.27 1.27))))
          (number "1_72" (effects (font (size 1.27 1.27))))
        )
        (pin input line (at 49.53 -68.58 180) (length 6.35)
          (name "CSI3_LN1_N" (effects (font (size 1.27 1.27))))
          (number "1_73" (effects (font (size 1.27 1.27))))
        )
        (pin passive line (at 0 -160.02 0) (length 6.35) hide
          (name "GND" (effects (font (size 1.27 1.27))))
          (number "1_74" (effects (font (size 1.27 1.27))))
        )
        (pin input line (at 49.53 -66.04 180) (length 6.35)
          (name "CSI3_LN1_P" (effects (font (size 1.27 1.27))))
          (number "1_75" (effects (font (size 1.27 1.27))))
        )
        (pin input line (at 0 -60.96 0) (length 6.35)
          (name "CSI2_LN3_P" (effects (font (size 1.27 1.27))))
          (number "1_76" (effects (font (size 1.27 1.27))))
        )
        (pin passive line (at 0 -160.02 0) (length 6.35) hide
          (name "GND" (effects (font (size 1.27 1.27))))
          (number "1_77" (effects (font (size 1.27 1.27))))
        )
        (pin input line (at 0 -63.5 0) (length 6.35)
          (name "CSI2_LN3_N" (effects (font (size 1.27 1.27))))
          (number "1_78" (effects (font (size 1.27 1.27))))
        )
        (pin input line (at 49.53 -71.12 180) (length 6.35)
          (name "CSI3_LN0_P" (effects (font (size 1.27 1.27))))
          (number "1_79" (effects (font (size 1.27 1.27))))
        )
        (pin passive line (at 0 -160.02 0) (length 6.35) hide
          (name "GND" (effects (font (size 1.27 1.27))))
          (number "1_8" (effects (font (size 1.27 1.27))))
        )
        (pin passive line (at 0 -160.02 0) (length 6.35) hide
          (name "GND" (effects (font (size 1.27 1.27))))
          (number "1_80" (effects (font (size 1.27 1.27))))
        )
        (pin input line (at 49.53 -73.66 180) (length 6.35)
          (name "CSI3_LN0_N" (effects (font (size 1.27 1.27))))
          (number "1_81" (effects (font (size 1.27 1.27))))
        )
        (pin output line (at 0 -66.04 0) (length 6.35)
          (name "SDC4_DATA0" (effects (font (size 1.27 1.27))))
          (number "1_82" (effects (font (size 1.27 1.27))))
        )
        (pin passive line (at 0 -160.02 0) (length 6.35) hide
          (name "GND" (effects (font (size 1.27 1.27))))
          (number "1_83" (effects (font (size 1.27 1.27))))
        )
        (pin output line (at 0 -68.58 0) (length 6.35)
          (name "SDC4_DATA1" (effects (font (size 1.27 1.27))))
          (number "1_84" (effects (font (size 1.27 1.27))))
        )
        (pin input line (at 49.53 -78.74 180) (length 6.35)
          (name "CSI3_CLK_N" (effects (font (size 1.27 1.27))))
          (number "1_85" (effects (font (size 1.27 1.27))))
        )
        (pin output line (at 0 -71.12 0) (length 6.35)
          (name "SDC4_CLK" (effects (font (size 1.27 1.27))))
          (number "1_86" (effects (font (size 1.27 1.27))))
        )
        (pin input line (at 49.53 -76.2 180) (length 6.35)
          (name "CSI3_CLK_P" (effects (font (size 1.27 1.27))))
          (number "1_87" (effects (font (size 1.27 1.27))))
        )
        (pin output line (at 0 -73.66 0) (length 6.35)
          (name "SDC4_DATA2" (effects (font (size 1.27 1.27))))
          (number "1_88" (effects (font (size 1.27 1.27))))
        )
        (pin passive line (at 0 -160.02 0) (length 6.35) hide
          (name "GND" (effects (font (size 1.27 1.27))))
          (number "1_89" (effects (font (size 1.27 1.27))))
        )
        (pin output line (at 49.53 -7.62 180) (length 6.35)
          (name "PCIE0_TX_M" (effects (font (size 1.27 1.27))))
          (number "1_9" (effects (font (size 1.27 1.27))))
        )
        (pin output line (at 0 -76.2 0) (length 6.35)
          (name "SDC4_DATA3" (effects (font (size 1.27 1.27))))
          (number "1_90" (effects (font (size 1.27 1.27))))
        )
        (pin output line (at 49.53 -81.28 180) (length 6.35)
          (name "CAM0_MCLK" (effects (font (size 1.27 1.27))))
          (number "1_91" (effects (font (size 1.27 1.27))))
        )
        (pin output line (at 0 -78.74 0) (length 6.35)
          (name "SDC4_CMD" (effects (font (size 1.27 1.27))))
          (number "1_92" (effects (font (size 1.27 1.27))))
        )
        (pin passive line (at 0 -160.02 0) (length 6.35) hide
          (name "GND" (effects (font (size 1.27 1.27))))
          (number "1_93" (effects (font (size 1.27 1.27))))
        )
        (pin passive line (at 0 -160.02 0) (length 6.35) hide
          (name "GND" (effects (font (size 1.27 1.27))))
          (number "1_94" (effects (font (size 1.27 1.27))))
        )
        (pin output line (at 49.53 -83.82 180) (length 6.35)
          (name "CAM1_MCLK" (effects (font (size 1.27 1.27))))
          (number "1_95" (effects (font (size 1.27 1.27))))
        )
        (pin output line (at 0 -81.28 0) (length 6.35)
          (name "CAM1_RST" (effects (font (size 1.27 1.27))))
          (number "1_96" (effects (font (size 1.27 1.27))))
        )
        (pin passive line (at 0 -160.02 0) (length 6.35) hide
          (name "GND" (effects (font (size 1.27 1.27))))
          (number "1_97" (effects (font (size 1.27 1.27))))
        )
        (pin output line (at 0 -83.82 0) (length 6.35)
          (name "CAM1_AVDD_EN" (effects (font (size 1.27 1.27))))
          (number "1_98" (effects (font (size 1.27 1.27))))
        )
        (pin output line (at 49.53 -86.36 180) (length 6.35)
          (name "CAM2_MCLK" (effects (font (size 1.27 1.27))))
          (number "1_99" (effects (font (size 1.27 1.27))))
        )
      )
      (symbol "Receptacle_SA800U-WF_2_1"
        (rectangle (start 6.35 2.54) (end 43.18 -175.26)
          (stroke (width 0.254) (type default) (color 0 0 0 0))
          (fill (type background))
        )
        (pin output line (at 49.53 0 180) (length 6.35)
          (name "SBU_SW_OE" (effects (font (size 1.27 1.27))))
          (number "2_1" (effects (font (size 1.27 1.27))))
        )
        (pin output line (at 0 -10.16 0) (length 6.35)
          (name "SSC_I2C1_SCL" (effects (font (size 1.27 1.27))))
          (number "2_10" (effects (font (size 1.27 1.27))))
        )
        (pin input line (at 0 -109.22 0) (length 6.35)
          (name "USB2_SS_RX_M" (effects (font (size 1.27 1.27))))
          (number "2_100" (effects (font (size 1.27 1.27))))
        )
        (pin output line (at 49.53 -106.68 180) (length 6.35)
          (name "SPI11_CS" (effects (font (size 1.27 1.27))))
          (number "2_101" (effects (font (size 1.27 1.27))))
        )
        (pin input line (at 0 -106.68 0) (length 6.35)
          (name "USB2_SS_RX_P" (effects (font (size 1.27 1.27))))
          (number "2_102" (effects (font (size 1.27 1.27))))
        )
        (pin power_in line (at 0 -172.72 0) (length 6.35)
          (name "GND" (effects (font (size 1.27 1.27))))
          (number "2_103" (effects (font (size 1.27 1.27))))
        )
        (pin passive line (at 0 -172.72 0) (length 6.35) hide
          (name "GND" (effects (font (size 1.27 1.27))))
          (number "2_104" (effects (font (size 1.27 1.27))))
        )
        (pin bidirectional line (at 49.53 -109.22 180) (length 6.35)
          (name "USB2_DP" (effects (font (size 1.27 1.27))))
          (number "2_105" (effects (font (size 1.27 1.27))))
        )
        (pin output line (at 0 -111.76 0) (length 6.35)
          (name "USB2_SS_TX_P" (effects (font (size 1.27 1.27))))
          (number "2_106" (effects (font (size 1.27 1.27))))
        )
        (pin bidirectional line (at 49.53 -111.76 180) (length 6.35)
          (name "USB2_DM" (effects (font (size 1.27 1.27))))
          (number "2_107" (effects (font (size 1.27 1.27))))
        )
        (pin output line (at 0 -114.3 0) (length 6.35)
          (name "USB2_SS_TX_M" (effects (font (size 1.27 1.27))))
          (number "2_108" (effects (font (size 1.27 1.27))))
        )
        (pin passive line (at 0 -172.72 0) (length 6.35) hide
          (name "GND" (effects (font (size 1.27 1.27))))
          (number "2_109" (effects (font (size 1.27 1.27))))
        )
        (pin passive line (at 0 -172.72 0) (length 6.35) hide
          (name "GND" (effects (font (size 1.27 1.27))))
          (number "2_11" (effects (font (size 1.27 1.27))))
        )
        (pin passive line (at 0 -172.72 0) (length 6.35) hide
          (name "GND" (effects (font (size 1.27 1.27))))
          (number "2_110" (effects (font (size 1.27 1.27))))
        )
        (pin output line (at 49.53 -116.84 180) (length 6.35)
          (name "USB1_SS2_TX_M" (effects (font (size 1.27 1.27))))
          (number "2_111" (effects (font (size 1.27 1.27))))
        )
        (pin input line (at 0 -116.84 0) (length 6.35)
          (name "USB1_SS2_RX_P" (effects (font (size 1.27 1.27))))
          (number "2_112" (effects (font (size 1.27 1.27))))
        )
        (pin output line (at 49.53 -114.3 180) (length 6.35)
          (name "USB1_SS2_TX_P" (effects (font (size 1.27 1.27))))
          (number "2_113" (effects (font (size 1.27 1.27))))
        )
        (pin input line (at 0 -119.38 0) (length 6.35)
          (name "USB1_SS2_RX_M" (effects (font (size 1.27 1.27))))
          (number "2_114" (effects (font (size 1.27 1.27))))
        )
        (pin passive line (at 0 -172.72 0) (length 6.35) hide
          (name "GND" (effects (font (size 1.27 1.27))))
          (number "2_115" (effects (font (size 1.27 1.27))))
        )
        (pin passive line (at 0 -172.72 0) (length 6.35) hide
          (name "GND" (effects (font (size 1.27 1.27))))
          (number "2_116" (effects (font (size 1.27 1.27))))
        )
        (pin bidirectional line (at 49.53 -121.92 180) (length 6.35)
          (name "USB1_DM" (effects (font (size 1.27 1.27))))
          (number "2_117" (effects (font (size 1.27 1.27))))
        )
        (pin input line (at 0 -124.46 0) (length 6.35)
          (name "USB1_SS1_RX_M" (effects (font (size 1.27 1.27))))
          (number "2_118" (effects (font (size 1.27 1.27))))
        )
        (pin bidirectional line (at 49.53 -119.38 180) (length 6.35)
          (name "USB1_DP" (effects (font (size 1.27 1.27))))
          (number "2_119" (effects (font (size 1.27 1.27))))
        )
        (pin passive line (at 0 -172.72 0) (length 6.35) hide
          (name "GND" (effects (font (size 1.27 1.27))))
          (number "2_12" (effects (font (size 1.27 1.27))))
        )
        (pin input line (at 0 -121.92 0) (length 6.35)
          (name "USB1_SS1_RX_P" (effects (font (size 1.27 1.27))))
          (number "2_120" (effects (font (size 1.27 1.27))))
        )
        (pin passive line (at 0 -172.72 0) (length 6.35) hide
          (name "GND" (effects (font (size 1.27 1.27))))
          (number "2_121" (effects (font (size 1.27 1.27))))
        )
        (pin passive line (at 0 -172.72 0) (length 6.35) hide
          (name "GND" (effects (font (size 1.27 1.27))))
          (number "2_122" (effects (font (size 1.27 1.27))))
        )
        (pin output line (at 49.53 -127 180) (length 6.35)
          (name "USB1_SS1_TX_M" (effects (font (size 1.27 1.27))))
          (number "2_123" (effects (font (size 1.27 1.27))))
        )
        (pin power_in line (at 0 -127 0) (length 6.35)
          (name "VREG_S4A_1V8" (effects (font (size 1.27 1.27))))
          (number "2_124" (effects (font (size 1.27 1.27))))
        )
        (pin output line (at 49.53 -124.46 180) (length 6.35)
          (name "USB1_SS1_TX_P" (effects (font (size 1.27 1.27))))
          (number "2_125" (effects (font (size 1.27 1.27))))
        )
        (pin passive line (at 0 -127 0) (length 6.35) hide
          (name "VREG_S4A_1V8" (effects (font (size 1.27 1.27))))
          (number "2_126" (effects (font (size 1.27 1.27))))
        )
        (pin passive line (at 0 -172.72 0) (length 6.35) hide
          (name "GND" (effects (font (size 1.27 1.27))))
          (number "2_127" (effects (font (size 1.27 1.27))))
        )
        (pin passive line (at 0 -127 0) (length 6.35) hide
          (name "VREG_S4A_1V8" (effects (font (size 1.27 1.27))))
          (number "2_128" (effects (font (size 1.27 1.27))))
        )
        (pin bidirectional line (at 49.53 -129.54 180) (length 6.35)
          (name "EDP_AUX_P" (effects (font (size 1.27 1.27))))
          (number "2_129" (effects (font (size 1.27 1.27))))
        )
        (pin output line (at 49.53 -15.24 180) (length 6.35)
          (name "DSI1_LN0_N" (effects (font (size 1.27 1.27))))
          (number "2_13" (effects (font (size 1.27 1.27))))
        )
        (pin input line (at 0 -129.54 0) (length 6.35)
          (name "USB_BOOT" (effects (font (size 1.27 1.27))))
          (number "2_130" (effects (font (size 1.27 1.27))))
        )
        (pin bidirectional line (at 49.53 -132.08 180) (length 6.35)
          (name "EDP_AUX_N" (effects (font (size 1.27 1.27))))
          (number "2_131" (effects (font (size 1.27 1.27))))
        )
        (pin bidirectional line (at 0 -132.08 0) (length 6.35)
          (name "GPIO_128" (effects (font (size 1.27 1.27))))
          (number "2_132" (effects (font (size 1.27 1.27))))
        )
        (pin bidirectional line (at 49.53 -134.62 180) (length 6.35)
          (name "VRTC" (effects (font (size 1.27 1.27))))
          (number "2_133" (effects (font (size 1.27 1.27))))
        )
        (pin bidirectional line (at 0 -134.62 0) (length 6.35)
          (name "GPIO_135" (effects (font (size 1.27 1.27))))
          (number "2_134" (effects (font (size 1.27 1.27))))
        )
        (pin input line (at 49.53 -137.16 180) (length 6.35)
          (name "DBG_RXD" (effects (font (size 1.27 1.27))))
          (number "2_135" (effects (font (size 1.27 1.27))))
        )
        (pin bidirectional line (at 0 -137.16 0) (length 6.35)
          (name "GPIO_129" (effects (font (size 1.27 1.27))))
          (number "2_136" (effects (font (size 1.27 1.27))))
        )
        (pin output line (at 49.53 -139.7 180) (length 6.35)
          (name "DBG_TXD" (effects (font (size 1.27 1.27))))
          (number "2_137" (effects (font (size 1.27 1.27))))
        )
        (pin no_connect line (at 6.35 -139.7 0) (length 6.35) hide
          (name "RESERVED1" (effects (font (size 1.27 1.27))))
          (number "2_138" (effects (font (size 1.27 1.27))))
        )
        (pin input line (at 49.53 -142.24 180) (length 6.35)
          (name "USB_CC2" (effects (font (size 1.27 1.27))))
          (number "2_139" (effects (font (size 1.27 1.27))))
        )
        (pin output line (at 0 -15.24 0) (length 6.35)
          (name "DSI0_LN3_N" (effects (font (size 1.27 1.27))))
          (number "2_14" (effects (font (size 1.27 1.27))))
        )
        (pin power_in line (at 0 -142.24 0) (length 6.35)
          (name "VREG_BOB2" (effects (font (size 1.27 1.27))))
          (number "2_140" (effects (font (size 1.27 1.27))))
        )
        (pin input line (at 49.53 -144.78 180) (length 6.35)
          (name "USB_CC1" (effects (font (size 1.27 1.27))))
          (number "2_141" (effects (font (size 1.27 1.27))))
        )
        (pin power_in line (at 0 -144.78 0) (length 6.35)
          (name "VREG_BOB1" (effects (font (size 1.27 1.27))))
          (number "2_142" (effects (font (size 1.27 1.27))))
        )
        (pin input line (at 49.53 -147.32 180) (length 6.35)
          (name "BAT_THERM" (effects (font (size 1.27 1.27))))
          (number "2_143" (effects (font (size 1.27 1.27))))
        )
        (pin output line (at 0 -147.32 0) (length 6.35)
          (name "PWM_PMI_GPIO8" (effects (font (size 1.27 1.27))))
          (number "2_144" (effects (font (size 1.27 1.27))))
        )
        (pin input line (at 49.53 -149.86 180) (length 6.35)
          (name "HOME_KEY" (effects (font (size 1.27 1.27))))
          (number "2_145" (effects (font (size 1.27 1.27))))
        )
        (pin output line (at 0 -149.86 0) (length 6.35)
          (name "PWM_PMI_GPIO5" (effects (font (size 1.27 1.27))))
          (number "2_146" (effects (font (size 1.27 1.27))))
        )
        (pin bidirectional line (at 49.53 -152.4 180) (length 6.35)
          (name "PMU_GPIO10" (effects (font (size 1.27 1.27))))
          (number "2_147" (effects (font (size 1.27 1.27))))
        )
        (pin power_in line (at 0 -152.4 0) (length 6.35)
          (name "LVS2A_1V8" (effects (font (size 1.27 1.27))))
          (number "2_148" (effects (font (size 1.27 1.27))))
        )
        (pin bidirectional line (at 49.53 -154.94 180) (length 6.35)
          (name "PMU_GPIO13" (effects (font (size 1.27 1.27))))
          (number "2_149" (effects (font (size 1.27 1.27))))
        )
        (pin output line (at 49.53 -12.7 180) (length 6.35)
          (name "DSI1_LN0_P" (effects (font (size 1.27 1.27))))
          (number "2_15" (effects (font (size 1.27 1.27))))
        )
        (pin power_in line (at 0 -154.94 0) (length 6.35)
          (name "LDO19A_3V0" (effects (font (size 1.27 1.27))))
          (number "2_150" (effects (font (size 1.27 1.27))))
        )
        (pin output line (at 49.53 -157.48 180) (length 6.35)
          (name "ADC_PMU_GPIO21" (effects (font (size 1.27 1.27))))
          (number "2_151" (effects (font (size 1.27 1.27))))
        )
        (pin output line (at 0 -157.48 0) (length 6.35)
          (name "R_LED" (effects (font (size 1.27 1.27))))
          (number "2_152" (effects (font (size 1.27 1.27))))
        )
        (pin output line (at 49.53 -160.02 180) (length 6.35)
          (name "ADC_PMU_GPIO8" (effects (font (size 1.27 1.27))))
          (number "2_153" (effects (font (size 1.27 1.27))))
        )
        (pin output line (at 0 -160.02 0) (length 6.35)
          (name "B_LED" (effects (font (size 1.27 1.27))))
          (number "2_154" (effects (font (size 1.27 1.27))))
        )
        (pin passive line (at 0 -172.72 0) (length 6.35) hide
          (name "GND" (effects (font (size 1.27 1.27))))
          (number "2_155" (effects (font (size 1.27 1.27))))
        )
        (pin output line (at 0 -162.56 0) (length 6.35)
          (name "G_LED" (effects (font (size 1.27 1.27))))
          (number "2_156" (effects (font (size 1.27 1.27))))
        )
        (pin input line (at 49.53 -162.56 180) (length 6.35)
          (name "CS_P" (effects (font (size 1.27 1.27))))
          (number "2_157" (effects (font (size 1.27 1.27))))
        )
        (pin passive line (at 0 -172.72 0) (length 6.35) hide
          (name "GND" (effects (font (size 1.27 1.27))))
          (number "2_158" (effects (font (size 1.27 1.27))))
        )
        (pin input line (at 49.53 -165.1 180) (length 6.35)
          (name "CS_M" (effects (font (size 1.27 1.27))))
          (number "2_159" (effects (font (size 1.27 1.27))))
        )
        (pin output line (at 0 -12.7 0) (length 6.35)
          (name "DSI0_LN3_P" (effects (font (size 1.27 1.27))))
          (number "2_16" (effects (font (size 1.27 1.27))))
        )
        (pin power_in line (at 0 -165.1 0) (length 6.35)
          (name "USB_VBUS" (effects (font (size 1.27 1.27))))
          (number "2_160" (effects (font (size 1.27 1.27))))
        )
        (pin passive line (at 0 -172.72 0) (length 6.35) hide
          (name "GND" (effects (font (size 1.27 1.27))))
          (number "2_161" (effects (font (size 1.27 1.27))))
        )
        (pin passive line (at 0 -165.1 0) (length 6.35) hide
          (name "USB_VBUS" (effects (font (size 1.27 1.27))))
          (number "2_162" (effects (font (size 1.27 1.27))))
        )
        (pin input line (at 49.53 -167.64 180) (length 6.35)
          (name "BAT_P" (effects (font (size 1.27 1.27))))
          (number "2_163" (effects (font (size 1.27 1.27))))
        )
        (pin passive line (at 0 -165.1 0) (length 6.35) hide
          (name "USB_VBUS" (effects (font (size 1.27 1.27))))
          (number "2_164" (effects (font (size 1.27 1.27))))
        )
        (pin input line (at 49.53 -170.18 180) (length 6.35)
          (name "BAT_M" (effects (font (size 1.27 1.27))))
          (number "2_165" (effects (font (size 1.27 1.27))))
        )
        (pin passive line (at 0 -165.1 0) (length 6.35) hide
          (name "USB_VBUS" (effects (font (size 1.27 1.27))))
          (number "2_166" (effects (font (size 1.27 1.27))))
        )
        (pin passive line (at 0 -172.72 0) (length 6.35) hide
          (name "GND" (effects (font (size 1.27 1.27))))
          (number "2_167" (effects (font (size 1.27 1.27))))
        )
        (pin passive line (at 0 -165.1 0) (length 6.35) hide
          (name "USB_VBUS" (effects (font (size 1.27 1.27))))
          (number "2_168" (effects (font (size 1.27 1.27))))
        )
        (pin passive line (at 0 -172.72 0) (length 6.35) hide
          (name "GND" (effects (font (size 1.27 1.27))))
          (number "2_17" (effects (font (size 1.27 1.27))))
        )
        (pin no_connect line (at 6.35 -167.64 0) (length 6.35) hide
          (name "NC" (effects (font (size 1.27 1.27))))
          (number "2_171" (effects (font (size 1.27 1.27))))
        )
        (pin no_connect line (at 6.35 -170.18 0) (length 6.35) hide
          (name "NC" (effects (font (size 1.27 1.27))))
          (number "2_172" (effects (font (size 1.27 1.27))))
        )
        (pin passive line (at 0 -172.72 0) (length 6.35) hide
          (name "GND" (effects (font (size 1.27 1.27))))
          (number "2_18" (effects (font (size 1.27 1.27))))
        )
        (pin output line (at 49.53 -17.78 180) (length 6.35)
          (name "DSI1_CLK_P" (effects (font (size 1.27 1.27))))
          (number "2_19" (effects (font (size 1.27 1.27))))
        )
        (pin bidirectional line (at 0 0 0) (length 6.35)
          (name "GPIO_25" (effects (font (size 1.27 1.27))))
          (number "2_2" (effects (font (size 1.27 1.27))))
        )
        (pin output line (at 0 -20.32 0) (length 6.35)
          (name "DSI0_LN2_N" (effects (font (size 1.27 1.27))))
          (number "2_20" (effects (font (size 1.27 1.27))))
        )
        (pin output line (at 49.53 -20.32 180) (length 6.35)
          (name "DSI1_CLK_N" (effects (font (size 1.27 1.27))))
          (number "2_21" (effects (font (size 1.27 1.27))))
        )
        (pin output line (at 0 -17.78 0) (length 6.35)
          (name "DSI0_LN2_P" (effects (font (size 1.27 1.27))))
          (number "2_22" (effects (font (size 1.27 1.27))))
        )
        (pin passive line (at 0 -172.72 0) (length 6.35) hide
          (name "GND" (effects (font (size 1.27 1.27))))
          (number "2_23" (effects (font (size 1.27 1.27))))
        )
        (pin passive line (at 0 -172.72 0) (length 6.35) hide
          (name "GND" (effects (font (size 1.27 1.27))))
          (number "2_24" (effects (font (size 1.27 1.27))))
        )
        (pin output line (at 49.53 -22.86 180) (length 6.35)
          (name "DSI1_LN2_P" (effects (font (size 1.27 1.27))))
          (number "2_25" (effects (font (size 1.27 1.27))))
        )
        (pin output line (at 0 -25.4 0) (length 6.35)
          (name "DSI0_CLK_N" (effects (font (size 1.27 1.27))))
          (number "2_26" (effects (font (size 1.27 1.27))))
        )
        (pin output line (at 49.53 -25.4 180) (length 6.35)
          (name "DSI1_LN2_N" (effects (font (size 1.27 1.27))))
          (number "2_27" (effects (font (size 1.27 1.27))))
        )
        (pin output line (at 0 -22.86 0) (length 6.35)
          (name "DSI0_CLK_P" (effects (font (size 1.27 1.27))))
          (number "2_28" (effects (font (size 1.27 1.27))))
        )
        (pin passive line (at 0 -172.72 0) (length 6.35) hide
          (name "GND" (effects (font (size 1.27 1.27))))
          (number "2_29" (effects (font (size 1.27 1.27))))
        )
        (pin output line (at 49.53 -2.54 180) (length 6.35)
          (name "SBU_SW_SEL" (effects (font (size 1.27 1.27))))
          (number "2_3" (effects (font (size 1.27 1.27))))
        )
        (pin passive line (at 0 -172.72 0) (length 6.35) hide
          (name "GND" (effects (font (size 1.27 1.27))))
          (number "2_30" (effects (font (size 1.27 1.27))))
        )
        (pin output line (at 49.53 -30.48 180) (length 6.35)
          (name "DSI1_LN3_N" (effects (font (size 1.27 1.27))))
          (number "2_31" (effects (font (size 1.27 1.27))))
        )
        (pin output line (at 0 -30.48 0) (length 6.35)
          (name "DSI0_LN1_N" (effects (font (size 1.27 1.27))))
          (number "2_32" (effects (font (size 1.27 1.27))))
        )
        (pin output line (at 49.53 -27.94 180) (length 6.35)
          (name "DSI1_LN3_P" (effects (font (size 1.27 1.27))))
          (number "2_33" (effects (font (size 1.27 1.27))))
        )
        (pin output line (at 0 -27.94 0) (length 6.35)
          (name "DSI0_LN1_P" (effects (font (size 1.27 1.27))))
          (number "2_34" (effects (font (size 1.27 1.27))))
        )
        (pin passive line (at 0 -172.72 0) (length 6.35) hide
          (name "GND" (effects (font (size 1.27 1.27))))
          (number "2_35" (effects (font (size 1.27 1.27))))
        )
        (pin passive line (at 0 -172.72 0) (length 6.35) hide
          (name "GND" (effects (font (size 1.27 1.27))))
          (number "2_36" (effects (font (size 1.27 1.27))))
        )
        (pin output line (at 49.53 -35.56 180) (length 6.35)
          (name "DSI1_LN1_N" (effects (font (size 1.27 1.27))))
          (number "2_37" (effects (font (size 1.27 1.27))))
        )
        (pin output line (at 0 -35.56 0) (length 6.35)
          (name "DSI0_LN0_N" (effects (font (size 1.27 1.27))))
          (number "2_38" (effects (font (size 1.27 1.27))))
        )
        (pin output line (at 49.53 -33.02 180) (length 6.35)
          (name "DSI1_LN1_P" (effects (font (size 1.27 1.27))))
          (number "2_39" (effects (font (size 1.27 1.27))))
        )
        (pin bidirectional line (at 0 -2.54 0) (length 6.35)
          (name "I2C4_SDA" (effects (font (size 1.27 1.27))))
          (number "2_4" (effects (font (size 1.27 1.27))))
        )
        (pin output line (at 0 -33.02 0) (length 6.35)
          (name "DSI0_LN0_P" (effects (font (size 1.27 1.27))))
          (number "2_40" (effects (font (size 1.27 1.27))))
        )
        (pin passive line (at 0 -172.72 0) (length 6.35) hide
          (name "GND" (effects (font (size 1.27 1.27))))
          (number "2_41" (effects (font (size 1.27 1.27))))
        )
        (pin passive line (at 0 -172.72 0) (length 6.35) hide
          (name "GND" (effects (font (size 1.27 1.27))))
          (number "2_42" (effects (font (size 1.27 1.27))))
        )
        (pin output line (at 49.53 -38.1 180) (length 6.35)
          (name "WCD_CLK" (effects (font (size 1.27 1.27))))
          (number "2_43" (effects (font (size 1.27 1.27))))
        )
        (pin output line (at 0 -38.1 0) (length 6.35)
          (name "TP_I2C_SCL" (effects (font (size 1.27 1.27))))
          (number "2_44" (effects (font (size 1.27 1.27))))
        )
        (pin passive line (at 0 -172.72 0) (length 6.35) hide
          (name "GND" (effects (font (size 1.27 1.27))))
          (number "2_45" (effects (font (size 1.27 1.27))))
        )
        (pin bidirectional line (at 0 -40.64 0) (length 6.35)
          (name "TP_I2C_SDA" (effects (font (size 1.27 1.27))))
          (number "2_46" (effects (font (size 1.27 1.27))))
        )
        (pin bidirectional line (at 49.53 -40.64 180) (length 6.35)
          (name "SLIMBUS_DATA0" (effects (font (size 1.27 1.27))))
          (number "2_47" (effects (font (size 1.27 1.27))))
        )
        (pin input line (at 0 -43.18 0) (length 6.35)
          (name "TP_INT" (effects (font (size 1.27 1.27))))
          (number "2_48" (effects (font (size 1.27 1.27))))
        )
        (pin bidirectional line (at 49.53 -43.18 180) (length 6.35)
          (name "SLIMBUS_DATA1" (effects (font (size 1.27 1.27))))
          (number "2_49" (effects (font (size 1.27 1.27))))
        )
        (pin input line (at 49.53 -5.08 180) (length 6.35)
          (name "PWRKEY" (effects (font (size 1.27 1.27))))
          (number "2_5" (effects (font (size 1.27 1.27))))
        )
        (pin output line (at 0 -45.72 0) (length 6.35)
          (name "TP_RST" (effects (font (size 1.27 1.27))))
          (number "2_50" (effects (font (size 1.27 1.27))))
        )
        (pin output line (at 49.53 -45.72 180) (length 6.35)
          (name "SLIMBUS_CLK" (effects (font (size 1.27 1.27))))
          (number "2_51" (effects (font (size 1.27 1.27))))
        )
        (pin output line (at 0 -48.26 0) (length 6.35)
          (name "SPI2_CLK" (effects (font (size 1.27 1.27))))
          (number "2_52" (effects (font (size 1.27 1.27))))
        )
        (pin passive line (at 0 -172.72 0) (length 6.35) hide
          (name "GND" (effects (font (size 1.27 1.27))))
          (number "2_53" (effects (font (size 1.27 1.27))))
        )
        (pin output line (at 0 -50.8 0) (length 6.35)
          (name "SPI2_CS" (effects (font (size 1.27 1.27))))
          (number "2_54" (effects (font (size 1.27 1.27))))
        )
        (pin output line (at 49.53 -48.26 180) (length 6.35)
          (name "I2S2_WS" (effects (font (size 1.27 1.27))))
          (number "2_55" (effects (font (size 1.27 1.27))))
        )
        (pin input line (at 0 -53.34 0) (length 6.35)
          (name "SPI2_MISO" (effects (font (size 1.27 1.27))))
          (number "2_56" (effects (font (size 1.27 1.27))))
        )
        (pin output line (at 49.53 -50.8 180) (length 6.35)
          (name "I2S2_SCK" (effects (font (size 1.27 1.27))))
          (number "2_57" (effects (font (size 1.27 1.27))))
        )
        (pin output line (at 0 -55.88 0) (length 6.35)
          (name "SPI2_MOSI" (effects (font (size 1.27 1.27))))
          (number "2_58" (effects (font (size 1.27 1.27))))
        )
        (pin bidirectional line (at 49.53 -53.34 180) (length 6.35)
          (name "I2S2_DATA0" (effects (font (size 1.27 1.27))))
          (number "2_59" (effects (font (size 1.27 1.27))))
        )
        (pin output line (at 0 -5.08 0) (length 6.35)
          (name "I2C4_SCL" (effects (font (size 1.27 1.27))))
          (number "2_6" (effects (font (size 1.27 1.27))))
        )
        (pin input line (at 0 -58.42 0) (length 6.35)
          (name "LCD_TE" (effects (font (size 1.27 1.27))))
          (number "2_60" (effects (font (size 1.27 1.27))))
        )
        (pin bidirectional line (at 49.53 -55.88 180) (length 6.35)
          (name "I2S2_DATA1" (effects (font (size 1.27 1.27))))
          (number "2_61" (effects (font (size 1.27 1.27))))
        )
        (pin output line (at 0 -60.96 0) (length 6.35)
          (name "LCD_RST" (effects (font (size 1.27 1.27))))
          (number "2_62" (effects (font (size 1.27 1.27))))
        )
        (pin output line (at 49.53 -58.42 180) (length 6.35)
          (name "I2S3_WS" (effects (font (size 1.27 1.27))))
          (number "2_63" (effects (font (size 1.27 1.27))))
        )
        (pin bidirectional line (at 0 -63.5 0) (length 6.35)
          (name "GPIO_42" (effects (font (size 1.27 1.27))))
          (number "2_64" (effects (font (size 1.27 1.27))))
        )
        (pin bidirectional line (at 49.53 -60.96 180) (length 6.35)
          (name "I2S3_DATA1" (effects (font (size 1.27 1.27))))
          (number "2_65" (effects (font (size 1.27 1.27))))
        )
        (pin bidirectional line (at 0 -66.04 0) (length 6.35)
          (name "GPIO_44" (effects (font (size 1.27 1.27))))
          (number "2_66" (effects (font (size 1.27 1.27))))
        )
        (pin bidirectional line (at 49.53 -63.5 180) (length 6.35)
          (name "I2S3_DATA2" (effects (font (size 1.27 1.27))))
          (number "2_67" (effects (font (size 1.27 1.27))))
        )
        (pin bidirectional line (at 0 -68.58 0) (length 6.35)
          (name "GPIO_52" (effects (font (size 1.27 1.27))))
          (number "2_68" (effects (font (size 1.27 1.27))))
        )
        (pin bidirectional line (at 49.53 -66.04 180) (length 6.35)
          (name "I2S3_DATA0" (effects (font (size 1.27 1.27))))
          (number "2_69" (effects (font (size 1.27 1.27))))
        )
        (pin input line (at 49.53 -7.62 180) (length 6.35)
          (name "VOL_DOWN" (effects (font (size 1.27 1.27))))
          (number "2_7" (effects (font (size 1.27 1.27))))
        )
        (pin bidirectional line (at 0 -71.12 0) (length 6.35)
          (name "GPIO_50" (effects (font (size 1.27 1.27))))
          (number "2_70" (effects (font (size 1.27 1.27))))
        )
        (pin bidirectional line (at 49.53 -68.58 180) (length 6.35)
          (name "I2S3_DATA3" (effects (font (size 1.27 1.27))))
          (number "2_71" (effects (font (size 1.27 1.27))))
        )
        (pin bidirectional line (at 0 -73.66 0) (length 6.35)
          (name "GPIO_134" (effects (font (size 1.27 1.27))))
          (number "2_72" (effects (font (size 1.27 1.27))))
        )
        (pin output line (at 49.53 -71.12 180) (length 6.35)
          (name "I2S3_SCK" (effects (font (size 1.27 1.27))))
          (number "2_73" (effects (font (size 1.27 1.27))))
        )
        (pin bidirectional line (at 0 -76.2 0) (length 6.35)
          (name "GPIO_122" (effects (font (size 1.27 1.27))))
          (number "2_74" (effects (font (size 1.27 1.27))))
        )
        (pin output line (at 49.53 -73.66 180) (length 6.35)
          (name "I2C10_SCL" (effects (font (size 1.27 1.27))))
          (number "2_75" (effects (font (size 1.27 1.27))))
        )
        (pin bidirectional line (at 0 -78.74 0) (length 6.35)
          (name "GPIO_124" (effects (font (size 1.27 1.27))))
          (number "2_76" (effects (font (size 1.27 1.27))))
        )
        (pin bidirectional line (at 49.53 -76.2 180) (length 6.35)
          (name "I2C10_SDA" (effects (font (size 1.27 1.27))))
          (number "2_77" (effects (font (size 1.27 1.27))))
        )
        (pin bidirectional line (at 0 -81.28 0) (length 6.35)
          (name "GPIO_49" (effects (font (size 1.27 1.27))))
          (number "2_78" (effects (font (size 1.27 1.27))))
        )
        (pin output line (at 49.53 -78.74 180) (length 6.35)
          (name "I2S1_WS" (effects (font (size 1.27 1.27))))
          (number "2_79" (effects (font (size 1.27 1.27))))
        )
        (pin bidirectional line (at 0 -7.62 0) (length 6.35)
          (name "SSC_I2C1_SDA" (effects (font (size 1.27 1.27))))
          (number "2_8" (effects (font (size 1.27 1.27))))
        )
        (pin output line (at 0 -83.82 0) (length 6.35)
          (name "SPI0_CS" (effects (font (size 1.27 1.27))))
          (number "2_80" (effects (font (size 1.27 1.27))))
        )
        (pin output line (at 49.53 -81.28 180) (length 6.35)
          (name "I2S1_MCLK" (effects (font (size 1.27 1.27))))
          (number "2_81" (effects (font (size 1.27 1.27))))
        )
        (pin output line (at 0 -86.36 0) (length 6.35)
          (name "SPI0_MOSI" (effects (font (size 1.27 1.27))))
          (number "2_82" (effects (font (size 1.27 1.27))))
        )
        (pin output line (at 49.53 -83.82 180) (length 6.35)
          (name "I2S1_SCK" (effects (font (size 1.27 1.27))))
          (number "2_83" (effects (font (size 1.27 1.27))))
        )
        (pin input line (at 0 -88.9 0) (length 6.35)
          (name "SPI0_MISO" (effects (font (size 1.27 1.27))))
          (number "2_84" (effects (font (size 1.27 1.27))))
        )
        (pin bidirectional line (at 49.53 -86.36 180) (length 6.35)
          (name "I2S1_DATA1" (effects (font (size 1.27 1.27))))
          (number "2_85" (effects (font (size 1.27 1.27))))
        )
        (pin output line (at 0 -91.44 0) (length 6.35)
          (name "SPI0_CLK" (effects (font (size 1.27 1.27))))
          (number "2_86" (effects (font (size 1.27 1.27))))
        )
        (pin bidirectional line (at 49.53 -88.9 180) (length 6.35)
          (name "I2S1_DATA0" (effects (font (size 1.27 1.27))))
          (number "2_87" (effects (font (size 1.27 1.27))))
        )
        (pin no_connect line (at 6.35 -93.98 0) (length 6.35) hide
          (name "RESERVED2" (effects (font (size 1.27 1.27))))
          (number "2_88" (effects (font (size 1.27 1.27))))
        )
        (pin input line (at 49.53 -91.44 180) (length 6.35)
          (name "CODEC_SPI_MISO" (effects (font (size 1.27 1.27))))
          (number "2_89" (effects (font (size 1.27 1.27))))
        )
        (pin input line (at 49.53 -10.16 180) (length 6.35)
          (name "VOL_UP_" (effects (font (size 1.27 1.27))))
          (number "2_9" (effects (font (size 1.27 1.27))))
        )
        (pin output line (at 0 -96.52 0) (length 6.35)
          (name "CODEC_RST" (effects (font (size 1.27 1.27))))
          (number "2_90" (effects (font (size 1.27 1.27))))
        )
        (pin input line (at 49.53 -93.98 180) (length 6.35)
          (name "CODEC_INT1" (effects (font (size 1.27 1.27))))
          (number "2_91" (effects (font (size 1.27 1.27))))
        )
        (pin output line (at 0 -99.06 0) (length 6.35)
          (name "CODEC_SPI_CLK" (effects (font (size 1.27 1.27))))
          (number "2_92" (effects (font (size 1.27 1.27))))
        )
        (pin input line (at 49.53 -96.52 180) (length 6.35)
          (name "CODEC_INT2" (effects (font (size 1.27 1.27))))
          (number "2_93" (effects (font (size 1.27 1.27))))
        )
        (pin output line (at 0 -101.6 0) (length 6.35)
          (name "CODEC_SPI_MOSI" (effects (font (size 1.27 1.27))))
          (number "2_94" (effects (font (size 1.27 1.27))))
        )
        (pin output line (at 49.53 -99.06 180) (length 6.35)
          (name "SPI11_MOSI" (effects (font (size 1.27 1.27))))
          (number "2_95" (effects (font (size 1.27 1.27))))
        )
        (pin output line (at 0 -104.14 0) (length 6.35)
          (name "CODEC_SPI_CS" (effects (font (size 1.27 1.27))))
          (number "2_96" (effects (font (size 1.27 1.27))))
        )
        (pin input line (at 49.53 -101.6 180) (length 6.35)
          (name "SPI11_MISO" (effects (font (size 1.27 1.27))))
          (number "2_97" (effects (font (size 1.27 1.27))))
        )
        (pin passive line (at 0 -172.72 0) (length 6.35) hide
          (name "GND" (effects (font (size 1.27 1.27))))
          (number "2_98" (effects (font (size 1.27 1.27))))
        )
        (pin output line (at 49.53 -104.14 180) (length 6.35)
          (name "SPI11_CLK" (effects (font (size 1.27 1.27))))
          (number "2_99" (effects (font (size 1.27 1.27))))
        )
      )
      (symbol "Receptacle_SA800U-WF_3_1"
        (rectangle (start 6.35 0) (end 39.37 -30.48)
          (stroke (width 0.254) (type default) (color 0 0 0 0))
          (fill (type background))
        )
        (pin power_in line (at 45.72 -27.94 180) (length 6.35)
          (name "GND" (effects (font (size 1.27 1.27))))
          (number "3_1" (effects (font (size 1.27 1.27))))
        )
        (pin input line (at 45.72 -12.7 180) (length 6.35)
          (name "SMB_STAT" (effects (font (size 1.27 1.27))))
          (number "3_10" (effects (font (size 1.27 1.27))))
        )
        (pin power_out line (at 45.72 -10.16 180) (length 6.35)
          (name "BAT_RBIAS" (effects (font (size 1.27 1.27))))
          (number "3_11" (effects (font (size 1.27 1.27))))
        )
        (pin power_out line (at 45.72 -7.62 180) (length 6.35)
          (name "LDO12A_1V8" (effects (font (size 1.27 1.27))))
          (number "3_12" (effects (font (size 1.27 1.27))))
        )
        (pin passive line (at 45.72 -27.94 180) (length 6.35) hide
          (name "GND" (effects (font (size 1.27 1.27))))
          (number "3_13" (effects (font (size 1.27 1.27))))
        )
        (pin input line (at 45.72 -5.08 180) (length 6.35)
          (name "SMB_CS_M" (effects (font (size 1.27 1.27))))
          (number "3_14" (effects (font (size 1.27 1.27))))
        )
        (pin input line (at 45.72 -2.54 180) (length 6.35)
          (name "SMB_CS_P" (effects (font (size 1.27 1.27))))
          (number "3_15" (effects (font (size 1.27 1.27))))
        )
        (pin input line (at 0 -2.54 0) (length 6.35)
          (name "BAT_ID" (effects (font (size 1.27 1.27))))
          (number "3_16" (effects (font (size 1.27 1.27))))
        )
        (pin input line (at 0 -5.08 0) (length 6.35)
          (name "SMB_THERM" (effects (font (size 1.27 1.27))))
          (number "3_17" (effects (font (size 1.27 1.27))))
        )
        (pin input line (at 0 -7.62 0) (length 6.35)
          (name "HAP_PWM_IN" (effects (font (size 1.27 1.27))))
          (number "3_18" (effects (font (size 1.27 1.27))))
        )
        (pin output line (at 0 -12.7 0) (length 6.35)
          (name "HAP_M" (effects (font (size 1.27 1.27))))
          (number "3_19" (effects (font (size 1.27 1.27))))
        )
        (pin power_out line (at 45.72 -17.78 180) (length 6.35)
          (name "SMB_USB_IN" (effects (font (size 1.27 1.27))))
          (number "3_2" (effects (font (size 1.27 1.27))))
        )
        (pin output line (at 0 -10.16 0) (length 6.35)
          (name "HAP_P" (effects (font (size 1.27 1.27))))
          (number "3_20" (effects (font (size 1.27 1.27))))
        )
        (pin passive line (at 45.72 -27.94 180) (length 6.35) hide
          (name "GND" (effects (font (size 1.27 1.27))))
          (number "3_21" (effects (font (size 1.27 1.27))))
        )
        (pin no_connect line (at 6.35 -15.24 0) (length 6.35) hide
          (name "RESERVED" (effects (font (size 1.27 1.27))))
          (number "3_22" (effects (font (size 1.27 1.27))))
        )
        (pin no_connect line (at 6.35 -17.78 0) (length 6.35) hide
          (name "RESERVED1" (effects (font (size 1.27 1.27))))
          (number "3_23" (effects (font (size 1.27 1.27))))
        )
        (pin no_connect line (at 6.35 -20.32 0) (length 6.35) hide
          (name "RESERVED2" (effects (font (size 1.27 1.27))))
          (number "3_24" (effects (font (size 1.27 1.27))))
        )
        (pin no_connect line (at 6.35 -22.86 0) (length 6.35) hide
          (name "RESERVED3" (effects (font (size 1.27 1.27))))
          (number "3_25" (effects (font (size 1.27 1.27))))
        )
        (pin no_connect line (at 39.37 -20.32 180) (length 6.35) hide
          (name "RESERVED4" (effects (font (size 1.27 1.27))))
          (number "3_26" (effects (font (size 1.27 1.27))))
        )
        (pin no_connect line (at 39.37 -22.86 180) (length 6.35) hide
          (name "RESERVED5" (effects (font (size 1.27 1.27))))
          (number "3_27" (effects (font (size 1.27 1.27))))
        )
        (pin passive line (at 45.72 -27.94 180) (length 6.35) hide
          (name "GND" (effects (font (size 1.27 1.27))))
          (number "3_28" (effects (font (size 1.27 1.27))))
        )
        (pin power_in line (at 0 -25.4 0) (length 6.35)
          (name "VCONN" (effects (font (size 1.27 1.27))))
          (number "3_29" (effects (font (size 1.27 1.27))))
        )
        (pin passive line (at 45.72 -17.78 180) (length 6.35) hide
          (name "SMB_USB_IN" (effects (font (size 1.27 1.27))))
          (number "3_3" (effects (font (size 1.27 1.27))))
        )
        (pin output line (at 0 -27.94 0) (length 6.35)
          (name "VCONN_EN" (effects (font (size 1.27 1.27))))
          (number "3_30" (effects (font (size 1.27 1.27))))
        )
        (pin passive line (at 45.72 -27.94 180) (length 6.35) hide
          (name "GND" (effects (font (size 1.27 1.27))))
          (number "3_31" (effects (font (size 1.27 1.27))))
        )
        (pin passive line (at 45.72 -27.94 180) (length 6.35) hide
          (name "GND" (effects (font (size 1.27 1.27))))
          (number "3_32" (effects (font (size 1.27 1.27))))
        )
        (pin passive line (at 45.72 -27.94 180) (length 6.35) hide
          (name "GND" (effects (font (size 1.27 1.27))))
          (number "3_33" (effects (font (size 1.27 1.27))))
        )
        (pin passive line (at 45.72 -27.94 180) (length 6.35) hide
          (name "GND" (effects (font (size 1.27 1.27))))
          (number "3_34" (effects (font (size 1.27 1.27))))
        )
        (pin passive line (at 45.72 -17.78 180) (length 6.35) hide
          (name "SMB_USB_IN" (effects (font (size 1.27 1.27))))
          (number "3_4" (effects (font (size 1.27 1.27))))
        )
        (pin passive line (at 45.72 -17.78 180) (length 6.35) hide
          (name "SMB_USB_IN" (effects (font (size 1.27 1.27))))
          (number "3_5" (effects (font (size 1.27 1.27))))
        )
        (pin passive line (at 45.72 -17.78 180) (length 6.35) hide
          (name "SMB_USB_IN" (effects (font (size 1.27 1.27))))
          (number "3_6" (effects (font (size 1.27 1.27))))
        )
        (pin passive line (at 45.72 -17.78 180) (length 6.35) hide
          (name "SMB_USB_IN" (effects (font (size 1.27 1.27))))
          (number "3_7" (effects (font (size 1.27 1.27))))
        )
        (pin passive line (at 45.72 -27.94 180) (length 6.35) hide
          (name "GND" (effects (font (size 1.27 1.27))))
          (number "3_8" (effects (font (size 1.27 1.27))))
        )
        (pin output line (at 45.72 -15.24 180) (length 6.35)
          (name "SMB_EN_CHG" (effects (font (size 1.27 1.27))))
          (number "3_9" (effects (font (size 1.27 1.27))))
        )
      )
      (symbol "Receptacle_SA800U-WF_4_1"
        (rectangle (start 6.35 2.54) (end 39.37 -25.4)
          (stroke (width 0.254) (type default) (color 0 0 0 0))
          (fill (type background))
        )
        (pin no_connect line (at 39.37 -20.32 180) (length 6.35) hide
          (name "RESERVED" (effects (font (size 1.27 1.27))))
          (number "4_1" (effects (font (size 1.27 1.27))))
        )
        (pin power_out line (at 0 -17.78 0) (length 6.35)
          (name "LDO28A_3V0" (effects (font (size 1.27 1.27))))
          (number "4_10" (effects (font (size 1.27 1.27))))
        )
        (pin power_out line (at 0 -20.32 0) (length 6.35)
          (name "SD_LDO13A" (effects (font (size 1.27 1.27))))
          (number "4_11" (effects (font (size 1.27 1.27))))
        )
        (pin power_in line (at 45.72 -22.86 180) (length 6.35)
          (name "GND" (effects (font (size 1.27 1.27))))
          (number "4_12" (effects (font (size 1.27 1.27))))
        )
        (pin power_out line (at 0 -22.86 0) (length 6.35)
          (name "USB_VBUS" (effects (font (size 1.27 1.27))))
          (number "4_13" (effects (font (size 1.27 1.27))))
        )
        (pin passive line (at 0 -22.86 0) (length 6.35) hide
          (name "USB_VBUS" (effects (font (size 1.27 1.27))))
          (number "4_14" (effects (font (size 1.27 1.27))))
        )
        (pin passive line (at 0 -22.86 0) (length 6.35) hide
          (name "USB_VBUS" (effects (font (size 1.27 1.27))))
          (number "4_15" (effects (font (size 1.27 1.27))))
        )
        (pin passive line (at 0 -22.86 0) (length 6.35) hide
          (name "USB_VBUS" (effects (font (size 1.27 1.27))))
          (number "4_16" (effects (font (size 1.27 1.27))))
        )
        (pin passive line (at 0 -22.86 0) (length 6.35) hide
          (name "USB_VBUS" (effects (font (size 1.27 1.27))))
          (number "4_17" (effects (font (size 1.27 1.27))))
        )
        (pin passive line (at 0 -22.86 0) (length 6.35) hide
          (name "USB_VBUS" (effects (font (size 1.27 1.27))))
          (number "4_18" (effects (font (size 1.27 1.27))))
        )
        (pin passive line (at 45.72 -22.86 180) (length 6.35) hide
          (name "GND" (effects (font (size 1.27 1.27))))
          (number "4_19" (effects (font (size 1.27 1.27))))
        )
        (pin input line (at 0 0 0) (length 6.35)
          (name "LCD_BL_K2" (effects (font (size 1.27 1.27))))
          (number "4_2" (effects (font (size 1.27 1.27))))
        )
        (pin output line (at 45.72 -17.78 180) (length 6.35)
          (name "FLASH_LED2" (effects (font (size 1.27 1.27))))
          (number "4_20" (effects (font (size 1.27 1.27))))
        )
        (pin output line (at 45.72 -15.24 180) (length 6.35)
          (name "FLASH_LED2_1" (effects (font (size 1.27 1.27))))
          (number "4_21" (effects (font (size 1.27 1.27))))
        )
        (pin passive line (at 45.72 -22.86 180) (length 6.35) hide
          (name "GND" (effects (font (size 1.27 1.27))))
          (number "4_22" (effects (font (size 1.27 1.27))))
        )
        (pin output line (at 45.72 -12.7 180) (length 6.35)
          (name "FLASH_LED1" (effects (font (size 1.27 1.27))))
          (number "4_23" (effects (font (size 1.27 1.27))))
        )
        (pin output line (at 45.72 -10.16 180) (length 6.35)
          (name "FLASH_LED1_1" (effects (font (size 1.27 1.27))))
          (number "4_24" (effects (font (size 1.27 1.27))))
        )
        (pin passive line (at 45.72 -22.86 180) (length 6.35) hide
          (name "GND" (effects (font (size 1.27 1.27))))
          (number "4_25" (effects (font (size 1.27 1.27))))
        )
        (pin input line (at 45.72 -7.62 180) (length 6.35)
          (name "LCD_BL_K4" (effects (font (size 1.27 1.27))))
          (number "4_26" (effects (font (size 1.27 1.27))))
        )
        (pin input line (at 45.72 -5.08 180) (length 6.35)
          (name "LCD_BL_K3" (effects (font (size 1.27 1.27))))
          (number "4_27" (effects (font (size 1.27 1.27))))
        )
        (pin passive line (at 45.72 -22.86 180) (length 6.35) hide
          (name "GND" (effects (font (size 1.27 1.27))))
          (number "4_28" (effects (font (size 1.27 1.27))))
        )
        (pin power_out line (at 45.72 0 180) (length 6.35)
          (name "VDISP_P" (effects (font (size 1.27 1.27))))
          (number "4_29" (effects (font (size 1.27 1.27))))
        )
        (pin input line (at 0 -2.54 0) (length 6.35)
          (name "LCD_BL_K1" (effects (font (size 1.27 1.27))))
          (number "4_3" (effects (font (size 1.27 1.27))))
        )
        (pin power_out line (at 45.72 -2.54 180) (length 6.35)
          (name "VDISP_M" (effects (font (size 1.27 1.27))))
          (number "4_30" (effects (font (size 1.27 1.27))))
        )
        (pin passive line (at 45.72 -22.86 180) (length 6.35) hide
          (name "GND" (effects (font (size 1.27 1.27))))
          (number "4_31" (effects (font (size 1.27 1.27))))
        )
        (pin passive line (at 45.72 -22.86 180) (length 6.35) hide
          (name "GND" (effects (font (size 1.27 1.27))))
          (number "4_32" (effects (font (size 1.27 1.27))))
        )
        (pin passive line (at 45.72 -22.86 180) (length 6.35) hide
          (name "GND" (effects (font (size 1.27 1.27))))
          (number "4_33" (effects (font (size 1.27 1.27))))
        )
        (pin passive line (at 45.72 -22.86 180) (length 6.35) hide
          (name "GND" (effects (font (size 1.27 1.27))))
          (number "4_34" (effects (font (size 1.27 1.27))))
        )
        (pin power_out line (at 0 -5.08 0) (length 6.35)
          (name "LCD_BL_A" (effects (font (size 1.27 1.27))))
          (number "4_4" (effects (font (size 1.27 1.27))))
        )
        (pin output line (at 0 -7.62 0) (length 6.35)
          (name "FLASH_LED3" (effects (font (size 1.27 1.27))))
          (number "4_5" (effects (font (size 1.27 1.27))))
        )
        (pin output line (at 0 -10.16 0) (length 6.35)
          (name "FLASH_LED3_1" (effects (font (size 1.27 1.27))))
          (number "4_6" (effects (font (size 1.27 1.27))))
        )
        (pin passive line (at 45.72 -22.86 180) (length 6.35) hide
          (name "GND" (effects (font (size 1.27 1.27))))
          (number "4_7" (effects (font (size 1.27 1.27))))
        )
        (pin power_out line (at 0 -12.7 0) (length 6.35)
          (name "LDO24A_3V075" (effects (font (size 1.27 1.27))))
          (number "4_8" (effects (font (size 1.27 1.27))))
        )
        (pin power_out line (at 0 -15.24 0) (length 6.35)
          (name "LDO14A_1V88" (effects (font (size 1.27 1.27))))
          (number "4_9" (effects (font (size 1.27 1.27))))
        )
      )
    )
	(symbol "sa800u-baseboard-hw:SA800U-WF" (in_bom yes) (on_board yes)
      (property "Reference" "A" (id 0) (at 30.48 -2.54 0)
        (effects (font (size 1.27 1.27) (thickness 0.15)) (justify left bottom))
      )
      (property "Value" "SA800U-WF" (id 1) (at 30.48 -5.08 0)
        (effects (font (size 1.27 1.27) (thickness 0.15)) (justify left bottom) hide)
      )
      (property "Footprint" "sa800u-baseboard-hw-footprints:SA800U-WF" (id 2) (at 30.48 -7.62 0)
        (effects (font (size 1.27 1.27) (thickness 0.15)) (justify left bottom) hide)
      )
      (property "Datasheet" "https://www.quectel.com/wp-content/uploads/2023/03/Quectel_Product_Brochure_V7.4.pdf" (id 3) (at 30.48 -10.16 0)
        (effects (font (size 1.27 1.27) (thickness 0.15)) (justify left bottom) hide)
      )
      (property "MPN" "SA800U-WF" (id 4) (at 30.48 -16.51 0)
        (effects (font (size 1.27 1.27)) (justify left) hide)
      )
      (property "Manufacturer" "Quectel" (id 5) (at 30.48 -19.05 0)
        (effects (font (size 1.27 1.27)) (justify left) hide)
      )
      (property "Author" "Antmicro" (id 6) (at 30.48 -12.7 0)
        (effects (font (size 1.27 1.27) (thickness 0.15)) (justify left bottom) hide)
      )
      (property "License" "Apache-2.0" (id 7) (at 30.48 -15.24 0)
        (effects (font (size 1.27 1.27) (thickness 0.15)) (justify left bottom) hide)
      )
      (property "ki_keywords" "MODULE" (id 8) (at 0 0 0)
        (effects (font (size 1.27 1.27)) hide)
      )
      (property "ki_description" "Qualcomm® KryoTM 385 64-bit CPU + AdrenoTM 630 GPU" (id 9) (at 0 0 0)
        (effects (font (size 1.27 1.27)) hide)
      )
      (symbol "SA800U-WF_1_1"
        (rectangle (start 0 0) (end 17.78 -10.16)
          (stroke (width 0.254) (type default) (color 0 0 0 0))
          (fill (type background))
        )
      )
    )
	(symbol "sa800u-baseboard-hw:SMAJ58A-13-F" (pin_names hide) (in_bom yes) (on_board yes)
      (property "Reference" "D" (id 0) (at 21.59 -5.08 0)
        (effects (font (size 1.27 1.27) (thickness 0.15)) (justify left bottom))
      )
      (property "Value" "SMAJ58A-13-F" (id 1) (at 21.59 -7.62 0)
        (effects (font (size 1.27 1.27) (thickness 0.15)) (justify left bottom))
      )
      (property "Footprint" "sa800u-baseboard-hw-footprints:DO-214AC" (id 2) (at 21.59 -10.16 0)
        (effects (font (size 1.27 1.27) (thickness 0.15)) (justify left bottom) hide)
      )
      (property "Datasheet" "https://4donline.ihs.com/images/VipMasterIC/IC/DIOD/DIOD-S-A0001754755/DIOD-S-A0001754755-1.pdf?hkey=52A5661711E402568146F3353EA87419" (id 3) (at 21.59 -12.7 0)
        (effects (font (size 1.27 1.27) (thickness 0.15)) (justify left bottom) hide)
      )
      (property "MPN" "SMAJ58A-13-F" (id 4) (at 21.59 -15.24 0)
        (effects (font (size 1.27 1.27) (thickness 0.15)) (justify left bottom) hide)
      )
      (property "Manufacturer" "Diodes Incorporated" (id 5) (at 21.59 -17.78 0)
        (effects (font (size 1.27 1.27) (thickness 0.15)) (justify left bottom) hide)
      )
      (property "Author" "Antmicro" (id 6) (at 21.59 -20.32 0)
        (effects (font (size 1.27 1.27) (thickness 0.15)) (justify left bottom) hide)
      )
      (property "License" "Apache-2.0" (id 7) (at 21.59 -22.86 0)
        (effects (font (size 1.27 1.27) (thickness 0.15)) (justify left bottom) hide)
      )
      (symbol "SMAJ58A-13-F_0_1"
        (polyline
          (pts
            (xy 6.35 0)
            (xy 5.08 0)
          )
          (stroke (width 0.254) (type default) (color 0 0 0 0))
          (fill (type none))
        )
      )
      (symbol "SMAJ58A-13-F_1_1"
        (polyline
          (pts
            (xy 5.08 1.27)
            (xy 5.08 -1.27)
          )
          (stroke (width 0.254) (type default) (color 0 0 0 0))
          (fill (type none))
        )
        (polyline
          (pts
            (xy 2.54 1.27)
            (xy 2.54 -1.27)
            (xy 5.08 0)
            (xy 2.54 1.27)
          )
          (stroke (width 0.254) (type default) (color 0 0 0 0))
          (fill (type outline))
        )
        (polyline
          (pts
            (xy 5.08 -1.27)
            (xy 5.08 -1.905)
            (xy 5.715 -1.905)
            (xy 5.715 -1.27)
          )
          (stroke (width 0.254) (type default) (color 0 0 0 0))
          (fill (type none))
        )
        (polyline
          (pts
            (xy 5.08 1.27)
            (xy 5.08 1.905)
            (xy 4.445 1.905)
            (xy 4.445 1.27)
          )
          (stroke (width 0.254) (type default) (color 0 0 0 0))
          (fill (type none))
        )
        (pin passive line (at 0 0 0) (length 2.54)
          (name "A" (effects (font (size 1.27 1.27))))
          (number "A" (effects (font (size 1.27 1.27))))
        )
        (pin passive line (at 8.89 0 180) (length 2.54)
          (name "K" (effects (font (size 1.27 1.27))))
          (number "K" (effects (font (size 1.27 1.27))))
        )
      )
    )
	(symbol "sa800u-baseboard-hw:SQS401EN-T1_BE3" (pin_names (offset 0) hide) (in_bom yes) (on_board yes)
      (property "Reference" "Q" (id 0) (at 15.24 -5.08 0)
        (effects (font (size 1.27 1.27) (thickness 0.15)) (justify left bottom))
      )
      (property "Value" "SQS401EN-T1_BE3" (id 1) (at 15.24 -10.16 0)
        (effects (font (size 1.27 1.27) (thickness 0.15)) (justify left bottom) hide)
      )
      (property "Footprint" "sa800u-baseboard-hw-footprints:Vishay_PowerPAK_1212-8_Single" (id 2) (at 15.24 -12.7 0)
        (effects (font (size 1.27 1.27) (thickness 0.15)) (justify left bottom) hide)
      )
      (property "Datasheet" "https://www.vishay.com/docs/65529/sqs401en.pdf" (id 3) (at 15.24 -15.24 0)
        (effects (font (size 1.27 1.27) (thickness 0.15)) (justify left bottom) hide)
      )
      (property "MPN" "SQS401EN-T1_BE3" (id 4) (at 15.24 -7.62 0)
        (effects (font (size 1.27 1.27) (thickness 0.15)) (justify left bottom))
      )
      (property "Manufacturer" "Vishay" (id 5) (at 15.24 -17.78 0)
        (effects (font (size 1.27 1.27) (thickness 0.15)) (justify left bottom) hide)
      )
      (property "Author" "Antmicro" (id 6) (at 15.24 -20.32 0)
        (effects (font (size 1.27 1.27) (thickness 0.15)) (justify left bottom) hide)
      )
      (property "License" "Apache-2.0" (id 7) (at 15.24 -22.86 0)
        (effects (font (size 1.27 1.27) (thickness 0.15)) (justify left bottom) hide)
      )
      (property "ki_description" "MOSFET P-CHANNEL 40V (D-S), 16 A, PowerPAK 1212-8 Single" (id 8) (at 0 0 0)
        (effects (font (size 1.27 1.27)) hide)
      )
      (symbol "SQS401EN-T1_BE3_1_1"
        (polyline
          (pts
            (xy 3.81 1.143)
            (xy 3.81 0.635)
          )
          (stroke (width 0.254) (type default) (color 0 0 0 0))
          (fill (type background))
        )
        (polyline
          (pts
            (xy 3.81 1.143)
            (xy 3.81 1.651)
          )
          (stroke (width 0.254) (type default) (color 0 0 0 0))
          (fill (type background))
        )
        (polyline
          (pts
            (xy 3.81 2.54)
            (xy 3.81 2.032)
          )
          (stroke (width 0.254) (type default) (color 0 0 0 0))
          (fill (type background))
        )
        (polyline
          (pts
            (xy 3.81 2.54)
            (xy 3.81 3.048)
          )
          (stroke (width 0.254) (type default) (color 0 0 0 0))
          (fill (type background))
        )
        (polyline
          (pts
            (xy 3.81 4.445)
            (xy 3.81 3.429)
          )
          (stroke (width 0.254) (type default) (color 0 0 0 0))
          (fill (type background))
        )
        (polyline
          (pts
            (xy 6.35 1.143)
            (xy 3.81 1.143)
          )
          (stroke (width 0.254) (type default) (color 0 0 0 0))
          (fill (type background))
        )
        (polyline
          (pts
            (xy 7.874 2.286)
            (xy 6.858 2.286)
          )
          (stroke (width 0.254) (type default) (color 0 0 0 0))
          (fill (type background))
        )
        (polyline
          (pts
            (xy 1.27 0)
            (xy 3.302 0)
            (xy 3.302 3.937)
          )
          (stroke (width 0.254) (type default) (color 0 0 0 0))
          (fill (type none))
        )
        (polyline
          (pts
            (xy 6.35 -1.27)
            (xy 6.35 2.54)
            (xy 3.81 2.54)
          )
          (stroke (width 0.254) (type default) (color 0 0 0 0))
          (fill (type none))
        )
        (polyline
          (pts
            (xy 6.35 6.35)
            (xy 6.35 3.937)
            (xy 3.81 3.937)
          )
          (stroke (width 0.254) (type default) (color 0 0 0 0))
          (fill (type none))
        )
        (polyline
          (pts
            (xy 6.096 2.54)
            (xy 5.334 2.032)
            (xy 5.334 3.048)
            (xy 6.096 2.54)
          )
          (stroke (width 0.254) (type default) (color 0 0 0 0))
          (fill (type outline))
        )
        (polyline
          (pts
            (xy 7.366 2.286)
            (xy 7.874 3.048)
            (xy 6.858 3.048)
            (xy 7.366 2.286)
          )
          (stroke (width 0.254) (type default) (color 0 0 0 0))
          (fill (type outline))
        )
        (polyline
          (pts
            (xy 6.223 0.635)
            (xy 7.366 0.635)
            (xy 7.366 3.937)
            (xy 7.366 4.445)
            (xy 6.223 4.445)
          )
          (stroke (width 0.254) (type default) (color 0 0 0 0))
          (fill (type none))
        )
        (circle (center 5.08 2.54) (radius 3.302)
          (stroke (width 0.254) (type default) (color 0 0 0 0))
          (fill (type background))
        )
        (circle (center 6.35 0.635) (radius 0.127)
          (stroke (width 0.254) (type default) (color 0 0 0 0))
          (fill (type background))
        )
        (circle (center 6.35 1.143) (radius 0.127)
          (stroke (width 0.254) (type default) (color 0 0 0 0))
          (fill (type background))
        )
        (circle (center 6.35 4.445) (radius 0.127)
          (stroke (width 0.254) (type default) (color 0 0 0 0))
          (fill (type background))
        )
        (pin bidirectional line (at 6.35 -2.54 90) (length 2.54)
          (name "S" (effects (font (size 1.27 1.27))))
          (number "1" (effects (font (size 1.27 1.27))))
        )
        (pin bidirectional line (at 6.35 -2.54 90) (length 2.54) hide
          (name "S" (effects (font (size 1.27 1.27))))
          (number "2" (effects (font (size 1.27 1.27))))
        )
        (pin bidirectional line (at 6.35 -2.54 90) (length 2.54) hide
          (name "S" (effects (font (size 1.27 1.27))))
          (number "3" (effects (font (size 1.27 1.27))))
        )
        (pin bidirectional line (at 0 0 0) (length 2.54)
          (name "G" (effects (font (size 1.27 1.27))))
          (number "4" (effects (font (size 1.27 1.27))))
        )
        (pin bidirectional line (at 6.35 7.62 270) (length 2.54)
          (name "D" (effects (font (size 1.27 1.27))))
          (number "5" (effects (font (size 1.27 1.27))))
        )
      )
    )
	(symbol "sa800u-baseboard-hw:STS321045B502" (pin_numbers hide) (pin_names hide) (in_bom yes) (on_board yes)
      (property "Reference" "D" (id 0) (at 25.4 -5.08 0)
        (effects (font (size 1.27 1.27) (thickness 0.15)) (justify left bottom))
      )
      (property "Value" "STS321045B502" (id 1) (at 25.4 -7.62 0)
        (effects (font (size 1.27 1.27) (thickness 0.15)) (justify left bottom) hide)
      )
      (property "Footprint" "sa800u-baseboard-hw-footprints:SOD-323" (id 2) (at 25.4 -10.16 0)
        (effects (font (size 1.27 1.27) (thickness 0.15)) (justify left bottom) hide)
      )
      (property "Datasheet" "https://www.eaton.com/content/dam/eaton/products/electronic-components/resources/data-sheet/eaton-sts321045b502-tvs-diode-esd-suppressor-data-sheet.pdf" (id 3) (at 25.4 -12.7 0)
        (effects (font (size 1.27 1.27) (thickness 0.15)) (justify left bottom) hide)
      )
      (property "MPN" "STS321045B502" (id 4) (at 25.4 -15.24 0)
        (effects (font (size 1.27 1.27) (thickness 0.15)) (justify left bottom) hide)
      )
      (property "Manufacturer" "Cooper Bussmann" (id 5) (at 25.4 -17.78 0)
        (effects (font (size 1.27 1.27) (thickness 0.15)) (justify left bottom) hide)
      )
      (property "Author" "Antmicro" (id 6) (at 25.4 -20.32 0)
        (effects (font (size 1.27 1.27) (thickness 0.15)) (justify left bottom) hide)
      )
      (property "License" "Apache-2.0" (id 7) (at 25.4 -22.86 0)
        (effects (font (size 1.27 1.27) (thickness 0.15)) (justify left bottom) hide)
      )
      (property "ki_description" "TVS, 2kW, working voltage 4.5V" (id 8) (at 0 0 0)
        (effects (font (size 1.27 1.27)) hide)
      )
      (symbol "STS321045B502_1_1"
        (polyline
          (pts
            (xy 5.08 -0.635)
            (xy 5.715 -1.27)
          )
          (stroke (width 0.254) (type default) (color 0 0 0 0))
          (fill (type none))
        )
        (polyline
          (pts
            (xy 5.08 0.635)
            (xy 4.445 1.27)
          )
          (stroke (width 0.254) (type default) (color 0 0 0 0))
          (fill (type none))
        )
        (polyline
          (pts
            (xy 5.08 0.635)
            (xy 5.08 -0.635)
          )
          (stroke (width 0.254) (type default) (color 0 0 0 0))
          (fill (type none))
        )
        (polyline
          (pts
            (xy 2.54 1.27)
            (xy 5.08 0)
            (xy 2.54 -1.27)
            (xy 2.54 1.27)
          )
          (stroke (width 0.254) (type default) (color 0 0 0 0))
          (fill (type outline))
        )
        (polyline
          (pts
            (xy 7.62 1.27)
            (xy 7.62 -1.27)
            (xy 5.08 0)
            (xy 7.62 1.27)
          )
          (stroke (width 0.254) (type default) (color 0 0 0 0))
          (fill (type outline))
        )
        (pin unspecified line (at 0 0 0) (length 2.54)
          (name "1" (effects (font (size 1.27 1.27))))
          (number "A" (effects (font (size 1.27 1.27))))
        )
        (pin unspecified line (at 10.16 0 180) (length 2.54)
          (name "2" (effects (font (size 1.27 1.27))))
          (number "K" (effects (font (size 1.27 1.27))))
        )
      )
    )
	(symbol "sa800u-baseboard-hw:STUSB4500_QFN" (in_bom yes) (on_board yes)
      (property "Reference" "U" (id 0) (at 45.72 -5.08 0)
        (effects (font (size 1.27 1.27) (thickness 0.15)) (justify left bottom))
      )
      (property "Value" "STUSB4500_QFN" (id 1) (at 45.72 -10.16 0)
        (effects (font (size 1.27 1.27) (thickness 0.15)) (justify left bottom) hide)
      )
      (property "Footprint" "antmicro-footprints:QFN-24-1EP_4x4mm_EP2.1x2.1mm" (id 2) (at 45.72 -12.7 0)
        (effects (font (size 1.27 1.27) (thickness 0.15)) (justify left bottom) hide)
      )
      (property "Datasheet" "https://www.mouser.pl/datasheet/2/389/dm00489312-1799262.pdf" (id 3) (at 45.72 -15.24 0)
        (effects (font (size 1.27 1.27) (thickness 0.15)) (justify left bottom) hide)
      )
      (property "MPN" "STUSB4500QTR" (id 4) (at 45.72 -7.62 0)
        (effects (font (size 1.27 1.27) (thickness 0.15)) (justify left bottom))
      )
      (property "Manufacturer" "STMicroelectronics" (id 5) (at 45.72 -17.78 0)
        (effects (font (size 1.27 1.27) (thickness 0.15)) (justify left bottom) hide)
      )
      (property "Author" "Antmicro" (id 6) (at 45.72 -20.32 0)
        (effects (font (size 1.27 1.27) (thickness 0.15)) (justify left bottom) hide)
      )
      (property "License" "Apache-2.0" (id 7) (at 45.72 -22.86 0)
        (effects (font (size 1.27 1.27) (thickness 0.15)) (justify left bottom) hide)
      )
      (property "ki_description" "Standalone USB PD sink controller with short-to-VBUS protections" (id 8) (at 0 0 0)
        (effects (font (size 1.27 1.27)) hide)
      )
      (symbol "STUSB4500_QFN_1_1"
        (rectangle (start 2.54 5.08) (end 27.94 -36.83)
          (stroke (width 0.254) (type default) (color 0 0 0 0))
          (fill (type background))
        )
        (pin bidirectional line (at 0 -17.78 0) (length 2.54)
          (name "CC1DB" (effects (font (size 1.27 1.27))))
          (number "1" (effects (font (size 1.27 1.27))))
        )
        (pin power_in line (at 30.48 -31.75 180) (length 2.54)
          (name "GND" (effects (font (size 1.27 1.27))))
          (number "10" (effects (font (size 1.27 1.27))))
        )
        (pin output line (at 30.48 0 180) (length 2.54)
          (name "ATTACH" (effects (font (size 1.27 1.27))))
          (number "11" (effects (font (size 1.27 1.27))))
        )
        (pin input line (at 0 -30.48 0) (length 2.54)
          (name "ADDR0" (effects (font (size 1.27 1.27))))
          (number "12" (effects (font (size 1.27 1.27))))
        )
        (pin input line (at 0 -33.02 0) (length 2.54)
          (name "ADDR1" (effects (font (size 1.27 1.27))))
          (number "13" (effects (font (size 1.27 1.27))))
        )
        (pin output line (at 30.48 -12.7 180) (length 2.54)
          (name "POWER_OK3" (effects (font (size 1.27 1.27))))
          (number "14" (effects (font (size 1.27 1.27))))
        )
        (pin output line (at 30.48 -2.54 180) (length 2.54)
          (name "GPIO" (effects (font (size 1.27 1.27))))
          (number "15" (effects (font (size 1.27 1.27))))
        )
        (pin output line (at 0 0 0) (length 2.54)
          (name "VBUS_EN_SNK" (effects (font (size 1.27 1.27))))
          (number "16" (effects (font (size 1.27 1.27))))
        )
        (pin output line (at 30.48 -5.08 180) (length 2.54)
          (name "A_B_SIDE" (effects (font (size 1.27 1.27))))
          (number "17" (effects (font (size 1.27 1.27))))
        )
        (pin input line (at 0 2.54 0) (length 2.54)
          (name "VBUS_VS_DISCH" (effects (font (size 1.27 1.27))))
          (number "18" (effects (font (size 1.27 1.27))))
        )
        (pin output line (at 30.48 2.54 180) (length 2.54)
          (name "~{ALERT}" (effects (font (size 1.27 1.27))))
          (number "19" (effects (font (size 1.27 1.27))))
        )
        (pin bidirectional line (at 0 -20.32 0) (length 2.54)
          (name "CC1" (effects (font (size 1.27 1.27))))
          (number "2" (effects (font (size 1.27 1.27))))
        )
        (pin output line (at 30.48 -10.16 180) (length 2.54)
          (name "POWER_OK2" (effects (font (size 1.27 1.27))))
          (number "20" (effects (font (size 1.27 1.27))))
        )
        (pin output line (at 30.48 -20.32 180) (length 2.54)
          (name "VREG_1V2" (effects (font (size 1.27 1.27))))
          (number "21" (effects (font (size 1.27 1.27))))
        )
        (pin power_in line (at 30.48 -25.4 180) (length 2.54)
          (name "VSYS" (effects (font (size 1.27 1.27))))
          (number "22" (effects (font (size 1.27 1.27))))
        )
        (pin output line (at 30.48 -22.86 180) (length 2.54)
          (name "VREG_2V7" (effects (font (size 1.27 1.27))))
          (number "23" (effects (font (size 1.27 1.27))))
        )
        (pin power_in line (at 30.48 -17.78 180) (length 2.54)
          (name "VDD" (effects (font (size 1.27 1.27))))
          (number "24" (effects (font (size 1.27 1.27))))
        )
        (pin power_in line (at 30.48 -34.29 180) (length 2.54)
          (name "EP" (effects (font (size 1.27 1.27))))
          (number "25" (effects (font (size 1.27 1.27))))
        )
        (pin no_connect line (at 2.54 -7.62 0) (length 2.54) hide
          (name "NC" (effects (font (size 1.27 1.27))))
          (number "3" (effects (font (size 1.27 1.27))))
        )
        (pin bidirectional line (at 0 -22.86 0) (length 2.54)
          (name "CC2" (effects (font (size 1.27 1.27))))
          (number "4" (effects (font (size 1.27 1.27))))
        )
        (pin bidirectional line (at 0 -25.4 0) (length 2.54)
          (name "CC2DB" (effects (font (size 1.27 1.27))))
          (number "5" (effects (font (size 1.27 1.27))))
        )
        (pin input line (at 0 -5.08 0) (length 2.54)
          (name "RESET" (effects (font (size 1.27 1.27))))
          (number "6" (effects (font (size 1.27 1.27))))
        )
        (pin input line (at 0 -10.16 0) (length 2.54)
          (name "SCL" (effects (font (size 1.27 1.27))))
          (number "7" (effects (font (size 1.27 1.27))))
        )
        (pin bidirectional line (at 0 -12.7 0) (length 2.54)
          (name "SDA" (effects (font (size 1.27 1.27))))
          (number "8" (effects (font (size 1.27 1.27))))
        )
        (pin bidirectional line (at 0 -2.54 0) (length 2.54)
          (name "DISCH" (effects (font (size 1.27 1.27))))
          (number "9" (effects (font (size 1.27 1.27))))
        )
      )
    )
	(symbol "sa800u-baseboard-hw:SW_CVS-02B" (in_bom yes) (on_board yes)
      (property "Reference" "SW" (id 0) (at 26.67 -2.54 0)
        (effects (font (size 1.27 1.27) (thickness 0.15)) (justify left bottom))
      )
      (property "Value" "SW_CVS-02B" (id 1) (at 26.67 -5.08 0)
        (effects (font (size 1.27 1.27) (thickness 0.15)) (justify left bottom))
      )
      (property "Footprint" "sa800u-baseboard-hw-footprints:SW_DIP_SPSTx02_Slide_Copal_CVS-02xB_W5.9mm_P1mm" (id 2) (at 26.67 -7.62 0)
        (effects (font (size 1.27 1.27) (thickness 0.15)) (justify left bottom) hide)
      )
      (property "Datasheet" "https://www.mouser.pl/datasheet/2/972/cvs-1827291.pdf" (id 3) (at 26.67 -10.16 0)
        (effects (font (size 1.27 1.27) (thickness 0.15)) (justify left bottom) hide)
      )
      (property "MPN" "CVS-02B" (id 4) (at 26.67 -12.7 0)
        (effects (font (size 1.27 1.27) (thickness 0.15)) (justify left bottom) hide)
      )
      (property "Manufacturer" "Nidec" (id 5) (at 26.67 -15.24 0)
        (effects (font (size 1.27 1.27) (thickness 0.15)) (justify left bottom) hide)
      )
      (property "Author" "Antmicro" (id 6) (at 26.67 -17.78 0)
        (effects (font (size 1.27 1.27) (thickness 0.15)) (justify left bottom) hide)
      )
      (property "License" "Apache-2.0" (id 7) (at 26.67 -20.32 0)
        (effects (font (size 1.27 1.27) (thickness 0.15)) (justify left bottom) hide)
      )
      (property "ki_keywords" "dip switch" (id 8) (at 0 0 0)
        (effects (font (size 1.27 1.27)) hide)
      )
      (property "ki_description" "2x DIP Switch, Single Pole Single Throw (SPST) switch, small symbol" (id 9) (at 0 0 0)
        (effects (font (size 1.27 1.27)) hide)
      )
      (property "ki_fp_filters" "SW?DIP?x2*" (id 10) (at 0 0 0)
        (effects (font (size 1.27 1.27)) hide)
      )
      (symbol "SW_CVS-02B_1_1"
        (polyline
          (pts
            (xy 3.81 -2.54)
            (xy 2.54 -2.54)
          )
          (stroke (width 0.254) (type default) (color 0 0 0 0))
          (fill (type none))
        )
        (polyline
          (pts
            (xy 3.81 0)
            (xy 2.54 0)
          )
          (stroke (width 0.254) (type default) (color 0 0 0 0))
          (fill (type none))
        )
        (polyline
          (pts
            (xy 4.826 -2.413)
            (xy 8.7122 -1.3716)
          )
          (stroke (width 0.254) (type default) (color 0 0 0 0))
          (fill (type none))
        )
        (polyline
          (pts
            (xy 4.826 0.127)
            (xy 8.7122 1.1684)
          )
          (stroke (width 0.254) (type default) (color 0 0 0 0))
          (fill (type none))
        )
        (polyline
          (pts
            (xy 10.16 -2.54)
            (xy 8.89 -2.54)
          )
          (stroke (width 0.254) (type default) (color 0 0 0 0))
          (fill (type none))
        )
        (polyline
          (pts
            (xy 10.16 0)
            (xy 8.89 0)
          )
          (stroke (width 0.254) (type default) (color 0 0 0 0))
          (fill (type none))
        )
        (rectangle (start 2.54 2.54) (end 10.16 -7.62)
          (stroke (width 0.254) (type default) (color 0 0 0 0))
          (fill (type background))
        )
        (circle (center 4.318 -2.54) (radius 0.508)
          (stroke (width 0.254) (type default) (color 0 0 0 0))
          (fill (type none))
        )
        (circle (center 4.318 0) (radius 0.508)
          (stroke (width 0.254) (type default) (color 0 0 0 0))
          (fill (type none))
        )
        (circle (center 8.382 -2.54) (radius 0.508)
          (stroke (width 0.254) (type default) (color 0 0 0 0))
          (fill (type none))
        )
        (circle (center 8.382 0) (radius 0.508)
          (stroke (width 0.254) (type default) (color 0 0 0 0))
          (fill (type none))
        )
        (pin passive line (at 0 0 0) (length 2.54)
          (name "~" (effects (font (size 1.27 1.27))))
          (number "1" (effects (font (size 1.27 1.27))))
        )
        (pin passive line (at 0 -2.54 0) (length 2.54)
          (name "~" (effects (font (size 1.27 1.27))))
          (number "2" (effects (font (size 1.27 1.27))))
        )
        (pin passive line (at 12.7 -2.54 180) (length 2.54)
          (name "~" (effects (font (size 1.27 1.27))))
          (number "3" (effects (font (size 1.27 1.27))))
        )
        (pin passive line (at 12.7 0 180) (length 2.54)
          (name "~" (effects (font (size 1.27 1.27))))
          (number "4" (effects (font (size 1.27 1.27))))
        )
        (pin power_in line (at 12.7 -5.08 180) (length 2.54)
          (name "SH" (effects (font (size 1.27 1.27))))
          (number "SH" (effects (font (size 1.27 1.27))))
        )
      )
    )
	(symbol "sa800u-baseboard-hw:SW_SPST_KMR211NGLFS" (in_bom yes) (on_board yes)
      (property "Reference" "SW" (id 0) (at 25.4 -2.54 0)
        (effects (font (size 1.27 1.27) (thickness 0.15)) (justify left bottom))
      )
      (property "Value" "SW_SPST_KMR211NGLFS" (id 1) (at 25.4 -5.08 0)
        (effects (font (size 1.27 1.27) (thickness 0.15)) (justify left bottom))
      )
      (property "Footprint" "sa800u-baseboard-hw-footprints:SW_SPST_4.2x2.8" (id 2) (at 25.4 -7.62 0)
        (effects (font (size 1.27 1.27) (thickness 0.15)) (justify left bottom) hide)
      )
      (property "Datasheet" "http://www.farnell.com/datasheets/2631211.pdf" (id 3) (at 25.4 -10.16 0)
        (effects (font (size 1.27 1.27) (thickness 0.15)) (justify left bottom) hide)
      )
      (property "MPN" "KMR211NGLFS" (id 4) (at 25.4 -12.7 0)
        (effects (font (size 1.27 1.27) (thickness 0.15)) (justify left bottom) hide)
      )
      (property "Manufacturer" "C&K" (id 5) (at 25.4 -15.24 0)
        (effects (font (size 1.27 1.27) (thickness 0.15)) (justify left bottom) hide)
      )
      (property "Author" "Antmicro" (id 6) (at 25.4 -17.78 0)
        (effects (font (size 1.27 1.27) (thickness 0.15)) (justify left bottom) hide)
      )
      (property "License" "Apache-2.0" (id 7) (at 25.4 -20.32 0)
        (effects (font (size 1.27 1.27) (thickness 0.15)) (justify left bottom) hide)
      )
      (symbol "SW_SPST_KMR211NGLFS_1_1"
        (polyline
          (pts
            (xy 2.54 -2.54)
            (xy 3.302 -2.54)
          )
          (stroke (width 0.254) (type default) (color 0 0 0 0))
          (fill (type background))
        )
        (polyline
          (pts
            (xy 2.54 0)
            (xy 3.302 0)
          )
          (stroke (width 0.254) (type default) (color 0 0 0 0))
          (fill (type background))
        )
        (polyline
          (pts
            (xy 3.302 1.27)
            (xy 6.858 1.27)
          )
          (stroke (width 0.254) (type default) (color 0 0 0 0))
          (fill (type background))
        )
        (polyline
          (pts
            (xy 3.556 -0.3048)
            (xy 3.556 -2.1844)
          )
          (stroke (width 0.254) (type default) (color 0 0 0 0))
          (fill (type background))
        )
        (polyline
          (pts
            (xy 4.064 2.794)
            (xy 6.096 2.794)
          )
          (stroke (width 0.254) (type default) (color 0 0 0 0))
          (fill (type background))
        )
        (polyline
          (pts
            (xy 5.08 1.27)
            (xy 5.08 2.794)
          )
          (stroke (width 0.254) (type default) (color 0 0 0 0))
          (fill (type background))
        )
        (polyline
          (pts
            (xy 6.604 -0.254)
            (xy 6.604 -2.1844)
          )
          (stroke (width 0.254) (type default) (color 0 0 0 0))
          (fill (type background))
        )
        (polyline
          (pts
            (xy 7.62 -2.54)
            (xy 6.858 -2.54)
          )
          (stroke (width 0.254) (type default) (color 0 0 0 0))
          (fill (type background))
        )
        (polyline
          (pts
            (xy 7.62 0)
            (xy 6.858 0)
          )
          (stroke (width 0.254) (type default) (color 0 0 0 0))
          (fill (type background))
        )
        (circle (center 3.556 -2.54) (radius 0.254)
          (stroke (width 0.254) (type default) (color 0 0 0 0))
          (fill (type outline))
        )
        (circle (center 3.556 0) (radius 0.254)
          (stroke (width 0.254) (type default) (color 0 0 0 0))
          (fill (type outline))
        )
        (circle (center 6.604 -2.54) (radius 0.254)
          (stroke (width 0.254) (type default) (color 0 0 0 0))
          (fill (type outline))
        )
        (circle (center 6.604 0) (radius 0.254)
          (stroke (width 0.254) (type default) (color 0 0 0 0))
          (fill (type outline))
        )
        (pin passive line (at 0 0 0) (length 2.54)
          (name "~" (effects (font (size 1.27 1.27))))
          (number "1" (effects (font (size 1.27 1.27))))
        )
        (pin passive line (at 10.16 0 180) (length 2.54)
          (name "~" (effects (font (size 1.27 1.27))))
          (number "2" (effects (font (size 1.27 1.27))))
        )
        (pin passive line (at 0 -2.54 0) (length 2.54)
          (name "~" (effects (font (size 1.27 1.27))))
          (number "3" (effects (font (size 1.27 1.27))))
        )
        (pin passive line (at 10.16 -2.54 180) (length 2.54)
          (name "~" (effects (font (size 1.27 1.27))))
          (number "4" (effects (font (size 1.27 1.27))))
        )
      )
    )
	(symbol "sa800u-baseboard-hw:Si7223DN" (pin_names (offset 0)) (in_bom yes) (on_board yes)
      (property "Reference" "Q" (id 0) (at 22.86 5.08 0)
        (effects (font (size 1.27 1.27) (thickness 0.15)) (justify left bottom))
      )
      (property "Value" "Si7223DN" (id 1) (at 22.86 0 0)
        (effects (font (size 1.27 1.27) (thickness 0.15)) (justify left bottom) hide)
      )
      (property "Footprint" "antmicro-footprints:PowerPak-1212" (id 2) (at 22.86 -2.54 0)
        (effects (font (size 1.27 1.27) (thickness 0.15)) (justify left bottom) hide)
      )
      (property "Datasheet" "https://www.farnell.com/datasheets/2606257.pdf" (id 3) (at 22.86 -5.08 0)
        (effects (font (size 1.27 1.27) (thickness 0.15)) (justify left bottom) hide)
      )
      (property "MPN" "SI7223DN-T1-GE3" (id 4) (at 22.86 2.54 0)
        (effects (font (size 1.27 1.27) (thickness 0.15)) (justify left bottom))
      )
      (property "Manufacturer" "Vishay" (id 5) (at 22.86 -7.62 0)
        (effects (font (size 1.27 1.27) (thickness 0.15)) (justify left bottom) hide)
      )
      (property "Author" "Antmicro" (id 6) (at 22.86 -10.16 0)
        (effects (font (size 1.27 1.27) (thickness 0.15)) (justify left bottom) hide)
      )
      (property "License" "Apache-2.0" (id 7) (at 22.86 -12.7 0)
        (effects (font (size 1.27 1.27) (thickness 0.15)) (justify left bottom) hide)
      )
      (property "ki_description" "Dual MOSFET, P Channel, 30 V, 6 A, 0.022 ohm, PowerPAK 1212, Surface Mount" (id 8) (at 0 0 0)
        (effects (font (size 1.27 1.27)) hide)
      )
      (symbol "Si7223DN_1_1"
        (polyline
          (pts
            (xy 2.54 -8.89)
            (xy 5.08 -8.89)
          )
          (stroke (width 0.254) (type default) (color 0 0 0 0))
          (fill (type background))
        )
        (polyline
          (pts
            (xy 2.54 0)
            (xy 5.08 0)
          )
          (stroke (width 0.254) (type default) (color 0 0 0 0))
          (fill (type background))
        )
        (polyline
          (pts
            (xy 5.08 -5.08)
            (xy 5.08 -10.16)
          )
          (stroke (width 0.254) (type default) (color 0 0 0 0))
          (fill (type background))
        )
        (polyline
          (pts
            (xy 5.08 3.81)
            (xy 5.08 -1.27)
          )
          (stroke (width 0.254) (type default) (color 0 0 0 0))
          (fill (type background))
        )
        (polyline
          (pts
            (xy 5.715 -8.89)
            (xy 5.715 -10.16)
          )
          (stroke (width 0.254) (type default) (color 0 0 0 0))
          (fill (type background))
        )
        (polyline
          (pts
            (xy 5.715 -8.255)
            (xy 5.715 -6.985)
          )
          (stroke (width 0.254) (type default) (color 0 0 0 0))
          (fill (type background))
        )
        (polyline
          (pts
            (xy 5.715 -6.35)
            (xy 5.715 -5.08)
          )
          (stroke (width 0.254) (type default) (color 0 0 0 0))
          (fill (type background))
        )
        (polyline
          (pts
            (xy 5.715 -5.715)
            (xy 8.89 -5.715)
          )
          (stroke (width 0.254) (type default) (color 0 0 0 0))
          (fill (type background))
        )
        (polyline
          (pts
            (xy 5.715 0)
            (xy 5.715 -1.27)
          )
          (stroke (width 0.254) (type default) (color 0 0 0 0))
          (fill (type background))
        )
        (polyline
          (pts
            (xy 5.715 0.635)
            (xy 5.715 1.905)
          )
          (stroke (width 0.254) (type default) (color 0 0 0 0))
          (fill (type background))
        )
        (polyline
          (pts
            (xy 5.715 2.54)
            (xy 5.715 3.81)
          )
          (stroke (width 0.254) (type default) (color 0 0 0 0))
          (fill (type background))
        )
        (polyline
          (pts
            (xy 5.715 3.175)
            (xy 8.89 3.175)
          )
          (stroke (width 0.254) (type default) (color 0 0 0 0))
          (fill (type background))
        )
        (polyline
          (pts
            (xy 7.62 -9.525)
            (xy 8.89 -9.525)
          )
          (stroke (width 0.254) (type default) (color 0 0 0 0))
          (fill (type background))
        )
        (polyline
          (pts
            (xy 7.62 -0.635)
            (xy 8.89 -0.635)
          )
          (stroke (width 0.254) (type default) (color 0 0 0 0))
          (fill (type background))
        )
        (polyline
          (pts
            (xy 8.255 -8.255)
            (xy 9.525 -8.255)
          )
          (stroke (width 0.254) (type default) (color 0 0 0 0))
          (fill (type background))
        )
        (polyline
          (pts
            (xy 8.255 0.635)
            (xy 9.525 0.635)
          )
          (stroke (width 0.254) (type default) (color 0 0 0 0))
          (fill (type background))
        )
        (polyline
          (pts
            (xy 8.89 -10.16)
            (xy 11.43 -10.16)
          )
          (stroke (width 0.254) (type default) (color 0 0 0 0))
          (fill (type background))
        )
        (polyline
          (pts
            (xy 8.89 -8.89)
            (xy 8.89 -10.16)
          )
          (stroke (width 0.254) (type default) (color 0 0 0 0))
          (fill (type background))
        )
        (polyline
          (pts
            (xy 8.89 -8.89)
            (xy 8.89 -5.08)
          )
          (stroke (width 0.254) (type default) (color 0 0 0 0))
          (fill (type background))
        )
        (polyline
          (pts
            (xy 8.89 -5.08)
            (xy 11.43 -5.08)
          )
          (stroke (width 0.254) (type default) (color 0 0 0 0))
          (fill (type background))
        )
        (polyline
          (pts
            (xy 8.89 -1.27)
            (xy 11.43 -1.27)
          )
          (stroke (width 0.254) (type default) (color 0 0 0 0))
          (fill (type background))
        )
        (polyline
          (pts
            (xy 8.89 0)
            (xy 8.89 -1.27)
          )
          (stroke (width 0.254) (type default) (color 0 0 0 0))
          (fill (type background))
        )
        (polyline
          (pts
            (xy 8.89 0)
            (xy 8.89 3.81)
          )
          (stroke (width 0.254) (type default) (color 0 0 0 0))
          (fill (type background))
        )
        (polyline
          (pts
            (xy 8.89 3.81)
            (xy 11.43 3.81)
          )
          (stroke (width 0.254) (type default) (color 0 0 0 0))
          (fill (type background))
        )
        (polyline
          (pts
            (xy 6.35 -6.985)
            (xy 7.62 -7.62)
            (xy 6.35 -8.255)
            (xy 6.35 -6.985)
          )
          (stroke (width 0.254) (type default) (color 0 0 0 0))
          (fill (type outline))
        )
        (polyline
          (pts
            (xy 6.35 1.905)
            (xy 7.62 1.27)
            (xy 6.35 0.635)
            (xy 6.35 1.905)
          )
          (stroke (width 0.254) (type default) (color 0 0 0 0))
          (fill (type outline))
        )
        (polyline
          (pts
            (xy 6.985 -7.62)
            (xy 7.62 -7.62)
            (xy 7.62 -9.525)
            (xy 5.715 -9.525)
          )
          (stroke (width 0.254) (type default) (color 0 0 0 0))
          (fill (type background))
        )
        (polyline
          (pts
            (xy 6.985 1.27)
            (xy 7.62 1.27)
            (xy 7.62 -0.635)
            (xy 5.715 -0.635)
          )
          (stroke (width 0.254) (type default) (color 0 0 0 0))
          (fill (type background))
        )
        (polyline
          (pts
            (xy 9.525 -6.985)
            (xy 8.89 -8.255)
            (xy 8.255 -6.985)
            (xy 9.525 -6.985)
          )
          (stroke (width 0.254) (type default) (color 0 0 0 0))
          (fill (type outline))
        )
        (polyline
          (pts
            (xy 9.525 1.905)
            (xy 8.89 0.635)
            (xy 8.255 1.905)
            (xy 9.525 1.905)
          )
          (stroke (width 0.254) (type default) (color 0 0 0 0))
          (fill (type outline))
        )
        (rectangle (start 2.54 6.35) (end 11.43 -12.7)
          (stroke (width 0.254) (type default) (color 0 0 0 0))
          (fill (type background))
        )
        (pin passive line (at 13.97 -1.27 180) (length 2.54)
          (name "S1" (effects (font (size 1.27 1.27))))
          (number "1" (effects (font (size 1.27 1.27))))
        )
        (pin passive line (at 0 0 0) (length 2.54)
          (name "G1" (effects (font (size 1.27 1.27))))
          (number "2" (effects (font (size 1.27 1.27))))
        )
        (pin passive line (at 13.97 -10.16 180) (length 2.54)
          (name "S2" (effects (font (size 1.27 1.27))))
          (number "3" (effects (font (size 1.27 1.27))))
        )
        (pin passive line (at 0 -8.89 0) (length 2.54)
          (name "G2" (effects (font (size 1.27 1.27))))
          (number "4" (effects (font (size 1.27 1.27))))
        )
        (pin passive line (at 13.97 -5.08 180) (length 2.54)
          (name "D2" (effects (font (size 1.27 1.27))))
          (number "5" (effects (font (size 1.27 1.27))))
        )
        (pin passive line (at 13.97 -5.08 180) (length 2.54) hide
          (name "D2" (effects (font (size 1.27 1.27))))
          (number "6" (effects (font (size 1.27 1.27))))
        )
        (pin passive line (at 13.97 3.81 180) (length 2.54)
          (name "D1" (effects (font (size 1.27 1.27))))
          (number "7" (effects (font (size 1.27 1.27))))
        )
        (pin passive line (at 13.97 3.81 180) (length 2.54) hide
          (name "D1" (effects (font (size 1.27 1.27))))
          (number "8" (effects (font (size 1.27 1.27))))
        )
      )
    )
	(symbol "sa800u-baseboard-hw:Spacer_H4.0mm_9774040151" (pin_names hide) (in_bom yes) (on_board yes)
      (property "Reference" "H" (id 0) (at 22.86 -2.54 0)
        (effects (font (size 1.27 1.27) (thickness 0.15)) (justify left bottom))
      )
      (property "Value" "Spacer_H4.0mm_9774040151" (id 1) (at 22.86 -5.08 0)
        (effects (font (size 1.27 1.27) (thickness 0.15)) (justify left bottom))
      )
      (property "Footprint" "antmicro-footprints:Spacer_SMD_M2.5_H4mm_Wurth_9774040151" (id 2) (at 22.86 -7.62 0)
        (effects (font (size 1.27 1.27) (thickness 0.15)) (justify left bottom) hide)
      )
      (property "Datasheet" "https://www.we-online.com/components/products/datasheet/9774040151R.pdf" (id 3) (at 22.86 -10.16 0)
        (effects (font (size 1.27 1.27) (thickness 0.15)) (justify left bottom) hide)
      )
      (property "Manufacturer" "Würth Elektronik" (id 4) (at 22.86 -12.7 0)
        (effects (font (size 1.27 1.27) (thickness 0.15)) (justify left bottom) hide)
      )
      (property "MPN" "9774040151R" (id 5) (at 22.86 -15.24 0)
        (effects (font (size 1.27 1.27) (thickness 0.15)) (justify left bottom) hide)
      )
      (property "Author" "Antmicro" (id 6) (at 22.86 -17.78 0)
        (effects (font (size 1.27 1.27) (thickness 0.15)) (justify left bottom) hide)
      )
      (property "License" "Apache-2.0" (id 7) (at 22.86 -20.32 0)
        (effects (font (size 1.27 1.27) (thickness 0.15)) (justify left bottom) hide)
      )
      (symbol "Spacer_H4.0mm_9774040151_1_1"
        (rectangle (start 2.54 -2.54) (end 7.62 2.54)
          (stroke (width 0.254) (type default) (color 0 0 0 0))
          (fill (type background))
        )
        (rectangle (start 3.81 -1.27) (end 6.35 1.27)
          (stroke (width 0.254) (type default) (color 0 0 0 0))
          (fill (type none))
        )
        (pin passive line (at 0 0 0) (length 2.54)
          (name "1" (effects (font (size 1.27 1.27))))
          (number "1" (effects (font (size 1.27 1.27))))
        )
      )
    )
	(symbol "sa800u-baseboard-hw:Spacer_H6mm_9774060151" (in_bom yes) (on_board yes)
      (property "Reference" "H" (id 0) (at 22.86 -2.54 0)
        (effects (font (size 1.27 1.27) (thickness 0.15)) (justify left bottom))
      )
      (property "Value" "Spacer_H6mm_9774060151" (id 1) (at 22.86 -5.08 0)
        (effects (font (size 1.27 1.27) (thickness 0.15)) (justify left bottom))
      )
      (property "Footprint" "antmicro-footprints:Spacer_SMD_M2.5_H6mm_Wurth_9774060151" (id 2) (at 22.86 -7.62 0)
        (effects (font (size 1.27 1.27) (thickness 0.15)) (justify left bottom) hide)
      )
      (property "Datasheet" "https://www.we-online.com/catalog/datasheet/9774060151.pdf" (id 3) (at 22.86 -10.16 0)
        (effects (font (size 1.27 1.27) (thickness 0.15)) (justify left bottom) hide)
      )
      (property "Manufacturer" "Würth Elektronik" (id 4) (at 22.86 -12.7 0)
        (effects (font (size 1.27 1.27) (thickness 0.15)) (justify left bottom) hide)
      )
      (property "MPN" "9774060151" (id 5) (at 22.86 -15.24 0)
        (effects (font (size 1.27 1.27) (thickness 0.15)) (justify left bottom) hide)
      )
      (property "Author" "Antmicro" (id 6) (at 22.86 -17.78 0)
        (effects (font (size 1.27 1.27) (thickness 0.15)) (justify left bottom) hide)
      )
      (property "License" "Apache-2.0" (id 7) (at 22.86 -20.32 0)
        (effects (font (size 1.27 1.27) (thickness 0.15)) (justify left bottom) hide)
      )
      (property "ki_keywords" "Standoffs & Spacers" (id 8) (at 0 0 0)
        (effects (font (size 1.27 1.27)) hide)
      )
      (property "ki_description" "Standoffs & Spacers" (id 9) (at 0 0 0)
        (effects (font (size 1.27 1.27)) hide)
      )
      (symbol "Spacer_H6mm_9774060151_1_1"
        (rectangle (start 2.54 -2.54) (end 7.62 2.54)
          (stroke (width 0.254) (type default) (color 0 0 0 0))
          (fill (type background))
        )
        (rectangle (start 3.81 -1.27) (end 6.35 1.27)
          (stroke (width 0.254) (type default) (color 0 0 0 0))
          (fill (type background))
        )
        (pin passive line (at 0 0 0) (length 2.54)
          (name "~" (effects (font (size 1.27 1.27))))
          (number "1" (effects (font (size 1.27 1.27))))
        )
      )
    )
	(symbol "sa800u-baseboard-hw:TPS2378DDA" (in_bom yes) (on_board yes)
      (property "Reference" "U" (id 0) (at 35.56 0 0)
        (effects (font (size 1.27 1.27) (thickness 0.15)) (justify left bottom))
      )
      (property "Value" "TPS2378DDA" (id 1) (at 35.56 -2.54 0)
        (effects (font (size 1.27 1.27) (thickness 0.15)) (justify left bottom) hide)
      )
      (property "Footprint" "sa800u-baseboard-hw-footprints:SOIC-8-1EP_3.9x4.9x1.75mm_P1.27mm" (id 2) (at 35.56 -5.08 0)
        (effects (font (size 1.27 1.27) (thickness 0.15)) (justify left bottom) hide)
      )
      (property "Datasheet" "http://www.ti.com/lit/ds/symlink/tps2378.pdf" (id 3) (at 35.56 -7.62 0)
        (effects (font (size 1.27 1.27) (thickness 0.15)) (justify left bottom) hide)
      )
      (property "MPN" "TPS2378DDA" (id 4) (at 35.56 -12.7 0)
        (effects (font (size 1.27 1.27) (thickness 0.15)) (justify left bottom))
      )
      (property "Manufacturer" "Texas Instruments" (id 5) (at 35.56 -10.16 0)
        (effects (font (size 1.27 1.27) (thickness 0.15)) (justify left bottom) hide)
      )
      (property "Author" "Antmicro" (id 6) (at 35.56 -15.24 0)
        (effects (font (size 1.27 1.27) (thickness 0.15)) (justify left bottom) hide)
      )
      (property "License" "Apache-2.0" (id 7) (at 35.56 -17.78 0)
        (effects (font (size 1.27 1.27) (thickness 0.15)) (justify left bottom) hide)
      )
      (property "ki_description" "IEEE 802.3at PoE High-Power PD Interface with AUX Control" (id 8) (at 0 0 0)
        (effects (font (size 1.27 1.27)) hide)
      )
      (symbol "TPS2378DDA_1_1"
        (polyline
          (pts
            (xy 2.54 2.54)
            (xy 17.78 2.54)
            (xy 17.78 -16.51)
            (xy 2.54 -16.51)
            (xy 2.54 2.54)
          )
          (stroke (width 0.254) (type default) (color 0 0 0 0))
          (fill (type background))
        )
        (pin power_in line (at 0 0 0) (length 2.54)
          (name "VDD" (effects (font (size 1.27 1.27))))
          (number "1" (effects (font (size 1.27 1.27))))
        )
        (pin passive line (at 0 -2.54 0) (length 2.54)
          (name "DEN" (effects (font (size 1.27 1.27))))
          (number "2" (effects (font (size 1.27 1.27))))
        )
        (pin passive line (at 0 -8.89 0) (length 2.54)
          (name "CLS" (effects (font (size 1.27 1.27))))
          (number "3" (effects (font (size 1.27 1.27))))
        )
        (pin power_in line (at 0 -11.43 0) (length 2.54)
          (name "VSS" (effects (font (size 1.27 1.27))))
          (number "4" (effects (font (size 1.27 1.27))))
        )
        (pin passive line (at 20.32 -13.97 180) (length 2.54)
          (name "RTN" (effects (font (size 1.27 1.27))))
          (number "5" (effects (font (size 1.27 1.27))))
        )
        (pin passive line (at 20.32 -5.08 180) (length 2.54)
          (name "CDB" (effects (font (size 1.27 1.27))))
          (number "6" (effects (font (size 1.27 1.27))))
        )
        (pin passive line (at 20.32 -2.54 180) (length 2.54)
          (name "T2P" (effects (font (size 1.27 1.27))))
          (number "7" (effects (font (size 1.27 1.27))))
        )
        (pin passive line (at 20.32 0 180) (length 2.54)
          (name "APD" (effects (font (size 1.27 1.27))))
          (number "8" (effects (font (size 1.27 1.27))))
        )
        (pin power_in line (at 0 -13.97 0) (length 2.54)
          (name "EP" (effects (font (size 1.27 1.27))))
          (number "9" (effects (font (size 1.27 1.27))))
        )
      )
    )
	(symbol "sa800u-baseboard-hw:TPS25820DSST" (in_bom yes) (on_board yes)
      (property "Reference" "U" (id 0) (at 35.56 -5.08 0)
        (effects (font (size 1.27 1.27) (thickness 0.15)) (justify left bottom))
      )
      (property "Value" "TPS25820DSST" (id 1) (at 35.56 -10.16 0)
        (effects (font (size 1.27 1.27) (thickness 0.15)) (justify left bottom) hide)
      )
      (property "Footprint" "sa800u-baseboard-hw-footprints:WSON-12-1EP_2x3mm_P0.5mm" (id 2) (at 35.56 -12.7 0)
        (effects (font (size 1.27 1.27) (thickness 0.15)) (justify left bottom) hide)
      )
      (property "Datasheet" "https://www.ti.com/lit/ds/symlink/tps25820.pdf?ts=1624891405505&ref_url=https%253A%252F%252Fwww.ti.com%252Fproduct%252FTPS25820" (id 3) (at 35.56 -15.24 0)
        (effects (font (size 1.27 1.27) (thickness 0.15)) (justify left bottom) hide)
      )
      (property "Manufacturer" "Texas Instruments" (id 4) (at 35.56 -17.78 0)
        (effects (font (size 1.27 1.27) (thickness 0.15)) (justify left bottom) hide)
      )
      (property "MPN" "TPS25820DSST" (id 5) (at 35.56 -7.62 0)
        (effects (font (size 1.27 1.27) (thickness 0.15)) (justify left bottom))
      )
      (property "Author" "Antmicro" (id 6) (at 35.56 -20.32 0)
        (effects (font (size 1.27 1.27) (thickness 0.15)) (justify left bottom) hide)
      )
      (property "License" "Apache-2.0" (id 7) (at 35.56 -22.86 0)
        (effects (font (size 1.27 1.27) (thickness 0.15)) (justify left bottom) hide)
      )
      (symbol "TPS25820DSST_1_1"
        (rectangle (start 2.54 2.54) (end 17.78 -22.86)
          (stroke (width 0.254) (type default) (color 0 0 0 0))
          (fill (type background))
        )
        (pin power_in line (at 0 0 0) (length 2.54)
          (name "IN" (effects (font (size 1.27 1.27))))
          (number "1" (effects (font (size 1.27 1.27))))
        )
        (pin input line (at 0 -20.32 0) (length 2.54)
          (name "GND" (effects (font (size 1.27 1.27))))
          (number "10" (effects (font (size 1.27 1.27))))
        )
        (pin bidirectional line (at 20.32 -7.62 180) (length 2.54)
          (name "CC2" (effects (font (size 1.27 1.27))))
          (number "11" (effects (font (size 1.27 1.27))))
        )
        (pin power_out line (at 20.32 0 180) (length 2.54)
          (name "OUT" (effects (font (size 1.27 1.27))))
          (number "12" (effects (font (size 1.27 1.27))))
        )
        (pin passive line (at 0 -20.32 0) (length 2.54) hide
          (name "GND" (effects (font (size 1.27 1.27))))
          (number "13" (effects (font (size 1.27 1.27))))
        )
        (pin passive line (at 0 0 0) (length 2.54) hide
          (name "IN" (effects (font (size 1.27 1.27))))
          (number "2" (effects (font (size 1.27 1.27))))
        )
        (pin input line (at 0 -10.16 0) (length 2.54)
          (name "CHG" (effects (font (size 1.27 1.27))))
          (number "3" (effects (font (size 1.27 1.27))))
        )
        (pin input line (at 0 -5.08 0) (length 2.54)
          (name "EN" (effects (font (size 1.27 1.27))))
          (number "4" (effects (font (size 1.27 1.27))))
        )
        (pin output line (at 20.32 -12.7 180) (length 2.54)
          (name "nFAULT" (effects (font (size 1.27 1.27))))
          (number "5" (effects (font (size 1.27 1.27))))
        )
        (pin output line (at 20.32 -16.51 180) (length 2.54)
          (name "nSINK" (effects (font (size 1.27 1.27))))
          (number "6" (effects (font (size 1.27 1.27))))
        )
        (pin output line (at 20.32 -20.32 180) (length 2.54)
          (name "nPOL" (effects (font (size 1.27 1.27))))
          (number "7" (effects (font (size 1.27 1.27))))
        )
        (pin input line (at 0 -15.24 0) (length 2.54)
          (name "REF" (effects (font (size 1.27 1.27))))
          (number "8" (effects (font (size 1.27 1.27))))
        )
        (pin bidirectional line (at 20.32 -5.08 180) (length 2.54)
          (name "CC1" (effects (font (size 1.27 1.27))))
          (number "9" (effects (font (size 1.27 1.27))))
        )
      )
    )
	(symbol "sa800u-baseboard-hw:TPS7A0518P_SOT23-5" (in_bom yes) (on_board yes)
      (property "Reference" "U" (id 0) (at 26.67 -1.27 0)
        (effects (font (size 1.27 1.27) (thickness 0.15)) (justify left bottom))
      )
      (property "Value" "TPS7A0518P_SOT23-5" (id 1) (at 26.67 -3.81 0)
        (effects (font (size 1.27 1.27) (thickness 0.15)) (justify left bottom) hide)
      )
      (property "Footprint" "sa800u-baseboard-hw-footprints:SOT-23-5" (id 2) (at 26.67 -6.35 0)
        (effects (font (size 1.27 1.27) (thickness 0.15)) (justify left bottom) hide)
      )
      (property "Datasheet" "https://www.ti.com/lit/ds/symlink/tps7a05.pdf?ts=1678973651768&ref_url=https%253A%252F%252Fwww.google.com%252F" (id 3) (at 26.67 -8.89 0)
        (effects (font (size 1.27 1.27) (thickness 0.15)) (justify left bottom) hide)
      )
      (property "MPN" "TPS7A0518PDBVT" (id 4) (at 26.67 -11.43 0)
        (effects (font (size 1.27 1.27) (thickness 0.15)) (justify left bottom))
      )
      (property "Manufacturer" "Texas Instruments" (id 5) (at 26.67 -13.97 0)
        (effects (font (size 1.27 1.27) (thickness 0.15)) (justify left bottom) hide)
      )
      (property "Author" "Antmicro" (id 6) (at 26.67 -16.51 0)
        (effects (font (size 1.27 1.27) (thickness 0.15)) (justify left bottom) hide)
      )
      (property "License" "Apache-2.0" (id 7) (at 26.67 -19.05 0)
        (effects (font (size 1.27 1.27) (thickness 0.15)) (justify left bottom) hide)
      )
      (symbol "TPS7A0518P_SOT23-5_1_1"
        (rectangle (start 2.54 2.54) (end 12.7 -5.08)
          (stroke (width 0.254) (type default) (color 0 0 0 0))
          (fill (type background))
        )
        (pin power_in line (at 0 0 0) (length 2.54)
          (name "VIN" (effects (font (size 1.27 1.27))))
          (number "1" (effects (font (size 1.27 1.27))))
        )
        (pin power_in line (at 15.24 -2.54 180) (length 2.54)
          (name "GND" (effects (font (size 1.27 1.27))))
          (number "2" (effects (font (size 1.27 1.27))))
        )
        (pin input line (at 0 -2.54 0) (length 2.54)
          (name "EN" (effects (font (size 1.27 1.27))))
          (number "3" (effects (font (size 1.27 1.27))))
        )
        (pin no_connect line (at 2.54 -3.81 0) (length 2.54) hide
          (name "NC" (effects (font (size 1.27 1.27))))
          (number "4" (effects (font (size 1.27 1.27))))
        )
        (pin power_out line (at 15.24 0 180) (length 2.54)
          (name "VOUT" (effects (font (size 1.27 1.27))))
          (number "5" (effects (font (size 1.27 1.27))))
        )
      )
    )
	(symbol "sa800u-baseboard-hw:TP_0.75mm_SMD" (pin_numbers hide) (pin_names hide) (in_bom yes) (on_board yes)
      (property "Reference" "TP" (id 0) (at 17.78 -5.08 0)
        (effects (font (size 1.27 1.27) (thickness 0.15)) (justify left bottom))
      )
      (property "Value" "TP_0.75mm_SMD" (id 1) (at 17.78 -7.62 0)
        (effects (font (size 1.27 1.27) (thickness 0.15)) (justify left bottom) hide)
      )
      (property "Footprint" "sa800u-baseboard-hw-footprints:TP_SMD_0.75mm" (id 2) (at 17.78 -10.16 0)
        (effects (font (size 1.27 1.27) (thickness 0.15)) (justify left bottom) hide)
      )
      (property "Datasheet" "" (id 3) (at 17.78 -12.7 0)
        (effects (font (size 1.27 1.27) (thickness 0.15)) (justify left bottom) hide)
      )
      (property "MPN" "" (id 4) (at 17.78 -15.24 0)
        (effects (font (size 1.27 1.27) (thickness 0.15)) (justify left bottom) hide)
      )
      (property "Manufacturer" "" (id 5) (at 17.78 -17.78 0)
        (effects (font (size 1.27 1.27) (thickness 0.15)) (justify left bottom) hide)
      )
      (property "Author" "Antmicro" (id 6) (at 17.78 -20.32 0)
        (effects (font (size 1.27 1.27) (thickness 0.15)) (justify left bottom) hide)
      )
      (property "License" "Apache-2.0" (id 7) (at 17.78 -22.86 0)
        (effects (font (size 1.27 1.27) (thickness 0.15)) (justify left bottom) hide)
      )
      (property "ki_description" "Test Point 0.75mm" (id 8) (at 0 0 0)
        (effects (font (size 1.27 1.27)) hide)
      )
      (symbol "TP_0.75mm_SMD_1_1"
        (circle (center 3.175 0) (radius 0.635)
          (stroke (width 0.254) (type default) (color 0 0 0 0))
          (fill (type none))
        )
        (pin passive line (at 0 0 0) (length 2.54)
          (name "1" (effects (font (size 1.27 1.27))))
          (number "1" (effects (font (size 1.27 1.27))))
        )
      )
    )
	(symbol "sa800u-baseboard-hw:TP_0.75mm_SMD_10" (pin_numbers hide) (pin_names hide) (in_bom yes) (on_board yes)
      (property "Reference" "TP" (id 0) (at 17.78 -5.08 0)
        (effects (font (size 1.27 1.27) (thickness 0.15)) (justify left bottom))
      )
      (property "Value" "TP_0.75mm_SMD_10" (id 1) (at 17.78 -7.62 0)
        (effects (font (size 1.27 1.27) (thickness 0.15)) (justify left bottom) hide)
      )
      (property "Footprint" "sa800u-baseboard-hw-footprints:TP_SMD_0.75mm" (id 2) (at 17.78 -10.16 0)
        (effects (font (size 1.27 1.27) (thickness 0.15)) (justify left bottom) hide)
      )
      (property "Datasheet" "" (id 3) (at 17.78 -12.7 0)
        (effects (font (size 1.27 1.27) (thickness 0.15)) (justify left bottom) hide)
      )
      (property "MPN" "" (id 4) (at 17.78 -15.24 0)
        (effects (font (size 1.27 1.27) (thickness 0.15)) (justify left bottom) hide)
      )
      (property "Manufacturer" "" (id 5) (at 17.78 -17.78 0)
        (effects (font (size 1.27 1.27) (thickness 0.15)) (justify left bottom) hide)
      )
      (property "Author" "Antmicro" (id 6) (at 17.78 -20.32 0)
        (effects (font (size 1.27 1.27) (thickness 0.15)) (justify left bottom) hide)
      )
      (property "License" "Apache-2.0" (id 7) (at 17.78 -22.86 0)
        (effects (font (size 1.27 1.27) (thickness 0.15)) (justify left bottom) hide)
      )
      (property "ki_description" "Test Point 0.75mm" (id 8) (at 0 0 0)
        (effects (font (size 1.27 1.27)) hide)
      )
      (symbol "TP_0.75mm_SMD_10_1_1"
        (circle (center 3.175 0) (radius 0.635)
          (stroke (width 0.254) (type default) (color 0 0 0 0))
          (fill (type none))
        )
        (pin passive line (at 0 0 0) (length 2.54)
          (name "1" (effects (font (size 1.27 1.27))))
          (number "1" (effects (font (size 1.27 1.27))))
        )
      )
    )
	(symbol "sa800u-baseboard-hw:TP_0.75mm_SMD_11" (pin_numbers hide) (pin_names hide) (in_bom yes) (on_board yes)
      (property "Reference" "TP" (id 0) (at 17.78 -5.08 0)
        (effects (font (size 1.27 1.27) (thickness 0.15)) (justify left bottom))
      )
      (property "Value" "TP_0.75mm_SMD_11" (id 1) (at 17.78 -7.62 0)
        (effects (font (size 1.27 1.27) (thickness 0.15)) (justify left bottom) hide)
      )
      (property "Footprint" "sa800u-baseboard-hw-footprints:TP_SMD_0.75mm" (id 2) (at 17.78 -10.16 0)
        (effects (font (size 1.27 1.27) (thickness 0.15)) (justify left bottom) hide)
      )
      (property "Datasheet" "" (id 3) (at 17.78 -12.7 0)
        (effects (font (size 1.27 1.27) (thickness 0.15)) (justify left bottom) hide)
      )
      (property "MPN" "" (id 4) (at 17.78 -15.24 0)
        (effects (font (size 1.27 1.27) (thickness 0.15)) (justify left bottom) hide)
      )
      (property "Manufacturer" "" (id 5) (at 17.78 -17.78 0)
        (effects (font (size 1.27 1.27) (thickness 0.15)) (justify left bottom) hide)
      )
      (property "Author" "Antmicro" (id 6) (at 17.78 -20.32 0)
        (effects (font (size 1.27 1.27) (thickness 0.15)) (justify left bottom) hide)
      )
      (property "License" "Apache-2.0" (id 7) (at 17.78 -22.86 0)
        (effects (font (size 1.27 1.27) (thickness 0.15)) (justify left bottom) hide)
      )
      (property "ki_description" "Test Point 0.75mm" (id 8) (at 0 0 0)
        (effects (font (size 1.27 1.27)) hide)
      )
      (symbol "TP_0.75mm_SMD_11_1_1"
        (circle (center 3.175 0) (radius 0.635)
          (stroke (width 0.254) (type default) (color 0 0 0 0))
          (fill (type none))
        )
        (pin passive line (at 0 0 0) (length 2.54)
          (name "1" (effects (font (size 1.27 1.27))))
          (number "1" (effects (font (size 1.27 1.27))))
        )
      )
    )
	(symbol "sa800u-baseboard-hw:TP_0.75mm_SMD_12" (pin_numbers hide) (pin_names hide) (in_bom yes) (on_board yes)
      (property "Reference" "TP" (id 0) (at 17.78 -5.08 0)
        (effects (font (size 1.27 1.27) (thickness 0.15)) (justify left bottom))
      )
      (property "Value" "TP_0.75mm_SMD_12" (id 1) (at 17.78 -7.62 0)
        (effects (font (size 1.27 1.27) (thickness 0.15)) (justify left bottom) hide)
      )
      (property "Footprint" "sa800u-baseboard-hw-footprints:TP_SMD_0.75mm" (id 2) (at 17.78 -10.16 0)
        (effects (font (size 1.27 1.27) (thickness 0.15)) (justify left bottom) hide)
      )
      (property "Datasheet" "" (id 3) (at 17.78 -12.7 0)
        (effects (font (size 1.27 1.27) (thickness 0.15)) (justify left bottom) hide)
      )
      (property "MPN" "" (id 4) (at 17.78 -15.24 0)
        (effects (font (size 1.27 1.27) (thickness 0.15)) (justify left bottom) hide)
      )
      (property "Manufacturer" "" (id 5) (at 17.78 -17.78 0)
        (effects (font (size 1.27 1.27) (thickness 0.15)) (justify left bottom) hide)
      )
      (property "Author" "Antmicro" (id 6) (at 17.78 -20.32 0)
        (effects (font (size 1.27 1.27) (thickness 0.15)) (justify left bottom) hide)
      )
      (property "License" "Apache-2.0" (id 7) (at 17.78 -22.86 0)
        (effects (font (size 1.27 1.27) (thickness 0.15)) (justify left bottom) hide)
      )
      (property "ki_description" "Test Point 0.75mm" (id 8) (at 0 0 0)
        (effects (font (size 1.27 1.27)) hide)
      )
      (symbol "TP_0.75mm_SMD_12_1_1"
        (circle (center 3.175 0) (radius 0.635)
          (stroke (width 0.254) (type default) (color 0 0 0 0))
          (fill (type none))
        )
        (pin passive line (at 0 0 0) (length 2.54)
          (name "1" (effects (font (size 1.27 1.27))))
          (number "1" (effects (font (size 1.27 1.27))))
        )
      )
    )
	(symbol "sa800u-baseboard-hw:TP_0.75mm_SMD_13" (pin_numbers hide) (pin_names hide) (in_bom yes) (on_board yes)
      (property "Reference" "TP" (id 0) (at 17.78 -5.08 0)
        (effects (font (size 1.27 1.27) (thickness 0.15)) (justify left bottom))
      )
      (property "Value" "TP_0.75mm_SMD_13" (id 1) (at 17.78 -7.62 0)
        (effects (font (size 1.27 1.27) (thickness 0.15)) (justify left bottom) hide)
      )
      (property "Footprint" "sa800u-baseboard-hw-footprints:TP_SMD_0.75mm" (id 2) (at 17.78 -10.16 0)
        (effects (font (size 1.27 1.27) (thickness 0.15)) (justify left bottom) hide)
      )
      (property "Datasheet" "" (id 3) (at 17.78 -12.7 0)
        (effects (font (size 1.27 1.27) (thickness 0.15)) (justify left bottom) hide)
      )
      (property "MPN" "" (id 4) (at 17.78 -15.24 0)
        (effects (font (size 1.27 1.27) (thickness 0.15)) (justify left bottom) hide)
      )
      (property "Manufacturer" "" (id 5) (at 17.78 -17.78 0)
        (effects (font (size 1.27 1.27) (thickness 0.15)) (justify left bottom) hide)
      )
      (property "Author" "Antmicro" (id 6) (at 17.78 -20.32 0)
        (effects (font (size 1.27 1.27) (thickness 0.15)) (justify left bottom) hide)
      )
      (property "License" "Apache-2.0" (id 7) (at 17.78 -22.86 0)
        (effects (font (size 1.27 1.27) (thickness 0.15)) (justify left bottom) hide)
      )
      (property "ki_description" "Test Point 0.75mm" (id 8) (at 0 0 0)
        (effects (font (size 1.27 1.27)) hide)
      )
      (symbol "TP_0.75mm_SMD_13_1_1"
        (circle (center 3.175 0) (radius 0.635)
          (stroke (width 0.254) (type default) (color 0 0 0 0))
          (fill (type none))
        )
        (pin passive line (at 0 0 0) (length 2.54)
          (name "1" (effects (font (size 1.27 1.27))))
          (number "1" (effects (font (size 1.27 1.27))))
        )
      )
    )
	(symbol "sa800u-baseboard-hw:TP_0.75mm_SMD_14" (pin_numbers hide) (pin_names hide) (in_bom yes) (on_board yes)
      (property "Reference" "TP" (id 0) (at 17.78 -5.08 0)
        (effects (font (size 1.27 1.27) (thickness 0.15)) (justify left bottom))
      )
      (property "Value" "TP_0.75mm_SMD_14" (id 1) (at 17.78 -7.62 0)
        (effects (font (size 1.27 1.27) (thickness 0.15)) (justify left bottom) hide)
      )
      (property "Footprint" "sa800u-baseboard-hw-footprints:TP_SMD_0.75mm" (id 2) (at 17.78 -10.16 0)
        (effects (font (size 1.27 1.27) (thickness 0.15)) (justify left bottom) hide)
      )
      (property "Datasheet" "" (id 3) (at 17.78 -12.7 0)
        (effects (font (size 1.27 1.27) (thickness 0.15)) (justify left bottom) hide)
      )
      (property "MPN" "" (id 4) (at 17.78 -15.24 0)
        (effects (font (size 1.27 1.27) (thickness 0.15)) (justify left bottom) hide)
      )
      (property "Manufacturer" "" (id 5) (at 17.78 -17.78 0)
        (effects (font (size 1.27 1.27) (thickness 0.15)) (justify left bottom) hide)
      )
      (property "Author" "Antmicro" (id 6) (at 17.78 -20.32 0)
        (effects (font (size 1.27 1.27) (thickness 0.15)) (justify left bottom) hide)
      )
      (property "License" "Apache-2.0" (id 7) (at 17.78 -22.86 0)
        (effects (font (size 1.27 1.27) (thickness 0.15)) (justify left bottom) hide)
      )
      (property "ki_description" "Test Point 0.75mm" (id 8) (at 0 0 0)
        (effects (font (size 1.27 1.27)) hide)
      )
      (symbol "TP_0.75mm_SMD_14_1_1"
        (circle (center 3.175 0) (radius 0.635)
          (stroke (width 0.254) (type default) (color 0 0 0 0))
          (fill (type none))
        )
        (pin passive line (at 0 0 0) (length 2.54)
          (name "1" (effects (font (size 1.27 1.27))))
          (number "1" (effects (font (size 1.27 1.27))))
        )
      )
    )
	(symbol "sa800u-baseboard-hw:TP_0.75mm_SMD_15" (pin_numbers hide) (pin_names hide) (in_bom yes) (on_board yes)
      (property "Reference" "TP" (id 0) (at 17.78 -5.08 0)
        (effects (font (size 1.27 1.27) (thickness 0.15)) (justify left bottom))
      )
      (property "Value" "TP_0.75mm_SMD_15" (id 1) (at 17.78 -7.62 0)
        (effects (font (size 1.27 1.27) (thickness 0.15)) (justify left bottom) hide)
      )
      (property "Footprint" "sa800u-baseboard-hw-footprints:TP_SMD_0.75mm" (id 2) (at 17.78 -10.16 0)
        (effects (font (size 1.27 1.27) (thickness 0.15)) (justify left bottom) hide)
      )
      (property "Datasheet" "" (id 3) (at 17.78 -12.7 0)
        (effects (font (size 1.27 1.27) (thickness 0.15)) (justify left bottom) hide)
      )
      (property "MPN" "" (id 4) (at 17.78 -15.24 0)
        (effects (font (size 1.27 1.27) (thickness 0.15)) (justify left bottom) hide)
      )
      (property "Manufacturer" "" (id 5) (at 17.78 -17.78 0)
        (effects (font (size 1.27 1.27) (thickness 0.15)) (justify left bottom) hide)
      )
      (property "Author" "Antmicro" (id 6) (at 17.78 -20.32 0)
        (effects (font (size 1.27 1.27) (thickness 0.15)) (justify left bottom) hide)
      )
      (property "License" "Apache-2.0" (id 7) (at 17.78 -22.86 0)
        (effects (font (size 1.27 1.27) (thickness 0.15)) (justify left bottom) hide)
      )
      (property "ki_description" "Test Point 0.75mm" (id 8) (at 0 0 0)
        (effects (font (size 1.27 1.27)) hide)
      )
      (symbol "TP_0.75mm_SMD_15_1_1"
        (circle (center 3.175 0) (radius 0.635)
          (stroke (width 0.254) (type default) (color 0 0 0 0))
          (fill (type none))
        )
        (pin passive line (at 0 0 0) (length 2.54)
          (name "1" (effects (font (size 1.27 1.27))))
          (number "1" (effects (font (size 1.27 1.27))))
        )
      )
    )
	(symbol "sa800u-baseboard-hw:TP_0.75mm_SMD_16" (pin_numbers hide) (pin_names hide) (in_bom yes) (on_board yes)
      (property "Reference" "TP" (id 0) (at 17.78 -5.08 0)
        (effects (font (size 1.27 1.27) (thickness 0.15)) (justify left bottom))
      )
      (property "Value" "TP_0.75mm_SMD_16" (id 1) (at 17.78 -7.62 0)
        (effects (font (size 1.27 1.27) (thickness 0.15)) (justify left bottom) hide)
      )
      (property "Footprint" "sa800u-baseboard-hw-footprints:TP_SMD_0.75mm" (id 2) (at 17.78 -10.16 0)
        (effects (font (size 1.27 1.27) (thickness 0.15)) (justify left bottom) hide)
      )
      (property "Datasheet" "" (id 3) (at 17.78 -12.7 0)
        (effects (font (size 1.27 1.27) (thickness 0.15)) (justify left bottom) hide)
      )
      (property "MPN" "" (id 4) (at 17.78 -15.24 0)
        (effects (font (size 1.27 1.27) (thickness 0.15)) (justify left bottom) hide)
      )
      (property "Manufacturer" "" (id 5) (at 17.78 -17.78 0)
        (effects (font (size 1.27 1.27) (thickness 0.15)) (justify left bottom) hide)
      )
      (property "Author" "Antmicro" (id 6) (at 17.78 -20.32 0)
        (effects (font (size 1.27 1.27) (thickness 0.15)) (justify left bottom) hide)
      )
      (property "License" "Apache-2.0" (id 7) (at 17.78 -22.86 0)
        (effects (font (size 1.27 1.27) (thickness 0.15)) (justify left bottom) hide)
      )
      (property "ki_description" "Test Point 0.75mm" (id 8) (at 0 0 0)
        (effects (font (size 1.27 1.27)) hide)
      )
      (symbol "TP_0.75mm_SMD_16_1_1"
        (circle (center 3.175 0) (radius 0.635)
          (stroke (width 0.254) (type default) (color 0 0 0 0))
          (fill (type none))
        )
        (pin passive line (at 0 0 0) (length 2.54)
          (name "1" (effects (font (size 1.27 1.27))))
          (number "1" (effects (font (size 1.27 1.27))))
        )
      )
    )
	(symbol "sa800u-baseboard-hw:TP_0.75mm_SMD_17" (pin_numbers hide) (pin_names hide) (in_bom yes) (on_board yes)
      (property "Reference" "TP" (id 0) (at 17.78 -5.08 0)
        (effects (font (size 1.27 1.27) (thickness 0.15)) (justify left bottom))
      )
      (property "Value" "TP_0.75mm_SMD_17" (id 1) (at 17.78 -7.62 0)
        (effects (font (size 1.27 1.27) (thickness 0.15)) (justify left bottom) hide)
      )
      (property "Footprint" "sa800u-baseboard-hw-footprints:TP_SMD_0.75mm" (id 2) (at 17.78 -10.16 0)
        (effects (font (size 1.27 1.27) (thickness 0.15)) (justify left bottom) hide)
      )
      (property "Datasheet" "" (id 3) (at 17.78 -12.7 0)
        (effects (font (size 1.27 1.27) (thickness 0.15)) (justify left bottom) hide)
      )
      (property "MPN" "" (id 4) (at 17.78 -15.24 0)
        (effects (font (size 1.27 1.27) (thickness 0.15)) (justify left bottom) hide)
      )
      (property "Manufacturer" "" (id 5) (at 17.78 -17.78 0)
        (effects (font (size 1.27 1.27) (thickness 0.15)) (justify left bottom) hide)
      )
      (property "Author" "Antmicro" (id 6) (at 17.78 -20.32 0)
        (effects (font (size 1.27 1.27) (thickness 0.15)) (justify left bottom) hide)
      )
      (property "License" "Apache-2.0" (id 7) (at 17.78 -22.86 0)
        (effects (font (size 1.27 1.27) (thickness 0.15)) (justify left bottom) hide)
      )
      (property "ki_description" "Test Point 0.75mm" (id 8) (at 0 0 0)
        (effects (font (size 1.27 1.27)) hide)
      )
      (symbol "TP_0.75mm_SMD_17_1_1"
        (circle (center 3.175 0) (radius 0.635)
          (stroke (width 0.254) (type default) (color 0 0 0 0))
          (fill (type none))
        )
        (pin passive line (at 0 0 0) (length 2.54)
          (name "1" (effects (font (size 1.27 1.27))))
          (number "1" (effects (font (size 1.27 1.27))))
        )
      )
    )
	(symbol "sa800u-baseboard-hw:TP_0.75mm_SMD_18" (pin_numbers hide) (pin_names hide) (in_bom yes) (on_board yes)
      (property "Reference" "TP" (id 0) (at 17.78 -5.08 0)
        (effects (font (size 1.27 1.27) (thickness 0.15)) (justify left bottom))
      )
      (property "Value" "TP_0.75mm_SMD_18" (id 1) (at 17.78 -7.62 0)
        (effects (font (size 1.27 1.27) (thickness 0.15)) (justify left bottom) hide)
      )
      (property "Footprint" "sa800u-baseboard-hw-footprints:TP_SMD_0.75mm" (id 2) (at 17.78 -10.16 0)
        (effects (font (size 1.27 1.27) (thickness 0.15)) (justify left bottom) hide)
      )
      (property "Datasheet" "" (id 3) (at 17.78 -12.7 0)
        (effects (font (size 1.27 1.27) (thickness 0.15)) (justify left bottom) hide)
      )
      (property "MPN" "" (id 4) (at 17.78 -15.24 0)
        (effects (font (size 1.27 1.27) (thickness 0.15)) (justify left bottom) hide)
      )
      (property "Manufacturer" "" (id 5) (at 17.78 -17.78 0)
        (effects (font (size 1.27 1.27) (thickness 0.15)) (justify left bottom) hide)
      )
      (property "Author" "Antmicro" (id 6) (at 17.78 -20.32 0)
        (effects (font (size 1.27 1.27) (thickness 0.15)) (justify left bottom) hide)
      )
      (property "License" "Apache-2.0" (id 7) (at 17.78 -22.86 0)
        (effects (font (size 1.27 1.27) (thickness 0.15)) (justify left bottom) hide)
      )
      (property "ki_description" "Test Point 0.75mm" (id 8) (at 0 0 0)
        (effects (font (size 1.27 1.27)) hide)
      )
      (symbol "TP_0.75mm_SMD_18_1_1"
        (circle (center 3.175 0) (radius 0.635)
          (stroke (width 0.254) (type default) (color 0 0 0 0))
          (fill (type none))
        )
        (pin passive line (at 0 0 0) (length 2.54)
          (name "1" (effects (font (size 1.27 1.27))))
          (number "1" (effects (font (size 1.27 1.27))))
        )
      )
    )
	(symbol "sa800u-baseboard-hw:TP_0.75mm_SMD_19" (pin_numbers hide) (pin_names hide) (in_bom yes) (on_board yes)
      (property "Reference" "TP" (id 0) (at 17.78 -5.08 0)
        (effects (font (size 1.27 1.27) (thickness 0.15)) (justify left bottom))
      )
      (property "Value" "TP_0.75mm_SMD_19" (id 1) (at 17.78 -7.62 0)
        (effects (font (size 1.27 1.27) (thickness 0.15)) (justify left bottom) hide)
      )
      (property "Footprint" "sa800u-baseboard-hw-footprints:TP_SMD_0.75mm" (id 2) (at 17.78 -10.16 0)
        (effects (font (size 1.27 1.27) (thickness 0.15)) (justify left bottom) hide)
      )
      (property "Datasheet" "" (id 3) (at 17.78 -12.7 0)
        (effects (font (size 1.27 1.27) (thickness 0.15)) (justify left bottom) hide)
      )
      (property "MPN" "" (id 4) (at 17.78 -15.24 0)
        (effects (font (size 1.27 1.27) (thickness 0.15)) (justify left bottom) hide)
      )
      (property "Manufacturer" "" (id 5) (at 17.78 -17.78 0)
        (effects (font (size 1.27 1.27) (thickness 0.15)) (justify left bottom) hide)
      )
      (property "Author" "Antmicro" (id 6) (at 17.78 -20.32 0)
        (effects (font (size 1.27 1.27) (thickness 0.15)) (justify left bottom) hide)
      )
      (property "License" "Apache-2.0" (id 7) (at 17.78 -22.86 0)
        (effects (font (size 1.27 1.27) (thickness 0.15)) (justify left bottom) hide)
      )
      (property "ki_description" "Test Point 0.75mm" (id 8) (at 0 0 0)
        (effects (font (size 1.27 1.27)) hide)
      )
      (symbol "TP_0.75mm_SMD_19_1_1"
        (circle (center 3.175 0) (radius 0.635)
          (stroke (width 0.254) (type default) (color 0 0 0 0))
          (fill (type none))
        )
        (pin passive line (at 0 0 0) (length 2.54)
          (name "1" (effects (font (size 1.27 1.27))))
          (number "1" (effects (font (size 1.27 1.27))))
        )
      )
    )
	(symbol "sa800u-baseboard-hw:TP_0.75mm_SMD_20" (pin_numbers hide) (pin_names hide) (in_bom yes) (on_board yes)
      (property "Reference" "TP" (id 0) (at 17.78 -5.08 0)
        (effects (font (size 1.27 1.27) (thickness 0.15)) (justify left bottom))
      )
      (property "Value" "TP_0.75mm_SMD_20" (id 1) (at 17.78 -7.62 0)
        (effects (font (size 1.27 1.27) (thickness 0.15)) (justify left bottom) hide)
      )
      (property "Footprint" "sa800u-baseboard-hw-footprints:TP_SMD_0.75mm" (id 2) (at 17.78 -10.16 0)
        (effects (font (size 1.27 1.27) (thickness 0.15)) (justify left bottom) hide)
      )
      (property "Datasheet" "" (id 3) (at 17.78 -12.7 0)
        (effects (font (size 1.27 1.27) (thickness 0.15)) (justify left bottom) hide)
      )
      (property "MPN" "" (id 4) (at 17.78 -15.24 0)
        (effects (font (size 1.27 1.27) (thickness 0.15)) (justify left bottom) hide)
      )
      (property "Manufacturer" "" (id 5) (at 17.78 -17.78 0)
        (effects (font (size 1.27 1.27) (thickness 0.15)) (justify left bottom) hide)
      )
      (property "Author" "Antmicro" (id 6) (at 17.78 -20.32 0)
        (effects (font (size 1.27 1.27) (thickness 0.15)) (justify left bottom) hide)
      )
      (property "License" "Apache-2.0" (id 7) (at 17.78 -22.86 0)
        (effects (font (size 1.27 1.27) (thickness 0.15)) (justify left bottom) hide)
      )
      (property "ki_description" "Test Point 0.75mm" (id 8) (at 0 0 0)
        (effects (font (size 1.27 1.27)) hide)
      )
      (symbol "TP_0.75mm_SMD_20_1_1"
        (circle (center 3.175 0) (radius 0.635)
          (stroke (width 0.254) (type default) (color 0 0 0 0))
          (fill (type none))
        )
        (pin passive line (at 0 0 0) (length 2.54)
          (name "1" (effects (font (size 1.27 1.27))))
          (number "1" (effects (font (size 1.27 1.27))))
        )
      )
    )
	(symbol "sa800u-baseboard-hw:TP_0.75mm_SMD_21" (pin_numbers hide) (pin_names hide) (in_bom yes) (on_board yes)
      (property "Reference" "TP" (id 0) (at 17.78 -5.08 0)
        (effects (font (size 1.27 1.27) (thickness 0.15)) (justify left bottom))
      )
      (property "Value" "TP_0.75mm_SMD_21" (id 1) (at 17.78 -7.62 0)
        (effects (font (size 1.27 1.27) (thickness 0.15)) (justify left bottom) hide)
      )
      (property "Footprint" "sa800u-baseboard-hw-footprints:TP_SMD_0.75mm" (id 2) (at 17.78 -10.16 0)
        (effects (font (size 1.27 1.27) (thickness 0.15)) (justify left bottom) hide)
      )
      (property "Datasheet" "" (id 3) (at 17.78 -12.7 0)
        (effects (font (size 1.27 1.27) (thickness 0.15)) (justify left bottom) hide)
      )
      (property "MPN" "" (id 4) (at 17.78 -15.24 0)
        (effects (font (size 1.27 1.27) (thickness 0.15)) (justify left bottom) hide)
      )
      (property "Manufacturer" "" (id 5) (at 17.78 -17.78 0)
        (effects (font (size 1.27 1.27) (thickness 0.15)) (justify left bottom) hide)
      )
      (property "Author" "Antmicro" (id 6) (at 17.78 -20.32 0)
        (effects (font (size 1.27 1.27) (thickness 0.15)) (justify left bottom) hide)
      )
      (property "License" "Apache-2.0" (id 7) (at 17.78 -22.86 0)
        (effects (font (size 1.27 1.27) (thickness 0.15)) (justify left bottom) hide)
      )
      (property "ki_description" "Test Point 0.75mm" (id 8) (at 0 0 0)
        (effects (font (size 1.27 1.27)) hide)
      )
      (symbol "TP_0.75mm_SMD_21_1_1"
        (circle (center 3.175 0) (radius 0.635)
          (stroke (width 0.254) (type default) (color 0 0 0 0))
          (fill (type none))
        )
        (pin passive line (at 0 0 0) (length 2.54)
          (name "1" (effects (font (size 1.27 1.27))))
          (number "1" (effects (font (size 1.27 1.27))))
        )
      )
    )
	(symbol "sa800u-baseboard-hw:TP_0.75mm_SMD_22" (pin_numbers hide) (pin_names hide) (in_bom yes) (on_board yes)
      (property "Reference" "TP" (id 0) (at 17.78 -5.08 0)
        (effects (font (size 1.27 1.27) (thickness 0.15)) (justify left bottom))
      )
      (property "Value" "TP_0.75mm_SMD_22" (id 1) (at 17.78 -7.62 0)
        (effects (font (size 1.27 1.27) (thickness 0.15)) (justify left bottom) hide)
      )
      (property "Footprint" "sa800u-baseboard-hw-footprints:TP_SMD_0.75mm" (id 2) (at 17.78 -10.16 0)
        (effects (font (size 1.27 1.27) (thickness 0.15)) (justify left bottom) hide)
      )
      (property "Datasheet" "" (id 3) (at 17.78 -12.7 0)
        (effects (font (size 1.27 1.27) (thickness 0.15)) (justify left bottom) hide)
      )
      (property "MPN" "" (id 4) (at 17.78 -15.24 0)
        (effects (font (size 1.27 1.27) (thickness 0.15)) (justify left bottom) hide)
      )
      (property "Manufacturer" "" (id 5) (at 17.78 -17.78 0)
        (effects (font (size 1.27 1.27) (thickness 0.15)) (justify left bottom) hide)
      )
      (property "Author" "Antmicro" (id 6) (at 17.78 -20.32 0)
        (effects (font (size 1.27 1.27) (thickness 0.15)) (justify left bottom) hide)
      )
      (property "License" "Apache-2.0" (id 7) (at 17.78 -22.86 0)
        (effects (font (size 1.27 1.27) (thickness 0.15)) (justify left bottom) hide)
      )
      (property "ki_description" "Test Point 0.75mm" (id 8) (at 0 0 0)
        (effects (font (size 1.27 1.27)) hide)
      )
      (symbol "TP_0.75mm_SMD_22_1_1"
        (circle (center 3.175 0) (radius 0.635)
          (stroke (width 0.254) (type default) (color 0 0 0 0))
          (fill (type none))
        )
        (pin passive line (at 0 0 0) (length 2.54)
          (name "1" (effects (font (size 1.27 1.27))))
          (number "1" (effects (font (size 1.27 1.27))))
        )
      )
    )
	(symbol "sa800u-baseboard-hw:TP_0.75mm_SMD_23" (pin_numbers hide) (pin_names hide) (in_bom yes) (on_board yes)
      (property "Reference" "TP" (id 0) (at 17.78 -5.08 0)
        (effects (font (size 1.27 1.27) (thickness 0.15)) (justify left bottom))
      )
      (property "Value" "TP_0.75mm_SMD_23" (id 1) (at 17.78 -7.62 0)
        (effects (font (size 1.27 1.27) (thickness 0.15)) (justify left bottom) hide)
      )
      (property "Footprint" "sa800u-baseboard-hw-footprints:TP_SMD_0.75mm" (id 2) (at 17.78 -10.16 0)
        (effects (font (size 1.27 1.27) (thickness 0.15)) (justify left bottom) hide)
      )
      (property "Datasheet" "" (id 3) (at 17.78 -12.7 0)
        (effects (font (size 1.27 1.27) (thickness 0.15)) (justify left bottom) hide)
      )
      (property "MPN" "" (id 4) (at 17.78 -15.24 0)
        (effects (font (size 1.27 1.27) (thickness 0.15)) (justify left bottom) hide)
      )
      (property "Manufacturer" "" (id 5) (at 17.78 -17.78 0)
        (effects (font (size 1.27 1.27) (thickness 0.15)) (justify left bottom) hide)
      )
      (property "Author" "Antmicro" (id 6) (at 17.78 -20.32 0)
        (effects (font (size 1.27 1.27) (thickness 0.15)) (justify left bottom) hide)
      )
      (property "License" "Apache-2.0" (id 7) (at 17.78 -22.86 0)
        (effects (font (size 1.27 1.27) (thickness 0.15)) (justify left bottom) hide)
      )
      (property "ki_description" "Test Point 0.75mm" (id 8) (at 0 0 0)
        (effects (font (size 1.27 1.27)) hide)
      )
      (symbol "TP_0.75mm_SMD_23_1_1"
        (circle (center 3.175 0) (radius 0.635)
          (stroke (width 0.254) (type default) (color 0 0 0 0))
          (fill (type none))
        )
        (pin passive line (at 0 0 0) (length 2.54)
          (name "1" (effects (font (size 1.27 1.27))))
          (number "1" (effects (font (size 1.27 1.27))))
        )
      )
    )
	(symbol "sa800u-baseboard-hw:TP_0.75mm_SMD_24" (pin_numbers hide) (pin_names hide) (in_bom yes) (on_board yes)
      (property "Reference" "TP" (id 0) (at 17.78 -5.08 0)
        (effects (font (size 1.27 1.27) (thickness 0.15)) (justify left bottom))
      )
      (property "Value" "TP_0.75mm_SMD_24" (id 1) (at 17.78 -7.62 0)
        (effects (font (size 1.27 1.27) (thickness 0.15)) (justify left bottom) hide)
      )
      (property "Footprint" "sa800u-baseboard-hw-footprints:TP_SMD_0.75mm" (id 2) (at 17.78 -10.16 0)
        (effects (font (size 1.27 1.27) (thickness 0.15)) (justify left bottom) hide)
      )
      (property "Datasheet" "" (id 3) (at 17.78 -12.7 0)
        (effects (font (size 1.27 1.27) (thickness 0.15)) (justify left bottom) hide)
      )
      (property "MPN" "" (id 4) (at 17.78 -15.24 0)
        (effects (font (size 1.27 1.27) (thickness 0.15)) (justify left bottom) hide)
      )
      (property "Manufacturer" "" (id 5) (at 17.78 -17.78 0)
        (effects (font (size 1.27 1.27) (thickness 0.15)) (justify left bottom) hide)
      )
      (property "Author" "Antmicro" (id 6) (at 17.78 -20.32 0)
        (effects (font (size 1.27 1.27) (thickness 0.15)) (justify left bottom) hide)
      )
      (property "License" "Apache-2.0" (id 7) (at 17.78 -22.86 0)
        (effects (font (size 1.27 1.27) (thickness 0.15)) (justify left bottom) hide)
      )
      (property "ki_description" "Test Point 0.75mm" (id 8) (at 0 0 0)
        (effects (font (size 1.27 1.27)) hide)
      )
      (symbol "TP_0.75mm_SMD_24_1_1"
        (circle (center 3.175 0) (radius 0.635)
          (stroke (width 0.254) (type default) (color 0 0 0 0))
          (fill (type none))
        )
        (pin passive line (at 0 0 0) (length 2.54)
          (name "1" (effects (font (size 1.27 1.27))))
          (number "1" (effects (font (size 1.27 1.27))))
        )
      )
    )
	(symbol "sa800u-baseboard-hw:TP_0.75mm_SMD_25" (pin_numbers hide) (pin_names hide) (in_bom yes) (on_board yes)
      (property "Reference" "TP" (id 0) (at 17.78 -5.08 0)
        (effects (font (size 1.27 1.27) (thickness 0.15)) (justify left bottom))
      )
      (property "Value" "TP_0.75mm_SMD_25" (id 1) (at 17.78 -7.62 0)
        (effects (font (size 1.27 1.27) (thickness 0.15)) (justify left bottom) hide)
      )
      (property "Footprint" "sa800u-baseboard-hw-footprints:TP_SMD_0.75mm" (id 2) (at 17.78 -10.16 0)
        (effects (font (size 1.27 1.27) (thickness 0.15)) (justify left bottom) hide)
      )
      (property "Datasheet" "" (id 3) (at 17.78 -12.7 0)
        (effects (font (size 1.27 1.27) (thickness 0.15)) (justify left bottom) hide)
      )
      (property "MPN" "" (id 4) (at 17.78 -15.24 0)
        (effects (font (size 1.27 1.27) (thickness 0.15)) (justify left bottom) hide)
      )
      (property "Manufacturer" "" (id 5) (at 17.78 -17.78 0)
        (effects (font (size 1.27 1.27) (thickness 0.15)) (justify left bottom) hide)
      )
      (property "Author" "Antmicro" (id 6) (at 17.78 -20.32 0)
        (effects (font (size 1.27 1.27) (thickness 0.15)) (justify left bottom) hide)
      )
      (property "License" "Apache-2.0" (id 7) (at 17.78 -22.86 0)
        (effects (font (size 1.27 1.27) (thickness 0.15)) (justify left bottom) hide)
      )
      (property "ki_description" "Test Point 0.75mm" (id 8) (at 0 0 0)
        (effects (font (size 1.27 1.27)) hide)
      )
      (symbol "TP_0.75mm_SMD_25_1_1"
        (circle (center 3.175 0) (radius 0.635)
          (stroke (width 0.254) (type default) (color 0 0 0 0))
          (fill (type none))
        )
        (pin passive line (at 0 0 0) (length 2.54)
          (name "1" (effects (font (size 1.27 1.27))))
          (number "1" (effects (font (size 1.27 1.27))))
        )
      )
    )
	(symbol "sa800u-baseboard-hw:TP_0.75mm_SMD_26" (pin_numbers hide) (pin_names hide) (in_bom yes) (on_board yes)
      (property "Reference" "TP" (id 0) (at 17.78 -5.08 0)
        (effects (font (size 1.27 1.27) (thickness 0.15)) (justify left bottom))
      )
      (property "Value" "TP_0.75mm_SMD_26" (id 1) (at 17.78 -7.62 0)
        (effects (font (size 1.27 1.27) (thickness 0.15)) (justify left bottom) hide)
      )
      (property "Footprint" "sa800u-baseboard-hw-footprints:TP_SMD_0.75mm" (id 2) (at 17.78 -10.16 0)
        (effects (font (size 1.27 1.27) (thickness 0.15)) (justify left bottom) hide)
      )
      (property "Datasheet" "" (id 3) (at 17.78 -12.7 0)
        (effects (font (size 1.27 1.27) (thickness 0.15)) (justify left bottom) hide)
      )
      (property "MPN" "" (id 4) (at 17.78 -15.24 0)
        (effects (font (size 1.27 1.27) (thickness 0.15)) (justify left bottom) hide)
      )
      (property "Manufacturer" "" (id 5) (at 17.78 -17.78 0)
        (effects (font (size 1.27 1.27) (thickness 0.15)) (justify left bottom) hide)
      )
      (property "Author" "Antmicro" (id 6) (at 17.78 -20.32 0)
        (effects (font (size 1.27 1.27) (thickness 0.15)) (justify left bottom) hide)
      )
      (property "License" "Apache-2.0" (id 7) (at 17.78 -22.86 0)
        (effects (font (size 1.27 1.27) (thickness 0.15)) (justify left bottom) hide)
      )
      (property "ki_description" "Test Point 0.75mm" (id 8) (at 0 0 0)
        (effects (font (size 1.27 1.27)) hide)
      )
      (symbol "TP_0.75mm_SMD_26_1_1"
        (circle (center 3.175 0) (radius 0.635)
          (stroke (width 0.254) (type default) (color 0 0 0 0))
          (fill (type none))
        )
        (pin passive line (at 0 0 0) (length 2.54)
          (name "1" (effects (font (size 1.27 1.27))))
          (number "1" (effects (font (size 1.27 1.27))))
        )
      )
    )
	(symbol "sa800u-baseboard-hw:TP_0.75mm_SMD_27" (pin_numbers hide) (pin_names hide) (in_bom yes) (on_board yes)
      (property "Reference" "TP" (id 0) (at 17.78 -5.08 0)
        (effects (font (size 1.27 1.27) (thickness 0.15)) (justify left bottom))
      )
      (property "Value" "TP_0.75mm_SMD_27" (id 1) (at 17.78 -7.62 0)
        (effects (font (size 1.27 1.27) (thickness 0.15)) (justify left bottom) hide)
      )
      (property "Footprint" "sa800u-baseboard-hw-footprints:TP_SMD_0.75mm" (id 2) (at 17.78 -10.16 0)
        (effects (font (size 1.27 1.27) (thickness 0.15)) (justify left bottom) hide)
      )
      (property "Datasheet" "" (id 3) (at 17.78 -12.7 0)
        (effects (font (size 1.27 1.27) (thickness 0.15)) (justify left bottom) hide)
      )
      (property "MPN" "" (id 4) (at 17.78 -15.24 0)
        (effects (font (size 1.27 1.27) (thickness 0.15)) (justify left bottom) hide)
      )
      (property "Manufacturer" "" (id 5) (at 17.78 -17.78 0)
        (effects (font (size 1.27 1.27) (thickness 0.15)) (justify left bottom) hide)
      )
      (property "Author" "Antmicro" (id 6) (at 17.78 -20.32 0)
        (effects (font (size 1.27 1.27) (thickness 0.15)) (justify left bottom) hide)
      )
      (property "License" "Apache-2.0" (id 7) (at 17.78 -22.86 0)
        (effects (font (size 1.27 1.27) (thickness 0.15)) (justify left bottom) hide)
      )
      (property "ki_description" "Test Point 0.75mm" (id 8) (at 0 0 0)
        (effects (font (size 1.27 1.27)) hide)
      )
      (symbol "TP_0.75mm_SMD_27_1_1"
        (circle (center 3.175 0) (radius 0.635)
          (stroke (width 0.254) (type default) (color 0 0 0 0))
          (fill (type none))
        )
        (pin passive line (at 0 0 0) (length 2.54)
          (name "1" (effects (font (size 1.27 1.27))))
          (number "1" (effects (font (size 1.27 1.27))))
        )
      )
    )
	(symbol "sa800u-baseboard-hw:TP_0.75mm_SMD_28" (pin_numbers hide) (pin_names hide) (in_bom yes) (on_board yes)
      (property "Reference" "TP" (id 0) (at 17.78 -5.08 0)
        (effects (font (size 1.27 1.27) (thickness 0.15)) (justify left bottom))
      )
      (property "Value" "TP_0.75mm_SMD_28" (id 1) (at 17.78 -7.62 0)
        (effects (font (size 1.27 1.27) (thickness 0.15)) (justify left bottom) hide)
      )
      (property "Footprint" "sa800u-baseboard-hw-footprints:TP_SMD_0.75mm" (id 2) (at 17.78 -10.16 0)
        (effects (font (size 1.27 1.27) (thickness 0.15)) (justify left bottom) hide)
      )
      (property "Datasheet" "" (id 3) (at 17.78 -12.7 0)
        (effects (font (size 1.27 1.27) (thickness 0.15)) (justify left bottom) hide)
      )
      (property "MPN" "" (id 4) (at 17.78 -15.24 0)
        (effects (font (size 1.27 1.27) (thickness 0.15)) (justify left bottom) hide)
      )
      (property "Manufacturer" "" (id 5) (at 17.78 -17.78 0)
        (effects (font (size 1.27 1.27) (thickness 0.15)) (justify left bottom) hide)
      )
      (property "Author" "Antmicro" (id 6) (at 17.78 -20.32 0)
        (effects (font (size 1.27 1.27) (thickness 0.15)) (justify left bottom) hide)
      )
      (property "License" "Apache-2.0" (id 7) (at 17.78 -22.86 0)
        (effects (font (size 1.27 1.27) (thickness 0.15)) (justify left bottom) hide)
      )
      (property "ki_description" "Test Point 0.75mm" (id 8) (at 0 0 0)
        (effects (font (size 1.27 1.27)) hide)
      )
      (symbol "TP_0.75mm_SMD_28_1_1"
        (circle (center 3.175 0) (radius 0.635)
          (stroke (width 0.254) (type default) (color 0 0 0 0))
          (fill (type none))
        )
        (pin passive line (at 0 0 0) (length 2.54)
          (name "1" (effects (font (size 1.27 1.27))))
          (number "1" (effects (font (size 1.27 1.27))))
        )
      )
    )
	(symbol "sa800u-baseboard-hw:TP_0.75mm_SMD_29" (pin_numbers hide) (pin_names hide) (in_bom yes) (on_board yes)
      (property "Reference" "TP" (id 0) (at 17.78 -5.08 0)
        (effects (font (size 1.27 1.27) (thickness 0.15)) (justify left bottom))
      )
      (property "Value" "TP_0.75mm_SMD_29" (id 1) (at 17.78 -7.62 0)
        (effects (font (size 1.27 1.27) (thickness 0.15)) (justify left bottom) hide)
      )
      (property "Footprint" "sa800u-baseboard-hw-footprints:TP_SMD_0.75mm" (id 2) (at 17.78 -10.16 0)
        (effects (font (size 1.27 1.27) (thickness 0.15)) (justify left bottom) hide)
      )
      (property "Datasheet" "" (id 3) (at 17.78 -12.7 0)
        (effects (font (size 1.27 1.27) (thickness 0.15)) (justify left bottom) hide)
      )
      (property "MPN" "" (id 4) (at 17.78 -15.24 0)
        (effects (font (size 1.27 1.27) (thickness 0.15)) (justify left bottom) hide)
      )
      (property "Manufacturer" "" (id 5) (at 17.78 -17.78 0)
        (effects (font (size 1.27 1.27) (thickness 0.15)) (justify left bottom) hide)
      )
      (property "Author" "Antmicro" (id 6) (at 17.78 -20.32 0)
        (effects (font (size 1.27 1.27) (thickness 0.15)) (justify left bottom) hide)
      )
      (property "License" "Apache-2.0" (id 7) (at 17.78 -22.86 0)
        (effects (font (size 1.27 1.27) (thickness 0.15)) (justify left bottom) hide)
      )
      (property "ki_description" "Test Point 0.75mm" (id 8) (at 0 0 0)
        (effects (font (size 1.27 1.27)) hide)
      )
      (symbol "TP_0.75mm_SMD_29_1_1"
        (circle (center 3.175 0) (radius 0.635)
          (stroke (width 0.254) (type default) (color 0 0 0 0))
          (fill (type none))
        )
        (pin passive line (at 0 0 0) (length 2.54)
          (name "1" (effects (font (size 1.27 1.27))))
          (number "1" (effects (font (size 1.27 1.27))))
        )
      )
    )
	(symbol "sa800u-baseboard-hw:TXB0104_UQFN" (in_bom yes) (on_board yes)
      (property "Reference" "U" (id 0) (at 35.56 -5.08 0)
        (effects (font (size 1.27 1.27) (thickness 0.15)) (justify left bottom))
      )
      (property "Value" "TXB0104_UQFN" (id 1) (at 35.56 -7.62 0)
        (effects (font (size 1.27 1.27) (thickness 0.15)) (justify left bottom))
      )
      (property "Footprint" "sa800u-baseboard-hw-footprints:UQFN-12_2x1.7mm_P0.4mm_Texas_RUT" (id 2) (at 35.56 -10.16 0)
        (effects (font (size 1.27 1.27) (thickness 0.15)) (justify left bottom) hide)
      )
      (property "Datasheet" "http://www.ti.com/lit/ds/symlink/txb0104.pdf" (id 3) (at 35.56 -12.7 0)
        (effects (font (size 1.27 1.27) (thickness 0.15)) (justify left bottom) hide)
      )
      (property "Manufacturer" "Texas Instruments" (id 4) (at 35.56 -15.24 0)
        (effects (font (size 1.27 1.27) (thickness 0.15)) (justify left bottom) hide)
      )
      (property "MPN" "TXB0104RUTR" (id 5) (at 35.56 -17.78 0)
        (effects (font (size 1.27 1.27) (thickness 0.15)) (justify left bottom) hide)
      )
      (property "Author" "Antmicro" (id 6) (at 35.56 -20.32 0)
        (effects (font (size 1.27 1.27) (thickness 0.15)) (justify left bottom) hide)
      )
      (property "License" "Apache-2.0" (id 7) (at 35.56 -22.86 0)
        (effects (font (size 1.27 1.27) (thickness 0.15)) (justify left bottom) hide)
      )
      (property "ki_keywords" "Level-Shifter CMOS-TTL-Translation" (id 8) (at 0 0 0)
        (effects (font (size 1.27 1.27)) hide)
      )
      (property "ki_description" "4-Bit Bidirectional Voltage-Level Translator, Auto Direction Sensing and ±15-kV ESD Protection, 1.2 - 3.6V APort, 1.65 - 5.5V BPort, Texas_PUQFN-12" (id 9) (at 0 0 0)
        (effects (font (size 1.27 1.27)) hide)
      )
      (property "ki_fp_filters" "Texas*R*PUQFN*N12*" (id 10) (at 0 0 0)
        (effects (font (size 1.27 1.27)) hide)
      )
      (symbol "TXB0104_UQFN_1_1"
        (polyline
          (pts
            (xy 7.874 -20.447)
            (xy 7.874 -19.431)
            (xy 9.652 -19.431)
          )
          (stroke (width 0.254) (type default) (color 0 0 0 0))
          (fill (type background))
        )
        (polyline
          (pts
            (xy 7.874 -15.367)
            (xy 7.874 -14.351)
            (xy 9.652 -14.351)
          )
          (stroke (width 0.254) (type default) (color 0 0 0 0))
          (fill (type background))
        )
        (polyline
          (pts
            (xy 7.874 -10.287)
            (xy 7.874 -9.271)
            (xy 9.652 -9.271)
          )
          (stroke (width 0.254) (type default) (color 0 0 0 0))
          (fill (type background))
        )
        (polyline
          (pts
            (xy 7.874 -5.207)
            (xy 7.874 -4.191)
            (xy 9.652 -4.191)
          )
          (stroke (width 0.254) (type default) (color 0 0 0 0))
          (fill (type background))
        )
        (polyline
          (pts
            (xy 13.208 -20.447)
            (xy 13.208 -21.463)
            (xy 11.43 -21.463)
          )
          (stroke (width 0.254) (type default) (color 0 0 0 0))
          (fill (type background))
        )
        (polyline
          (pts
            (xy 13.208 -15.367)
            (xy 13.208 -16.383)
            (xy 11.43 -16.383)
          )
          (stroke (width 0.254) (type default) (color 0 0 0 0))
          (fill (type background))
        )
        (polyline
          (pts
            (xy 13.208 -10.287)
            (xy 13.208 -11.303)
            (xy 11.43 -11.303)
          )
          (stroke (width 0.254) (type default) (color 0 0 0 0))
          (fill (type background))
        )
        (polyline
          (pts
            (xy 13.208 -5.207)
            (xy 13.208 -6.223)
            (xy 11.43 -6.223)
          )
          (stroke (width 0.254) (type default) (color 0 0 0 0))
          (fill (type background))
        )
        (polyline
          (pts
            (xy 9.652 -21.463)
            (xy 7.874 -21.463)
            (xy 7.874 -20.447)
            (xy 6.096 -20.447)
          )
          (stroke (width 0.254) (type default) (color 0 0 0 0))
          (fill (type background))
        )
        (polyline
          (pts
            (xy 9.652 -21.463)
            (xy 11.43 -20.447)
            (xy 11.43 -22.479)
            (xy 9.652 -21.463)
          )
          (stroke (width 0.254) (type default) (color 0 0 0 0))
          (fill (type outline))
        )
        (polyline
          (pts
            (xy 9.652 -16.383)
            (xy 7.874 -16.383)
            (xy 7.874 -15.367)
            (xy 6.096 -15.367)
          )
          (stroke (width 0.254) (type default) (color 0 0 0 0))
          (fill (type background))
        )
        (polyline
          (pts
            (xy 9.652 -16.383)
            (xy 11.43 -15.367)
            (xy 11.43 -17.399)
            (xy 9.652 -16.383)
          )
          (stroke (width 0.254) (type default) (color 0 0 0 0))
          (fill (type outline))
        )
        (polyline
          (pts
            (xy 9.652 -11.303)
            (xy 7.874 -11.303)
            (xy 7.874 -10.287)
            (xy 6.096 -10.287)
          )
          (stroke (width 0.254) (type default) (color 0 0 0 0))
          (fill (type background))
        )
        (polyline
          (pts
            (xy 9.652 -11.303)
            (xy 11.43 -10.287)
            (xy 11.43 -12.319)
            (xy 9.652 -11.303)
          )
          (stroke (width 0.254) (type default) (color 0 0 0 0))
          (fill (type outline))
        )
        (polyline
          (pts
            (xy 9.652 -6.223)
            (xy 7.874 -6.223)
            (xy 7.874 -5.207)
            (xy 5.842 -5.207)
          )
          (stroke (width 0.254) (type default) (color 0 0 0 0))
          (fill (type background))
        )
        (polyline
          (pts
            (xy 9.652 -6.223)
            (xy 11.43 -5.207)
            (xy 11.43 -7.239)
            (xy 9.652 -6.223)
          )
          (stroke (width 0.254) (type default) (color 0 0 0 0))
          (fill (type outline))
        )
        (polyline
          (pts
            (xy 11.43 -19.431)
            (xy 9.652 -20.447)
            (xy 9.652 -18.415)
            (xy 11.43 -19.431)
          )
          (stroke (width 0.254) (type default) (color 0 0 0 0))
          (fill (type outline))
        )
        (polyline
          (pts
            (xy 11.43 -19.431)
            (xy 13.208 -19.431)
            (xy 13.208 -20.447)
            (xy 14.478 -20.447)
          )
          (stroke (width 0.254) (type default) (color 0 0 0 0))
          (fill (type background))
        )
        (polyline
          (pts
            (xy 11.43 -14.351)
            (xy 9.652 -15.367)
            (xy 9.652 -13.335)
            (xy 11.43 -14.351)
          )
          (stroke (width 0.254) (type default) (color 0 0 0 0))
          (fill (type outline))
        )
        (polyline
          (pts
            (xy 11.43 -14.351)
            (xy 13.208 -14.351)
            (xy 13.208 -15.367)
            (xy 14.478 -15.367)
          )
          (stroke (width 0.254) (type default) (color 0 0 0 0))
          (fill (type background))
        )
        (polyline
          (pts
            (xy 11.43 -9.271)
            (xy 9.652 -10.287)
            (xy 9.652 -8.255)
            (xy 11.43 -9.271)
          )
          (stroke (width 0.254) (type default) (color 0 0 0 0))
          (fill (type outline))
        )
        (polyline
          (pts
            (xy 11.43 -9.271)
            (xy 13.208 -9.271)
            (xy 13.208 -10.287)
            (xy 14.478 -10.287)
          )
          (stroke (width 0.254) (type default) (color 0 0 0 0))
          (fill (type background))
        )
        (polyline
          (pts
            (xy 11.43 -4.191)
            (xy 9.652 -5.207)
            (xy 9.652 -3.175)
            (xy 11.43 -4.191)
          )
          (stroke (width 0.254) (type default) (color 0 0 0 0))
          (fill (type outline))
        )
        (polyline
          (pts
            (xy 11.43 -4.191)
            (xy 13.208 -4.191)
            (xy 13.208 -5.207)
            (xy 14.478 -5.207)
          )
          (stroke (width 0.254) (type default) (color 0 0 0 0))
          (fill (type background))
        )
        (rectangle (start 2.54 2.54) (end 17.78 -27.94)
          (stroke (width 0.254) (type default) (color 0 0 0 0))
          (fill (type background))
        )
        (pin power_in line (at 0 0 0) (length 2.54)
          (name "VCCA" (effects (font (size 1.27 1.27))))
          (number "1" (effects (font (size 1.27 1.27))))
        )
        (pin tri_state line (at 20.32 -5.08 180) (length 2.54)
          (name "B1" (effects (font (size 1.27 1.27))))
          (number "10" (effects (font (size 1.27 1.27))))
        )
        (pin power_in line (at 20.32 0 180) (length 2.54)
          (name "VCCB" (effects (font (size 1.27 1.27))))
          (number "11" (effects (font (size 1.27 1.27))))
        )
        (pin input line (at 0 -25.4 0) (length 2.54)
          (name "OE" (effects (font (size 1.27 1.27))))
          (number "12" (effects (font (size 1.27 1.27))))
        )
        (pin tri_state line (at 0 -5.08 0) (length 2.54)
          (name "A1" (effects (font (size 1.27 1.27))))
          (number "2" (effects (font (size 1.27 1.27))))
        )
        (pin tri_state line (at 0 -10.16 0) (length 2.54)
          (name "A2" (effects (font (size 1.27 1.27))))
          (number "3" (effects (font (size 1.27 1.27))))
        )
        (pin tri_state line (at 0 -15.24 0) (length 2.54)
          (name "A3" (effects (font (size 1.27 1.27))))
          (number "4" (effects (font (size 1.27 1.27))))
        )
        (pin tri_state line (at 0 -20.32 0) (length 2.54)
          (name "A4" (effects (font (size 1.27 1.27))))
          (number "5" (effects (font (size 1.27 1.27))))
        )
        (pin power_in line (at 20.32 -25.4 180) (length 2.54)
          (name "GND" (effects (font (size 1.27 1.27))))
          (number "6" (effects (font (size 1.27 1.27))))
        )
        (pin tri_state line (at 20.32 -20.32 180) (length 2.54)
          (name "B4" (effects (font (size 1.27 1.27))))
          (number "7" (effects (font (size 1.27 1.27))))
        )
        (pin tri_state line (at 20.32 -15.24 180) (length 2.54)
          (name "B3" (effects (font (size 1.27 1.27))))
          (number "8" (effects (font (size 1.27 1.27))))
        )
        (pin tri_state line (at 20.32 -10.16 180) (length 2.54)
          (name "B2" (effects (font (size 1.27 1.27))))
          (number "9" (effects (font (size 1.27 1.27))))
        )
      )
    )
)
